(kicad_pcb
	(version 20260206)
	(generator "pcbnew")
	(generator_version "10.0")
	(general
		(thickness 1.6)
		(legacy_teardrops no)
	)
	(paper "A4")
	(layers
		(0 "F.Cu" signal "TOP")
		(4 "In1.Cu" signal "GND")
		(6 "In2.Cu" signal "IN1")
		(8 "In3.Cu" signal "GND1")
		(10 "In4.Cu" signal "VCC")
		(12 "In5.Cu" signal "VCC1")
		(14 "In6.Cu" signal "GND2")
		(16 "In7.Cu" signal "IN2")
		(18 "In8.Cu" signal "GND3")
		(2 "B.Cu" signal "BOTTOM")
		(9 "F.Adhes" user "F.Adhesive")
		(11 "B.Adhes" user "B.Adhesive")
		(13 "F.Paste" user "Package Geometry/Pastemask Top")
		(15 "B.Paste" user "Package Geometry/Pastemask Bottom")
		(5 "F.SilkS" user "Ref Des/Silkscreen Top")
		(7 "B.SilkS" user "Ref Des/Silkscreen Bottom")
		(1 "F.Mask" user "Board Geometry/Soldermask Top")
		(3 "B.Mask" user "Board Geometry/Soldermask Bottom")
		(17 "Dwgs.User" user "User.Drawings")
		(19 "Cmts.User" user "User.Comments")
		(21 "Eco1.User" user "User.Eco1")
		(23 "Eco2.User" user "User.Eco2")
		(25 "Edge.Cuts" user "Board Geometry/Outline")
		(27 "Margin" user)
		(31 "F.CrtYd" user "Package Geometry/Place Bound Top")
		(29 "B.CrtYd" user "Package Geometry/Place Bound Bottom")
		(35 "F.Fab" user "Ref Des/Assembly Top")
		(33 "B.Fab" user "Ref Des/Assembly Bottom")
	)
	(setup
		(pad_to_mask_clearance 0)
		(allow_soldermask_bridges_in_footprints no)
		(tenting
			(front yes)
			(back yes)
		)
		(covering
			(front no)
			(back no)
		)
		(plugging
			(front no)
			(back no)
		)
		(capping no)
		(filling no)
		(pcbplotparams
			(layerselection 0x00000000_00000000_55555555_5755f5ff)
			(plot_on_all_layers_selection 0x00000000_00000000_00000000_00000000)
			(disableapertmacros no)
			(usegerberextensions no)
			(usegerberattributes yes)
			(usegerberadvancedattributes yes)
			(creategerberjobfile yes)
			(dashed_line_dash_ratio 12)
			(dashed_line_gap_ratio 3)
			(svgprecision 4)
			(plotframeref no)
			(mode 1)
			(useauxorigin no)
			(pdf_front_fp_property_popups yes)
			(pdf_back_fp_property_popups yes)
			(pdf_metadata yes)
			(pdf_single_document no)
			(dxfpolygonmode yes)
			(dxfimperialunits yes)
			(dxfusepcbnewfont yes)
			(psnegative no)
			(psa4output no)
			(plot_black_and_white yes)
			(sketchpadsonfab no)
			(plotpadnumbers no)
			(hidednponfab no)
			(sketchdnponfab yes)
			(crossoutdnponfab yes)
			(subtractmaskfromsilk no)
			(outputformat 1)
			(mirror no)
			(drillshape 1)
			(scaleselection 1)
			(outputdirectory "")
		)
	)
	(footprint ""
		(layer "F.Cu")
		(at 439.547 -63.5 180)
		(property "Reference" "R5929"
			(at 0 0 180)
			(layer "F.SilkS")
			(hide yes)
			(effects
				(font
					(size 1.27 1.27)
				)
			)
		)
		(property "Value" ""
			(at 0 0 180)
			(layer "F.Fab")
			(effects
				(font
					(size 1.27 1.27)
				)
			)
		)
		(duplicate_pad_numbers_are_jumpers no)
		(fp_line
			(start 0.7874 0.4064)
			(end -0.7874 0.4064)
			(stroke
				(width 0.1524)
				(type default)
			)
			(layer "F.SilkS")
		)
		(fp_line
			(start 0.7874 -0.4064)
			(end 0.7874 0.4064)
			(stroke
				(width 0.1524)
				(type default)
			)
			(layer "F.SilkS")
		)
		(fp_line
			(start -0.7874 0.4064)
			(end -0.7874 -0.4064)
			(stroke
				(width 0.1524)
				(type default)
			)
			(layer "F.SilkS")
		)
		(fp_line
			(start -0.7874 -0.4064)
			(end 0.7874 -0.4064)
			(stroke
				(width 0.1524)
				(type default)
			)
			(layer "F.SilkS")
		)
		(fp_line
			(start 0.67945 0.3048)
			(end 0.120396 0.3048)
			(stroke
				(width 0.1)
				(type default)
			)
			(layer "F.Fab")
		)
		(fp_line
			(start 0.67945 -0.3048)
			(end 0.67945 0.3048)
			(stroke
				(width 0.1)
				(type default)
			)
			(layer "F.Fab")
		)
		(fp_line
			(start 0.12065 -0.2794)
			(end 0.12065 -0.3048)
			(stroke
				(width 0.1)
				(type default)
			)
			(layer "F.Fab")
		)
		(fp_line
			(start 0.12065 -0.3048)
			(end 0.67945 -0.3048)
			(stroke
				(width 0.1)
				(type default)
			)
			(layer "F.Fab")
		)
		(fp_line
			(start 0.120396 0.3048)
			(end 0.120396 0.2794)
			(stroke
				(width 0.1)
				(type default)
			)
			(layer "F.Fab")
		)
		(fp_line
			(start 0.120396 0.2794)
			(end -0.12065 0.2794)
			(stroke
				(width 0.1)
				(type default)
			)
			(layer "F.Fab")
		)
		(fp_line
			(start -0.12065 0.3048)
			(end -0.67945 0.3048)
			(stroke
				(width 0.1)
				(type default)
			)
			(layer "F.Fab")
		)
		(fp_line
			(start -0.12065 0.2794)
			(end -0.12065 0.3048)
			(stroke
				(width 0.1)
				(type default)
			)
			(layer "F.Fab")
		)
		(fp_line
			(start -0.12065 -0.2794)
			(end 0.12065 -0.2794)
			(stroke
				(width 0.1)
				(type default)
			)
			(layer "F.Fab")
		)
		(fp_line
			(start -0.12065 -0.305054)
			(end -0.12065 -0.2794)
			(stroke
				(width 0.1)
				(type default)
			)
			(layer "F.Fab")
		)
		(fp_line
			(start -0.67945 0.3048)
			(end -0.67945 -0.305054)
			(stroke
				(width 0.1)
				(type default)
			)
			(layer "F.Fab")
		)
		(fp_line
			(start -0.67945 -0.305054)
			(end -0.12065 -0.305054)
			(stroke
				(width 0.1)
				(type default)
			)
			(layer "F.Fab")
		)
		(pad "1" smd circle
			(at -0.40005 0 180)
			(size 0 0)
			(layers "F.Cu" "F.Mask" "F.Paste")
			(net "P3V3_AUX")
		)
		(pad "2" smd circle
			(at 0.40005 0 180)
			(size 0 0)
			(layers "F.Cu" "F.Mask" "F.Paste")
			(net "LED_D6_R1")
		)
	)
	(footprint ""
		(layer "F.Cu")
		(at 445.741806 -90.888058 180)
		(property "Reference" "PC56"
			(at 0 0 180)
			(layer "F.SilkS")
			(hide yes)
			(effects
				(font
					(size 1.27 1.27)
				)
			)
		)
		(property "Value" ""
			(at 0 0 180)
			(layer "F.Fab")
			(effects
				(font
					(size 1.27 1.27)
				)
			)
		)
		(duplicate_pad_numbers_are_jumpers no)
		(fp_line
			(start 1.524 0.762)
			(end -1.524 0.762)
			(stroke
				(width 0.1524)
				(type default)
			)
			(layer "F.SilkS")
		)
		(fp_line
			(start 1.524 -0.762)
			(end 1.524 0.762)
			(stroke
				(width 0.1524)
				(type default)
			)
			(layer "F.SilkS")
		)
		(fp_line
			(start -1.524 0.762)
			(end -1.524 -0.762)
			(stroke
				(width 0.1524)
				(type default)
			)
			(layer "F.SilkS")
		)
		(fp_line
			(start -1.524 -0.762)
			(end 1.524 -0.762)
			(stroke
				(width 0.1524)
				(type default)
			)
			(layer "F.SilkS")
		)
		(fp_line
			(start 1.1049 0.724916)
			(end 1.1049 -0.724916)
			(stroke
				(width 0.1)
				(type default)
			)
			(layer "F.Fab")
		)
		(fp_line
			(start 1.1049 -0.724916)
			(end -1.1049 -0.724916)
			(stroke
				(width 0.1)
				(type default)
			)
			(layer "F.Fab")
		)
		(fp_line
			(start -1.1049 0.724916)
			(end 1.1049 0.724916)
			(stroke
				(width 0.1)
				(type default)
			)
			(layer "F.Fab")
		)
		(fp_line
			(start -1.1049 -0.724916)
			(end -1.1049 0.724916)
			(stroke
				(width 0.1)
				(type default)
			)
			(layer "F.Fab")
		)
		(pad "1" smd rect
			(at -0.889 0)
			(size 1.016 1.27)
			(layers "F.Cu" "F.Mask" "F.Paste")
			(net "SW_P3V3_HPDB_FLT")
		)
		(pad "2" smd rect
			(at 0.889 0)
			(size 1.016 1.27)
			(layers "F.Cu" "F.Mask" "F.Paste")
			(net "GND")
		)
	)
	(footprint ""
		(layer "F.Cu")
		(at 238.810038 -79.624936)
		(property "Reference" "H34"
			(at -1.9812 -4.079748 0)
			(unlocked yes)
			(layer "B.SilkS")
			(effects
				(font
					(size 0.7874 0.5842)
					(thickness 0.1524)
				)
				(justify left mirror)
			)
		)
		(property "Value" ""
			(at 0 0 0)
			(layer "F.Fab")
			(effects
				(font
					(size 1.27 1.27)
				)
			)
		)
		(duplicate_pad_numbers_are_jumpers no)
		(pad "1" thru_hole circle
			(at 0 0)
			(size 8.001 8.001)
			(drill 4.2418)
			(layers "*.Cu" "*.Mask")
			(remove_unused_layers no)
			(net "TP_H34")
			(clearance -1.6256)
			(padstack
				(mode front_inner_back)
				(layer "Inner"
					(shape circle)
					(size 6.0198 6.0198)
					(clearance -0.635)
				)
				(layer "B.Cu"
					(shape circle)
					(size 8.001 8.001)
					(clearance -1.6256)
				)
			)
		)
		(zone
			(layers "F.Cu" "B.Cu" "In1.Cu" "In2.Cu" "In3.Cu" "In4.Cu" "In5.Cu" "In6.Cu"
				"In7.Cu" "In8.Cu"
			)
			(hatch none 0.5)
			(connect_pads
				(clearance 0)
			)
			(min_thickness 0.25)
			(keepout
				(tracks not_allowed)
				(vias allowed)
				(pads allowed)
				(copperpour not_allowed)
				(footprints allowed)
			)
			(placement
				(enabled no)
				(sheetname "")
			)
			(fill
				(thermal_gap 0.5)
				(thermal_bridge_width 0.5)
				(island_removal_mode 0)
			)
			(polygon
				(pts
					(arc
						(start 242.320064 -79.624936)
						(mid 235.300012 -79.624936)
						(end 242.320064 -79.624936)
					)
				)
			)
		)
	)
	(footprint ""
		(layer "F.Cu")
		(at 449.8594 -62.23 -90)
		(property "Reference" "PC49"
			(at 0 0 270)
			(layer "F.SilkS")
			(hide yes)
			(effects
				(font
					(size 1.27 1.27)
				)
			)
		)
		(property "Value" ""
			(at 0 0 270)
			(layer "F.Fab")
			(effects
				(font
					(size 1.27 1.27)
				)
			)
		)
		(duplicate_pad_numbers_are_jumpers no)
		(fp_line
			(start -1.524 0.762)
			(end -1.524 -0.762)
			(stroke
				(width 0.1524)
				(type default)
			)
			(layer "F.SilkS")
		)
		(fp_line
			(start 1.524 0.762)
			(end -1.524 0.762)
			(stroke
				(width 0.1524)
				(type default)
			)
			(layer "F.SilkS")
		)
		(fp_line
			(start -1.524 -0.762)
			(end 1.524 -0.762)
			(stroke
				(width 0.1524)
				(type default)
			)
			(layer "F.SilkS")
		)
		(fp_line
			(start 1.524 -0.762)
			(end 1.524 0.762)
			(stroke
				(width 0.1524)
				(type default)
			)
			(layer "F.SilkS")
		)
		(fp_line
			(start -1.1049 0.724916)
			(end 1.1049 0.724916)
			(stroke
				(width 0.1)
				(type default)
			)
			(layer "F.Fab")
		)
		(fp_line
			(start 1.1049 0.724916)
			(end 1.1049 -0.724916)
			(stroke
				(width 0.1)
				(type default)
			)
			(layer "F.Fab")
		)
		(fp_line
			(start -1.1049 -0.724916)
			(end -1.1049 0.724916)
			(stroke
				(width 0.1)
				(type default)
			)
			(layer "F.Fab")
		)
		(fp_line
			(start 1.1049 -0.724916)
			(end -1.1049 -0.724916)
			(stroke
				(width 0.1)
				(type default)
			)
			(layer "F.Fab")
		)
		(pad "1" smd rect
			(at -0.889 0 90)
			(size 1.016 1.27)
			(layers "F.Cu" "F.Mask" "F.Paste")
			(net "P3V3_AUX")
		)
		(pad "2" smd rect
			(at 0.889 0 90)
			(size 1.016 1.27)
			(layers "F.Cu" "F.Mask" "F.Paste")
			(net "GND")
		)
	)
	(footprint ""
		(layer "F.Cu")
		(at 450.42074 -83.393788)
		(property "Reference" "PR113"
			(at 0 0 0)
			(layer "F.SilkS")
			(hide yes)
			(effects
				(font
					(size 1.27 1.27)
				)
			)
		)
		(property "Value" ""
			(at 0 0 0)
			(layer "F.Fab")
			(effects
				(font
					(size 1.27 1.27)
				)
			)
		)
		(duplicate_pad_numbers_are_jumpers no)
		(fp_line
			(start -0.7874 -0.4064)
			(end 0.7874 -0.4064)
			(stroke
				(width 0.1524)
				(type default)
			)
			(layer "F.SilkS")
		)
		(fp_line
			(start -0.7874 0.4064)
			(end -0.7874 -0.4064)
			(stroke
				(width 0.1524)
				(type default)
			)
			(layer "F.SilkS")
		)
		(fp_line
			(start 0.7874 -0.4064)
			(end 0.7874 0.4064)
			(stroke
				(width 0.1524)
				(type default)
			)
			(layer "F.SilkS")
		)
		(fp_line
			(start 0.7874 0.4064)
			(end -0.7874 0.4064)
			(stroke
				(width 0.1524)
				(type default)
			)
			(layer "F.SilkS")
		)
		(fp_line
			(start -0.67945 -0.305054)
			(end -0.12065 -0.305054)
			(stroke
				(width 0.1)
				(type default)
			)
			(layer "F.Fab")
		)
		(fp_line
			(start -0.67945 0.3048)
			(end -0.67945 -0.305054)
			(stroke
				(width 0.1)
				(type default)
			)
			(layer "F.Fab")
		)
		(fp_line
			(start -0.12065 -0.305054)
			(end -0.12065 -0.2794)
			(stroke
				(width 0.1)
				(type default)
			)
			(layer "F.Fab")
		)
		(fp_line
			(start -0.12065 -0.2794)
			(end 0.12065 -0.2794)
			(stroke
				(width 0.1)
				(type default)
			)
			(layer "F.Fab")
		)
		(fp_line
			(start -0.12065 0.2794)
			(end -0.12065 0.3048)
			(stroke
				(width 0.1)
				(type default)
			)
			(layer "F.Fab")
		)
		(fp_line
			(start -0.12065 0.3048)
			(end -0.67945 0.3048)
			(stroke
				(width 0.1)
				(type default)
			)
			(layer "F.Fab")
		)
		(fp_line
			(start 0.120396 0.2794)
			(end -0.12065 0.2794)
			(stroke
				(width 0.1)
				(type default)
			)
			(layer "F.Fab")
		)
		(fp_line
			(start 0.120396 0.3048)
			(end 0.120396 0.2794)
			(stroke
				(width 0.1)
				(type default)
			)
			(layer "F.Fab")
		)
		(fp_line
			(start 0.12065 -0.3048)
			(end 0.67945 -0.3048)
			(stroke
				(width 0.1)
				(type default)
			)
			(layer "F.Fab")
		)
		(fp_line
			(start 0.12065 -0.2794)
			(end 0.12065 -0.3048)
			(stroke
				(width 0.1)
				(type default)
			)
			(layer "F.Fab")
		)
		(fp_line
			(start 0.67945 -0.3048)
			(end 0.67945 0.3048)
			(stroke
				(width 0.1)
				(type default)
			)
			(layer "F.Fab")
		)
		(fp_line
			(start 0.67945 0.3048)
			(end 0.120396 0.3048)
			(stroke
				(width 0.1)
				(type default)
			)
			(layer "F.Fab")
		)
		(pad "1" smd circle
			(at -0.40005 0)
			(size 0 0)
			(layers "F.Cu" "F.Mask" "F.Paste")
			(net "P3V3_HPDB_CS")
		)
		(pad "2" smd circle
			(at 0.40005 0)
			(size 0 0)
			(layers "F.Cu" "F.Mask" "F.Paste")
			(net "GND")
		)
	)
	(footprint ""
		(layer "F.Cu")
		(at 124.483876 -40.8178)
		(property "Reference" "PQ41"
			(at 8.913114 -3.609848 0)
			(unlocked yes)
			(layer "F.SilkS")
			(effects
				(font
					(size 0.7874 0.5842)
					(thickness 0.1524)
				)
				(justify left)
			)
		)
		(property "Value" ""
			(at 0 0 0)
			(layer "F.Fab")
			(effects
				(font
					(size 1.27 1.27)
				)
			)
		)
		(duplicate_pad_numbers_are_jumpers no)
		(fp_line
			(start -7.649972 -4.99999)
			(end -7.649972 -3.3274)
			(stroke
				(width 0.1524)
				(type default)
			)
			(layer "F.SilkS")
		)
		(fp_line
			(start -7.649972 -1.7526)
			(end -7.649972 1.7526)
			(stroke
				(width 0.1524)
				(type default)
			)
			(layer "F.SilkS")
		)
		(fp_line
			(start -7.649972 3.3274)
			(end -7.649972 4.99999)
			(stroke
				(width 0.1524)
				(type default)
			)
			(layer "F.SilkS")
		)
		(fp_line
			(start -7.649972 4.99999)
			(end 5.115814 4.99999)
			(stroke
				(width 0.1524)
				(type default)
			)
			(layer "F.SilkS")
		)
		(fp_line
			(start 5.115814 -4.99999)
			(end -7.649972 -4.99999)
			(stroke
				(width 0.1524)
				(type default)
			)
			(layer "F.SilkS")
		)
		(fp_line
			(start 7.630414 4.99999)
			(end 7.649972 4.99999)
			(stroke
				(width 0.1524)
				(type default)
			)
			(layer "F.SilkS")
		)
		(fp_line
			(start 7.649972 -4.99999)
			(end 7.630414 -4.99999)
			(stroke
				(width 0.1524)
				(type default)
			)
			(layer "F.SilkS")
		)
		(fp_line
			(start 7.649972 4.99999)
			(end 7.649972 -4.99999)
			(stroke
				(width 0.1524)
				(type default)
			)
			(layer "F.SilkS")
		)
		(fp_line
			(start -7.649972 -4.99999)
			(end -7.649972 4.99999)
			(stroke
				(width 0.1)
				(type default)
			)
			(layer "F.Fab")
		)
		(fp_line
			(start -7.649972 4.99999)
			(end 7.649972 4.99999)
			(stroke
				(width 0.1)
				(type default)
			)
			(layer "F.Fab")
		)
		(fp_line
			(start 7.649972 -4.99999)
			(end -7.649972 -4.99999)
			(stroke
				(width 0.1)
				(type default)
			)
			(layer "F.Fab")
		)
		(fp_line
			(start 7.649972 4.99999)
			(end 7.649972 -4.99999)
			(stroke
				(width 0.1)
				(type default)
			)
			(layer "F.Fab")
		)
		(pad "D" smd circle
			(at 2.15011 0)
			(size 0 0)
			(layers "F.Cu" "F.Mask" "F.Paste")
			(net "P52V_HS2_DRAIN_2")
		)
		(pad "G" smd rect
			(at -7.050024 -2.54 270)
			(size 1.3208 3.0988)
			(layers "F.Cu" "F.Mask" "F.Paste")
			(net "P52V_HS2_GATE4")
		)
		(pad "S" smd rect
			(at -7.050024 2.54 270)
			(size 1.3208 3.0988)
			(layers "F.Cu" "F.Mask" "F.Paste")
			(net "P52V_HS2")
		)
		(zone
			(layer "F.Cu")
			(hatch none 0.5)
			(connect_pads
				(clearance 0)
			)
			(min_thickness 0.25)
			(keepout
				(tracks not_allowed)
				(vias allowed)
				(pads allowed)
				(copperpour not_allowed)
				(footprints allowed)
			)
			(placement
				(enabled no)
				(sheetname "")
			)
			(fill
				(thermal_gap 0.5)
				(thermal_bridge_width 0.5)
				(island_removal_mode 0)
			)
			(polygon
				(pts
					(xy 129.665476 -45.7962) (xy 116.838476 -45.7962) (xy 116.838476 -44.069) (xy 119.048276 -44.069)
					(xy 119.048276 -42.6466) (xy 116.838476 -42.6466) (xy 116.838476 -38.989) (xy 119.048276 -38.989)
					(xy 119.048276 -37.5666) (xy 116.838476 -37.5666) (xy 116.838476 -35.8394) (xy 129.665476 -35.8394)
					(xy 129.665476 -37.0078) (xy 123.467876 -37.0078) (xy 123.467876 -44.6278) (xy 129.665476 -44.6278)
				)
			)
		)
	)
	(footprint ""
		(layer "F.Cu")
		(at 413.512 -46.482)
		(property "Reference" "R48"
			(at 0 0 0)
			(layer "F.SilkS")
			(hide yes)
			(effects
				(font
					(size 1.27 1.27)
				)
			)
		)
		(property "Value" ""
			(at 0 0 0)
			(layer "F.Fab")
			(effects
				(font
					(size 1.27 1.27)
				)
			)
		)
		(duplicate_pad_numbers_are_jumpers no)
		(fp_line
			(start -0.7874 -0.4064)
			(end 0.7874 -0.4064)
			(stroke
				(width 0.1524)
				(type default)
			)
			(layer "F.SilkS")
		)
		(fp_line
			(start -0.7874 0.4064)
			(end -0.7874 -0.4064)
			(stroke
				(width 0.1524)
				(type default)
			)
			(layer "F.SilkS")
		)
		(fp_line
			(start 0.7874 -0.4064)
			(end 0.7874 0.4064)
			(stroke
				(width 0.1524)
				(type default)
			)
			(layer "F.SilkS")
		)
		(fp_line
			(start 0.7874 0.4064)
			(end -0.7874 0.4064)
			(stroke
				(width 0.1524)
				(type default)
			)
			(layer "F.SilkS")
		)
		(fp_line
			(start -0.67945 -0.305054)
			(end -0.12065 -0.305054)
			(stroke
				(width 0.1)
				(type default)
			)
			(layer "F.Fab")
		)
		(fp_line
			(start -0.67945 0.3048)
			(end -0.67945 -0.305054)
			(stroke
				(width 0.1)
				(type default)
			)
			(layer "F.Fab")
		)
		(fp_line
			(start -0.12065 -0.305054)
			(end -0.12065 -0.2794)
			(stroke
				(width 0.1)
				(type default)
			)
			(layer "F.Fab")
		)
		(fp_line
			(start -0.12065 -0.2794)
			(end 0.12065 -0.2794)
			(stroke
				(width 0.1)
				(type default)
			)
			(layer "F.Fab")
		)
		(fp_line
			(start -0.12065 0.2794)
			(end -0.12065 0.3048)
			(stroke
				(width 0.1)
				(type default)
			)
			(layer "F.Fab")
		)
		(fp_line
			(start -0.12065 0.3048)
			(end -0.67945 0.3048)
			(stroke
				(width 0.1)
				(type default)
			)
			(layer "F.Fab")
		)
		(fp_line
			(start 0.120396 0.2794)
			(end -0.12065 0.2794)
			(stroke
				(width 0.1)
				(type default)
			)
			(layer "F.Fab")
		)
		(fp_line
			(start 0.120396 0.3048)
			(end 0.120396 0.2794)
			(stroke
				(width 0.1)
				(type default)
			)
			(layer "F.Fab")
		)
		(fp_line
			(start 0.12065 -0.3048)
			(end 0.67945 -0.3048)
			(stroke
				(width 0.1)
				(type default)
			)
			(layer "F.Fab")
		)
		(fp_line
			(start 0.12065 -0.2794)
			(end 0.12065 -0.3048)
			(stroke
				(width 0.1)
				(type default)
			)
			(layer "F.Fab")
		)
		(fp_line
			(start 0.67945 -0.3048)
			(end 0.67945 0.3048)
			(stroke
				(width 0.1)
				(type default)
			)
			(layer "F.Fab")
		)
		(fp_line
			(start 0.67945 0.3048)
			(end 0.120396 0.3048)
			(stroke
				(width 0.1)
				(type default)
			)
			(layer "F.Fab")
		)
		(pad "1" smd circle
			(at -0.40005 0)
			(size 0 0)
			(layers "F.Cu" "F.Mask" "F.Paste")
			(net "P3V3_AUX")
		)
		(pad "2" smd circle
			(at 0.40005 0)
			(size 0 0)
			(layers "F.Cu" "F.Mask" "F.Paste")
			(net "PU_U8_PIN1")
		)
	)
	(footprint ""
		(layer "F.Cu")
		(at 430.276 -41.783 180)
		(property "Reference" "R98"
			(at 0 0 180)
			(layer "F.SilkS")
			(hide yes)
			(effects
				(font
					(size 1.27 1.27)
				)
			)
		)
		(property "Value" ""
			(at 0 0 180)
			(layer "F.Fab")
			(effects
				(font
					(size 1.27 1.27)
				)
			)
		)
		(duplicate_pad_numbers_are_jumpers no)
		(fp_line
			(start 0.7874 0.4064)
			(end -0.7874 0.4064)
			(stroke
				(width 0.1524)
				(type default)
			)
			(layer "F.SilkS")
		)
		(fp_line
			(start 0.7874 -0.4064)
			(end 0.7874 0.4064)
			(stroke
				(width 0.1524)
				(type default)
			)
			(layer "F.SilkS")
		)
		(fp_line
			(start -0.7874 0.4064)
			(end -0.7874 -0.4064)
			(stroke
				(width 0.1524)
				(type default)
			)
			(layer "F.SilkS")
		)
		(fp_line
			(start -0.7874 -0.4064)
			(end 0.7874 -0.4064)
			(stroke
				(width 0.1524)
				(type default)
			)
			(layer "F.SilkS")
		)
		(fp_line
			(start 0.67945 0.3048)
			(end 0.120396 0.3048)
			(stroke
				(width 0.1)
				(type default)
			)
			(layer "F.Fab")
		)
		(fp_line
			(start 0.67945 -0.3048)
			(end 0.67945 0.3048)
			(stroke
				(width 0.1)
				(type default)
			)
			(layer "F.Fab")
		)
		(fp_line
			(start 0.12065 -0.2794)
			(end 0.12065 -0.3048)
			(stroke
				(width 0.1)
				(type default)
			)
			(layer "F.Fab")
		)
		(fp_line
			(start 0.12065 -0.3048)
			(end 0.67945 -0.3048)
			(stroke
				(width 0.1)
				(type default)
			)
			(layer "F.Fab")
		)
		(fp_line
			(start 0.120396 0.3048)
			(end 0.120396 0.2794)
			(stroke
				(width 0.1)
				(type default)
			)
			(layer "F.Fab")
		)
		(fp_line
			(start 0.120396 0.2794)
			(end -0.12065 0.2794)
			(stroke
				(width 0.1)
				(type default)
			)
			(layer "F.Fab")
		)
		(fp_line
			(start -0.12065 0.3048)
			(end -0.67945 0.3048)
			(stroke
				(width 0.1)
				(type default)
			)
			(layer "F.Fab")
		)
		(fp_line
			(start -0.12065 0.2794)
			(end -0.12065 0.3048)
			(stroke
				(width 0.1)
				(type default)
			)
			(layer "F.Fab")
		)
		(fp_line
			(start -0.12065 -0.2794)
			(end 0.12065 -0.2794)
			(stroke
				(width 0.1)
				(type default)
			)
			(layer "F.Fab")
		)
		(fp_line
			(start -0.12065 -0.305054)
			(end -0.12065 -0.2794)
			(stroke
				(width 0.1)
				(type default)
			)
			(layer "F.Fab")
		)
		(fp_line
			(start -0.67945 0.3048)
			(end -0.67945 -0.305054)
			(stroke
				(width 0.1)
				(type default)
			)
			(layer "F.Fab")
		)
		(fp_line
			(start -0.67945 -0.305054)
			(end -0.12065 -0.305054)
			(stroke
				(width 0.1)
				(type default)
			)
			(layer "F.Fab")
		)
		(pad "1" smd circle
			(at -0.40005 0 180)
			(size 0 0)
			(layers "F.Cu" "F.Mask" "F.Paste")
			(net "P3V3_AUX")
		)
		(pad "2" smd circle
			(at 0.40005 0 180)
			(size 0 0)
			(layers "F.Cu" "F.Mask" "F.Paste")
			(net "SKU_ID_0")
		)
	)
	(footprint ""
		(layer "F.Cu")
		(at 209.7786 -91.9988 180)
		(property "Reference" "JP6"
			(at 1.1176 -3.25247 0)
			(unlocked yes)
			(layer "F.SilkS")
			(effects
				(font
					(size 0.7874 0.5842)
					(thickness 0.1524)
				)
				(justify left)
			)
		)
		(property "Value" ""
			(at 0 0 180)
			(layer "F.Fab")
			(effects
				(font
					(size 1.27 1.27)
				)
			)
		)
		(duplicate_pad_numbers_are_jumpers no)
		(fp_line
			(start 1.234948 6.415024)
			(end -1.234948 6.415024)
			(stroke
				(width 0.1524)
				(type default)
			)
			(layer "F.SilkS")
		)
		(fp_line
			(start 1.234948 -1.335024)
			(end 1.234948 6.415024)
			(stroke
				(width 0.1524)
				(type default)
			)
			(layer "F.SilkS")
		)
		(fp_line
			(start -1.234948 6.415024)
			(end -1.234948 -1.335024)
			(stroke
				(width 0.1524)
				(type default)
			)
			(layer "F.SilkS")
		)
		(fp_line
			(start -1.234948 -1.335024)
			(end 1.234948 -1.335024)
			(stroke
				(width 0.1524)
				(type default)
			)
			(layer "F.SilkS")
		)
		(fp_poly
			(pts
				(xy 0.508 -2.530348) (xy -0.508 -2.530348) (xy 0 -1.514348)
			)
			(stroke
				(width 0)
				(type default)
			)
			(fill yes)
			(layer "F.SilkS")
		)
		(fp_line
			(start 1.234948 6.415024)
			(end -1.234948 6.415024)
			(stroke
				(width 0.1)
				(type default)
			)
			(layer "F.Fab")
		)
		(fp_line
			(start 1.234948 -1.335024)
			(end 1.234948 6.415024)
			(stroke
				(width 0.1)
				(type default)
			)
			(layer "F.Fab")
		)
		(fp_line
			(start -1.234948 6.415024)
			(end -1.234948 -1.335024)
			(stroke
				(width 0.1)
				(type default)
			)
			(layer "F.Fab")
		)
		(fp_line
			(start -1.234948 -1.335024)
			(end 1.234948 -1.335024)
			(stroke
				(width 0.1)
				(type default)
			)
			(layer "F.Fab")
		)
		(fp_poly
			(pts
				(xy 0.508 -2.530348) (xy -0.508 -2.530348) (xy 0 -1.514348)
			)
			(stroke
				(width 0)
				(type default)
			)
			(fill yes)
			(layer "F.Fab")
		)
		(fp_text user "3"
			(at -0.009652 6.5659 90)
			(unlocked yes)
			(layer "F.SilkS")
			(effects
				(font
					(size 0.7874 0.5842)
					(thickness 0.1524)
				)
				(justify left)
			)
		)
		(fp_text user "3"
			(at -0.00127 6.640576 90)
			(unlocked yes)
			(layer "B.SilkS")
			(effects
				(font
					(size 0.7874 0.5842)
					(thickness 0.1524)
				)
				(justify left mirror)
			)
		)
		(fp_text user "1"
			(at -0.00127 -0.954024 90)
			(unlocked yes)
			(layer "B.SilkS")
			(effects
				(font
					(size 0.7874 0.5842)
					(thickness 0.1524)
				)
				(justify left mirror)
			)
		)
		(fp_text user "3"
			(at -0.00127 6.640576 90)
			(unlocked yes)
			(layer "B.Fab")
			(effects
				(font
					(size 0.7874 0.5842)
					(thickness 0.1524)
				)
				(justify left mirror)
			)
		)
		(fp_text user "1"
			(at -0.00127 -0.954024 90)
			(unlocked yes)
			(layer "B.Fab")
			(effects
				(font
					(size 0.7874 0.5842)
					(thickness 0.1524)
				)
				(justify left mirror)
			)
		)
		(fp_text user "3"
			(at -0.009652 6.5659 90)
			(unlocked yes)
			(layer "F.Fab")
			(effects
				(font
					(size 0.7874 0.5842)
					(thickness 0.1524)
				)
				(justify left)
			)
		)
		(pad "1" thru_hole rect
			(at 0 0 90)
			(size 1.6764 1.6764)
			(drill 1.1684)
			(layers "*.Cu" "*.Mask")
			(remove_unused_layers no)
			(net "TP_P52V_HS2_EN")
			(clearance 0)
			(padstack
				(mode front_inner_back)
				(layer "Inner"
					(shape circle)
					(size 1.6764 1.6764)
					(clearance 0)
				)
				(layer "B.Cu"
					(shape rect)
					(size 1.6764 1.6764)
					(clearance 0)
				)
			)
		)
		(pad "2" thru_hole circle
			(at 0 2.54 90)
			(size 1.6764 1.6764)
			(drill 1.1684)
			(layers "*.Cu" "*.Mask")
			(remove_unused_layers no)
			(net "GPU_HSC2_BUF_EN_N")
			(clearance 0)
		)
		(pad "3" thru_hole circle
			(at 0 5.08 90)
			(size 1.6764 1.6764)
			(drill 1.1684)
			(layers "*.Cu" "*.Mask")
			(remove_unused_layers no)
			(net "GND")
			(clearance 0)
		)
	)
	(footprint ""
		(layer "F.Cu")
		(at 42.36339 -119.38)
		(property "Reference" "PC36"
			(at 6.04901 -4.79933 0)
			(unlocked yes)
			(layer "F.SilkS")
			(effects
				(font
					(size 0.7874 0.5842)
					(thickness 0.1524)
				)
				(justify left)
			)
		)
		(property "Value" ""
			(at 0 0 0)
			(layer "F.Fab")
			(effects
				(font
					(size 1.27 1.27)
				)
			)
		)
		(duplicate_pad_numbers_are_jumpers no)
		(fp_line
			(start -9.253728 3.750056)
			(end 9.249918 3.750056)
			(stroke
				(width 0.1524)
				(type default)
			)
			(layer "F.SilkS")
		)
		(fp_line
			(start 0 3.750056)
			(end -9.253728 3.750056)
			(stroke
				(width 0.1524)
				(type default)
			)
			(layer "F.SilkS")
		)
		(fp_circle
			(center 0 3.750056)
			(end 9.249918 3.750056)
			(stroke
				(width 0.1524)
				(type default)
			)
			(fill no)
			(layer "F.SilkS")
		)
		(fp_poly
			(pts
				(arc
					(start 9.249918 3.750056)
					(mid 0 12.999974)
					(end -9.249918 3.750056)
				)
			)
			(stroke
				(width 0)
				(type default)
			)
			(fill yes)
			(layer "F.SilkS")
		)
		(fp_circle
			(center 0 3.750056)
			(end 9.249918 3.750056)
			(stroke
				(width 0.1)
				(type default)
			)
			(fill no)
			(layer "F.Fab")
		)
		(pad "1" thru_hole rect
			(at 0 0)
			(size 1.778 1.778)
			(drill 1.27)
			(layers "*.Cu" "*.Mask")
			(remove_unused_layers no)
			(net "P52V_HS2")
			(clearance 0)
			(padstack
				(mode front_inner_back)
				(layer "Inner"
					(shape circle)
					(size 1.778 1.778)
					(clearance 0)
				)
				(layer "B.Cu"
					(shape rect)
					(size 1.778 1.778)
					(clearance 0)
				)
			)
		)
		(pad "2" thru_hole circle
			(at 0 7.500112)
			(size 1.778 1.778)
			(drill 1.27)
			(layers "*.Cu" "*.Mask")
			(remove_unused_layers no)
			(net "GND")
			(clearance 0)
		)
	)
	(footprint ""
		(layer "F.Cu")
		(at 100.000308 -87.499952 180)
		(property "Reference" "H5"
			(at 0.686308 10.390378 0)
			(unlocked yes)
			(layer "F.SilkS")
			(effects
				(font
					(size 0.7874 0.5842)
					(thickness 0.1524)
				)
				(justify left)
			)
		)
		(property "Value" ""
			(at 0 0 180)
			(layer "F.Fab")
			(effects
				(font
					(size 1.27 1.27)
				)
			)
		)
		(duplicate_pad_numbers_are_jumpers no)
		(pad "1" thru_hole oval
			(at 0 0 180)
			(size 9.017 14.0208)
			(drill 3.0226
				(offset 0 2.499868)
			)
			(layers "*.Cu" "*.Mask")
			(remove_unused_layers no)
			(net "GND")
			(clearance -1.500378)
			(padstack
				(mode front_inner_back)
				(layer "Inner"
					(shape circle)
					(size 0 0)
					(clearance 0)
				)
				(layer "B.Cu"
					(shape oval)
					(size 9.017 14.0208)
					(offset 0 2.499868)
					(clearance -1.500378)
				)
			)
		)
	)
	(footprint ""
		(layer "F.Cu")
		(at 49.85639 -30.226 180)
		(property "Reference" "PQ18"
			(at -0.56261 2.51333 0)
			(unlocked yes)
			(layer "F.SilkS")
			(effects
				(font
					(size 0.7874 0.5842)
					(thickness 0.1524)
				)
				(justify left)
			)
		)
		(property "Value" ""
			(at 0 0 180)
			(layer "F.Fab")
			(effects
				(font
					(size 1.27 1.27)
				)
			)
		)
		(duplicate_pad_numbers_are_jumpers no)
		(fp_line
			(start 1.905 1.651)
			(end -1.905 1.651)
			(stroke
				(width 0.1524)
				(type default)
			)
			(layer "F.SilkS")
		)
		(fp_line
			(start 1.905 -1.651)
			(end 1.905 1.651)
			(stroke
				(width 0.1524)
				(type default)
			)
			(layer "F.SilkS")
		)
		(fp_line
			(start -1.905 1.651)
			(end -1.905 -1.651)
			(stroke
				(width 0.1524)
				(type default)
			)
			(layer "F.SilkS")
		)
		(fp_line
			(start -1.905 -1.651)
			(end 1.905 -1.651)
			(stroke
				(width 0.1524)
				(type default)
			)
			(layer "F.SilkS")
		)
		(fp_line
			(start 1.249934 0.219964)
			(end 0.6985 0.219964)
			(stroke
				(width 0.1)
				(type default)
			)
			(layer "F.Fab")
		)
		(fp_line
			(start 1.249934 -0.219964)
			(end 1.249934 0.219964)
			(stroke
				(width 0.1)
				(type default)
			)
			(layer "F.Fab")
		)
		(fp_line
			(start 0.6985 1.524)
			(end -0.649986 1.524)
			(stroke
				(width 0.1)
				(type default)
			)
			(layer "F.Fab")
		)
		(fp_line
			(start 0.6985 0.219964)
			(end 0.6985 1.524)
			(stroke
				(width 0.1)
				(type default)
			)
			(layer "F.Fab")
		)
		(fp_line
			(start 0.6985 -0.219964)
			(end 1.249934 -0.219964)
			(stroke
				(width 0.1)
				(type default)
			)
			(layer "F.Fab")
		)
		(fp_line
			(start 0.6985 -1.524)
			(end 0.6985 -0.219964)
			(stroke
				(width 0.1)
				(type default)
			)
			(layer "F.Fab")
		)
		(fp_line
			(start -0.649986 1.524)
			(end -0.649986 1.169924)
			(stroke
				(width 0.1)
				(type default)
			)
			(layer "F.Fab")
		)
		(fp_line
			(start -0.649986 1.169924)
			(end -1.249934 1.169924)
			(stroke
				(width 0.1)
				(type default)
			)
			(layer "F.Fab")
		)
		(fp_line
			(start -0.649986 -1.169924)
			(end -0.649986 -1.524)
			(stroke
				(width 0.1)
				(type default)
			)
			(layer "F.Fab")
		)
		(fp_line
			(start -0.649986 -1.524)
			(end 0.6985 -1.524)
			(stroke
				(width 0.1)
				(type default)
			)
			(layer "F.Fab")
		)
		(fp_line
			(start -0.6985 0.729996)
			(end -0.6985 -0.729996)
			(stroke
				(width 0.1)
				(type default)
			)
			(layer "F.Fab")
		)
		(fp_line
			(start -0.6985 -0.729996)
			(end -1.249934 -0.729996)
			(stroke
				(width 0.1)
				(type default)
			)
			(layer "F.Fab")
		)
		(fp_line
			(start -1.249934 1.169924)
			(end -1.249934 0.729996)
			(stroke
				(width 0.1)
				(type default)
			)
			(layer "F.Fab")
		)
		(fp_line
			(start -1.249934 0.729996)
			(end -0.6985 0.729996)
			(stroke
				(width 0.1)
				(type default)
			)
			(layer "F.Fab")
		)
		(fp_line
			(start -1.249934 -0.729996)
			(end -1.249934 -1.169924)
			(stroke
				(width 0.1)
				(type default)
			)
			(layer "F.Fab")
		)
		(fp_line
			(start -1.249934 -1.169924)
			(end -0.649986 -1.169924)
			(stroke
				(width 0.1)
				(type default)
			)
			(layer "F.Fab")
		)
		(pad "B" smd rect
			(at -1.1176 -1.016 90)
			(size 1.016 1.27)
			(layers "F.Cu" "F.Mask" "F.Paste")
			(net "P52V_HS2_EN_DISCHARGE_VBE")
		)
		(pad "C" smd rect
			(at 1.1176 0 90)
			(size 1.016 1.27)
			(layers "F.Cu" "F.Mask" "F.Paste")
			(net "P52V_HS2_EN_DISCHARGE_N")
		)
		(pad "E" smd rect
			(at -1.1176 1.016 90)
			(size 1.016 1.27)
			(layers "F.Cu" "F.Mask" "F.Paste")
			(net "GND")
		)
	)
	(footprint ""
		(layer "F.Cu")
		(at 449.326 -34.163)
		(property "Reference" "C3"
			(at 0 0 0)
			(layer "F.SilkS")
			(hide yes)
			(effects
				(font
					(size 1.27 1.27)
				)
			)
		)
		(property "Value" ""
			(at 0 0 0)
			(layer "F.Fab")
			(effects
				(font
					(size 1.27 1.27)
				)
			)
		)
		(duplicate_pad_numbers_are_jumpers no)
		(fp_line
			(start -0.7874 -0.4064)
			(end 0.7874 -0.4064)
			(stroke
				(width 0.1524)
				(type default)
			)
			(layer "F.SilkS")
		)
		(fp_line
			(start -0.7874 0.4064)
			(end -0.7874 -0.4064)
			(stroke
				(width 0.1524)
				(type default)
			)
			(layer "F.SilkS")
		)
		(fp_line
			(start 0.7874 -0.4064)
			(end 0.7874 0.4064)
			(stroke
				(width 0.1524)
				(type default)
			)
			(layer "F.SilkS")
		)
		(fp_line
			(start 0.7874 0.4064)
			(end -0.7874 0.4064)
			(stroke
				(width 0.1524)
				(type default)
			)
			(layer "F.SilkS")
		)
		(fp_line
			(start -0.67945 -0.305054)
			(end -0.12065 -0.305054)
			(stroke
				(width 0.1)
				(type default)
			)
			(layer "F.Fab")
		)
		(fp_line
			(start -0.67945 0.3048)
			(end -0.67945 -0.305054)
			(stroke
				(width 0.1)
				(type default)
			)
			(layer "F.Fab")
		)
		(fp_line
			(start -0.12065 -0.305054)
			(end -0.12065 -0.2794)
			(stroke
				(width 0.1)
				(type default)
			)
			(layer "F.Fab")
		)
		(fp_line
			(start -0.12065 -0.2794)
			(end 0.12065 -0.2794)
			(stroke
				(width 0.1)
				(type default)
			)
			(layer "F.Fab")
		)
		(fp_line
			(start -0.12065 0.2794)
			(end -0.12065 0.3048)
			(stroke
				(width 0.1)
				(type default)
			)
			(layer "F.Fab")
		)
		(fp_line
			(start -0.12065 0.3048)
			(end -0.67945 0.3048)
			(stroke
				(width 0.1)
				(type default)
			)
			(layer "F.Fab")
		)
		(fp_line
			(start 0.120396 0.2794)
			(end -0.12065 0.2794)
			(stroke
				(width 0.1)
				(type default)
			)
			(layer "F.Fab")
		)
		(fp_line
			(start 0.120396 0.3048)
			(end 0.120396 0.2794)
			(stroke
				(width 0.1)
				(type default)
			)
			(layer "F.Fab")
		)
		(fp_line
			(start 0.12065 -0.3048)
			(end 0.67945 -0.3048)
			(stroke
				(width 0.1)
				(type default)
			)
			(layer "F.Fab")
		)
		(fp_line
			(start 0.12065 -0.2794)
			(end 0.12065 -0.3048)
			(stroke
				(width 0.1)
				(type default)
			)
			(layer "F.Fab")
		)
		(fp_line
			(start 0.67945 -0.3048)
			(end 0.67945 0.3048)
			(stroke
				(width 0.1)
				(type default)
			)
			(layer "F.Fab")
		)
		(fp_line
			(start 0.67945 0.3048)
			(end 0.120396 0.3048)
			(stroke
				(width 0.1)
				(type default)
			)
			(layer "F.Fab")
		)
		(pad "1" smd circle
			(at -0.40005 0)
			(size 0 0)
			(layers "F.Cu" "F.Mask" "F.Paste")
			(net "P3V3_AUX")
		)
		(pad "2" smd circle
			(at 0.40005 0)
			(size 0 0)
			(layers "F.Cu" "F.Mask" "F.Paste")
			(net "GND")
		)
	)
	(footprint ""
		(layer "F.Cu")
		(at 77.851 -55.4736)
		(property "Reference" "DM1"
			(at 0 0 0)
			(layer "F.SilkS")
			(hide yes)
			(effects
				(font
					(size 1.27 1.27)
				)
			)
		)
		(property "Value" ""
			(at 0 0 0)
			(layer "F.Fab")
			(effects
				(font
					(size 1.27 1.27)
				)
			)
		)
		(duplicate_pad_numbers_are_jumpers no)
		(fp_line
			(start 0 -4.99999)
			(end 0 -3.47599)
			(stroke
				(width 0.1524)
				(type default)
			)
			(layer "F.SilkS")
		)
		(fp_line
			(start 0 -1.524)
			(end 0 0)
			(stroke
				(width 0.1524)
				(type default)
			)
			(layer "F.SilkS")
		)
		(fp_line
			(start 1.524 -4.99999)
			(end 0 -4.99999)
			(stroke
				(width 0.1524)
				(type default)
			)
			(layer "F.SilkS")
		)
		(fp_text user "P/N"
			(at 0.361188 -3.449828 0)
			(unlocked yes)
			(layer "F.SilkS")
			(effects
				(font
					(size 1.905 1.4224)
					(thickness 0.1524)
				)
				(justify left)
			)
		)
	)
	(footprint ""
		(layer "F.Cu")
		(at 449.326 -31.623 180)
		(property "Reference" "R20"
			(at 0 0 180)
			(layer "F.SilkS")
			(hide yes)
			(effects
				(font
					(size 1.27 1.27)
				)
			)
		)
		(property "Value" ""
			(at 0 0 180)
			(layer "F.Fab")
			(effects
				(font
					(size 1.27 1.27)
				)
			)
		)
		(duplicate_pad_numbers_are_jumpers no)
		(fp_line
			(start 0.7874 0.4064)
			(end -0.7874 0.4064)
			(stroke
				(width 0.1524)
				(type default)
			)
			(layer "F.SilkS")
		)
		(fp_line
			(start 0.7874 -0.4064)
			(end 0.7874 0.4064)
			(stroke
				(width 0.1524)
				(type default)
			)
			(layer "F.SilkS")
		)
		(fp_line
			(start -0.7874 0.4064)
			(end -0.7874 -0.4064)
			(stroke
				(width 0.1524)
				(type default)
			)
			(layer "F.SilkS")
		)
		(fp_line
			(start -0.7874 -0.4064)
			(end 0.7874 -0.4064)
			(stroke
				(width 0.1524)
				(type default)
			)
			(layer "F.SilkS")
		)
		(fp_line
			(start 0.67945 0.3048)
			(end 0.120396 0.3048)
			(stroke
				(width 0.1)
				(type default)
			)
			(layer "F.Fab")
		)
		(fp_line
			(start 0.67945 -0.3048)
			(end 0.67945 0.3048)
			(stroke
				(width 0.1)
				(type default)
			)
			(layer "F.Fab")
		)
		(fp_line
			(start 0.12065 -0.2794)
			(end 0.12065 -0.3048)
			(stroke
				(width 0.1)
				(type default)
			)
			(layer "F.Fab")
		)
		(fp_line
			(start 0.12065 -0.3048)
			(end 0.67945 -0.3048)
			(stroke
				(width 0.1)
				(type default)
			)
			(layer "F.Fab")
		)
		(fp_line
			(start 0.120396 0.3048)
			(end 0.120396 0.2794)
			(stroke
				(width 0.1)
				(type default)
			)
			(layer "F.Fab")
		)
		(fp_line
			(start 0.120396 0.2794)
			(end -0.12065 0.2794)
			(stroke
				(width 0.1)
				(type default)
			)
			(layer "F.Fab")
		)
		(fp_line
			(start -0.12065 0.3048)
			(end -0.67945 0.3048)
			(stroke
				(width 0.1)
				(type default)
			)
			(layer "F.Fab")
		)
		(fp_line
			(start -0.12065 0.2794)
			(end -0.12065 0.3048)
			(stroke
				(width 0.1)
				(type default)
			)
			(layer "F.Fab")
		)
		(fp_line
			(start -0.12065 -0.2794)
			(end 0.12065 -0.2794)
			(stroke
				(width 0.1)
				(type default)
			)
			(layer "F.Fab")
		)
		(fp_line
			(start -0.12065 -0.305054)
			(end -0.12065 -0.2794)
			(stroke
				(width 0.1)
				(type default)
			)
			(layer "F.Fab")
		)
		(fp_line
			(start -0.67945 0.3048)
			(end -0.67945 -0.305054)
			(stroke
				(width 0.1)
				(type default)
			)
			(layer "F.Fab")
		)
		(fp_line
			(start -0.67945 -0.305054)
			(end -0.12065 -0.305054)
			(stroke
				(width 0.1)
				(type default)
			)
			(layer "F.Fab")
		)
		(pad "1" smd circle
			(at -0.40005 0 180)
			(size 0 0)
			(layers "F.Cu" "F.Mask" "F.Paste")
			(net "SMB_PDB_MISC_SCL_R1")
		)
		(pad "2" smd circle
			(at 0.40005 0 180)
			(size 0 0)
			(layers "F.Cu" "F.Mask" "F.Paste")
			(net "SMB_FAN_MUX_SCL")
		)
	)
	(footprint ""
		(layer "F.Cu")
		(at 42.36339 -35.053778 90)
		(property "Reference" "PQ16"
			(at 2.538222 6.71068 90)
			(unlocked yes)
			(layer "F.SilkS")
			(effects
				(font
					(size 0.7874 0.5842)
					(thickness 0.1524)
				)
				(justify left)
			)
		)
		(property "Value" ""
			(at 0 0 90)
			(layer "F.Fab")
			(effects
				(font
					(size 1.27 1.27)
				)
			)
		)
		(duplicate_pad_numbers_are_jumpers no)
		(fp_line
			(start 7.649972 -4.99999)
			(end 7.630414 -4.99999)
			(stroke
				(width 0.1524)
				(type default)
			)
			(layer "F.SilkS")
		)
		(fp_line
			(start 5.115814 -4.99999)
			(end -7.649972 -4.99999)
			(stroke
				(width 0.1524)
				(type default)
			)
			(layer "F.SilkS")
		)
		(fp_line
			(start -7.649972 -4.99999)
			(end -7.649972 -3.3274)
			(stroke
				(width 0.1524)
				(type default)
			)
			(layer "F.SilkS")
		)
		(fp_line
			(start -7.649972 -1.7526)
			(end -7.649972 1.7526)
			(stroke
				(width 0.1524)
				(type default)
			)
			(layer "F.SilkS")
		)
		(fp_line
			(start -7.649972 3.3274)
			(end -7.649972 4.99999)
			(stroke
				(width 0.1524)
				(type default)
			)
			(layer "F.SilkS")
		)
		(fp_line
			(start 7.649972 4.99999)
			(end 7.649972 -4.99999)
			(stroke
				(width 0.1524)
				(type default)
			)
			(layer "F.SilkS")
		)
		(fp_line
			(start 7.630414 4.99999)
			(end 7.649972 4.99999)
			(stroke
				(width 0.1524)
				(type default)
			)
			(layer "F.SilkS")
		)
		(fp_line
			(start -7.649972 4.99999)
			(end 5.115814 4.99999)
			(stroke
				(width 0.1524)
				(type default)
			)
			(layer "F.SilkS")
		)
		(fp_line
			(start 7.649972 -4.99999)
			(end -7.649972 -4.99999)
			(stroke
				(width 0.1)
				(type default)
			)
			(layer "F.Fab")
		)
		(fp_line
			(start -7.649972 -4.99999)
			(end -7.649972 4.99999)
			(stroke
				(width 0.1)
				(type default)
			)
			(layer "F.Fab")
		)
		(fp_line
			(start 7.649972 4.99999)
			(end 7.649972 -4.99999)
			(stroke
				(width 0.1)
				(type default)
			)
			(layer "F.Fab")
		)
		(fp_line
			(start -7.649972 4.99999)
			(end 7.649972 4.99999)
			(stroke
				(width 0.1)
				(type default)
			)
			(layer "F.Fab")
		)
		(pad "D" smd circle
			(at 2.15011 0 90)
			(size 0 0)
			(layers "F.Cu" "F.Mask" "F.Paste")
			(net "P52V_HS2")
		)
		(pad "G" smd rect
			(at -7.050024 -2.54)
			(size 1.3208 3.0988)
			(layers "F.Cu" "F.Mask" "F.Paste")
			(net "P52V_HS2_EN_DISCHARGE_N")
		)
		(pad "S" smd rect
			(at -7.050024 2.54)
			(size 1.3208 3.0988)
			(layers "F.Cu" "F.Mask" "F.Paste")
			(net "P52V_HS2_EN_DISCHARGE_VBE_R")
		)
		(zone
			(layer "F.Cu")
			(hatch none 0.5)
			(connect_pads
				(clearance 0)
			)
			(min_thickness 0.25)
			(keepout
				(tracks not_allowed)
				(vias allowed)
				(pads allowed)
				(copperpour not_allowed)
				(footprints allowed)
			)
			(placement
				(enabled no)
				(sheetname "")
			)
			(fill
				(thermal_gap 0.5)
				(thermal_bridge_width 0.5)
				(island_removal_mode 0)
			)
			(polygon
				(pts
					(xy 37.38499 -40.235378) (xy 37.38499 -27.408378) (xy 39.11219 -27.408378) (xy 39.11219 -29.618178)
					(xy 40.53459 -29.618178) (xy 40.53459 -27.408378) (xy 44.19219 -27.408378) (xy 44.19219 -29.618178)
					(xy 45.61459 -29.618178) (xy 45.61459 -27.408378) (xy 47.34179 -27.408378) (xy 47.34179 -40.235378)
					(xy 46.17339 -40.235378) (xy 46.17339 -34.037778) (xy 38.55339 -34.037778) (xy 38.55339 -40.235378)
				)
			)
		)
	)
	(footprint ""
		(layer "F.Cu")
		(at 381.4064 -31.242 90)
		(property "Reference" "PD8"
			(at -4.7752 -3.749548 90)
			(unlocked yes)
			(layer "F.SilkS")
			(effects
				(font
					(size 0.7874 0.5842)
					(thickness 0.1524)
				)
				(justify left)
			)
		)
		(property "Value" ""
			(at 0 0 90)
			(layer "F.Fab")
			(effects
				(font
					(size 1.27 1.27)
				)
			)
		)
		(duplicate_pad_numbers_are_jumpers no)
		(fp_line
			(start 4.826 -3.109976)
			(end 4.826 0)
			(stroke
				(width 0.1524)
				(type default)
			)
			(layer "F.SilkS")
		)
		(fp_line
			(start 4.8133 -3.109976)
			(end 5.3467 -3.109976)
			(stroke
				(width 0.1524)
				(type default)
			)
			(layer "F.SilkS")
		)
		(fp_line
			(start -4.826 -3.109976)
			(end 4.826 -3.109976)
			(stroke
				(width 0.1524)
				(type default)
			)
			(layer "F.SilkS")
		)
		(fp_line
			(start -1.016 -1.016)
			(end -1.016 1.016)
			(stroke
				(width 0.1524)
				(type default)
			)
			(layer "F.SilkS")
		)
		(fp_line
			(start 5.334 0)
			(end 5.334 -3.109976)
			(stroke
				(width 0.1524)
				(type default)
			)
			(layer "F.SilkS")
		)
		(fp_line
			(start 4.826 0)
			(end 4.826 3.109976)
			(stroke
				(width 0.1524)
				(type default)
			)
			(layer "F.SilkS")
		)
		(fp_line
			(start 1.143 0)
			(end -1.016 -1.016)
			(stroke
				(width 0.1524)
				(type default)
			)
			(layer "F.SilkS")
		)
		(fp_line
			(start 1.143 0)
			(end 1.8034 0)
			(stroke
				(width 0.1524)
				(type default)
			)
			(layer "F.SilkS")
		)
		(fp_line
			(start -1.0922 0)
			(end -1.7018 0)
			(stroke
				(width 0.1524)
				(type default)
			)
			(layer "F.SilkS")
		)
		(fp_line
			(start -4.826 0)
			(end -4.826 -3.109976)
			(stroke
				(width 0.1524)
				(type default)
			)
			(layer "F.SilkS")
		)
		(fp_line
			(start -1.016 1.016)
			(end 1.016 0)
			(stroke
				(width 0.1524)
				(type default)
			)
			(layer "F.SilkS")
		)
		(fp_line
			(start 1.143 1.397)
			(end 1.143 -1.397)
			(stroke
				(width 0.1524)
				(type default)
			)
			(layer "F.SilkS")
		)
		(fp_line
			(start 5.334 3.109976)
			(end 5.334 0)
			(stroke
				(width 0.1524)
				(type default)
			)
			(layer "F.SilkS")
		)
		(fp_line
			(start 5.334 3.109976)
			(end 4.8133 3.109976)
			(stroke
				(width 0.1524)
				(type default)
			)
			(layer "F.SilkS")
		)
		(fp_line
			(start 5.207 3.109976)
			(end 5.207 -3.109976)
			(stroke
				(width 0.1524)
				(type default)
			)
			(layer "F.SilkS")
		)
		(fp_line
			(start 5.1308 3.109976)
			(end 5.1308 -3.109976)
			(stroke
				(width 0.1524)
				(type default)
			)
			(layer "F.SilkS")
		)
		(fp_line
			(start 5.0292 3.109976)
			(end 5.0292 -3.109976)
			(stroke
				(width 0.1524)
				(type default)
			)
			(layer "F.SilkS")
		)
		(fp_line
			(start 4.9276 3.109976)
			(end 4.9276 -3.109976)
			(stroke
				(width 0.1524)
				(type default)
			)
			(layer "F.SilkS")
		)
		(fp_line
			(start 4.826 3.109976)
			(end -4.826 3.109976)
			(stroke
				(width 0.1524)
				(type default)
			)
			(layer "F.SilkS")
		)
		(fp_line
			(start -4.826 3.109976)
			(end -4.826 0)
			(stroke
				(width 0.1524)
				(type default)
			)
			(layer "F.SilkS")
		)
		(fp_line
			(start 3.554984 -3.109976)
			(end 3.554984 3.109976)
			(stroke
				(width 0.1)
				(type default)
			)
			(layer "F.Fab")
		)
		(fp_line
			(start -3.554984 -3.109976)
			(end 3.554984 -3.109976)
			(stroke
				(width 0.1)
				(type default)
			)
			(layer "F.Fab")
		)
		(fp_line
			(start -1.016 -1.016)
			(end -1.016 1.016)
			(stroke
				(width 0.1)
				(type default)
			)
			(layer "F.Fab")
		)
		(fp_line
			(start 1.143 0)
			(end -1.016 -1.016)
			(stroke
				(width 0.1)
				(type default)
			)
			(layer "F.Fab")
		)
		(fp_line
			(start 1.143 0)
			(end 1.8034 0)
			(stroke
				(width 0.1)
				(type default)
			)
			(layer "F.Fab")
		)
		(fp_line
			(start -1.0922 0)
			(end -1.7018 0)
			(stroke
				(width 0.1)
				(type default)
			)
			(layer "F.Fab")
		)
		(fp_line
			(start -1.016 1.016)
			(end 1.016 0)
			(stroke
				(width 0.1)
				(type default)
			)
			(layer "F.Fab")
		)
		(fp_line
			(start 1.143 1.397)
			(end 1.143 -1.397)
			(stroke
				(width 0.1)
				(type default)
			)
			(layer "F.Fab")
		)
		(fp_line
			(start 3.554984 3.109976)
			(end -3.554984 3.109976)
			(stroke
				(width 0.1)
				(type default)
			)
			(layer "F.Fab")
		)
		(fp_line
			(start -3.554984 3.109976)
			(end -3.554984 -3.109976)
			(stroke
				(width 0.1)
				(type default)
			)
			(layer "F.Fab")
		)
		(fp_text user "+"
			(at -4.5466 0.19685 270)
			(unlocked yes)
			(layer "F.SilkS")
			(effects
				(font
					(size 1.905 1.4224)
					(thickness 0.1524)
				)
				(justify left)
			)
		)
		(fp_text user "-"
			(at 6.6802 0.22225 270)
			(unlocked yes)
			(layer "F.SilkS")
			(effects
				(font
					(size 1.905 1.4224)
					(thickness 0.1524)
				)
				(justify left)
			)
		)
		(fp_text user "+"
			(at -4.5466 0.19685 270)
			(unlocked yes)
			(layer "F.Fab")
			(effects
				(font
					(size 1.905 1.4224)
					(thickness 0.1524)
				)
				(justify left)
			)
		)
		(fp_text user "-"
			(at 6.6802 0.22225 270)
			(unlocked yes)
			(layer "F.Fab")
			(effects
				(font
					(size 1.905 1.4224)
					(thickness 0.1524)
				)
				(justify left)
			)
		)
		(pad "A" smd rect
			(at -3.400044 0 270)
			(size 2.5146 3.302)
			(layers "F.Cu" "F.Mask" "F.Paste")
			(net "GND")
		)
		(pad "C" smd rect
			(at 3.400044 0 270)
			(size 2.5146 3.302)
			(layers "F.Cu" "F.Mask" "F.Paste")
			(net "P52V_HS1")
		)
	)
	(footprint ""
		(layer "F.Cu")
		(at 302.4124 -71.755 180)
		(property "Reference" "PR6956"
			(at 0 0 180)
			(layer "F.SilkS")
			(hide yes)
			(effects
				(font
					(size 1.27 1.27)
				)
			)
		)
		(property "Value" ""
			(at 0 0 180)
			(layer "F.Fab")
			(effects
				(font
					(size 1.27 1.27)
				)
			)
		)
		(duplicate_pad_numbers_are_jumpers no)
		(fp_line
			(start 1.2954 0.5842)
			(end -1.2954 0.5842)
			(stroke
				(width 0.1524)
				(type default)
			)
			(layer "F.SilkS")
		)
		(fp_line
			(start 1.2954 -0.5842)
			(end 1.2954 0.5842)
			(stroke
				(width 0.1524)
				(type default)
			)
			(layer "F.SilkS")
		)
		(fp_line
			(start -1.2954 0.5842)
			(end -1.2954 -0.5842)
			(stroke
				(width 0.1524)
				(type default)
			)
			(layer "F.SilkS")
		)
		(fp_line
			(start -1.2954 -0.5842)
			(end 1.2954 -0.5842)
			(stroke
				(width 0.1524)
				(type default)
			)
			(layer "F.SilkS")
		)
		(fp_line
			(start 1.1938 0.4064)
			(end 0.8636 0.4064)
			(stroke
				(width 0.1)
				(type default)
			)
			(layer "F.Fab")
		)
		(fp_line
			(start 1.1938 -0.406654)
			(end 1.1938 0.4064)
			(stroke
				(width 0.1)
				(type default)
			)
			(layer "F.Fab")
		)
		(fp_line
			(start 0.8636 0.4572)
			(end -0.8636 0.4572)
			(stroke
				(width 0.1)
				(type default)
			)
			(layer "F.Fab")
		)
		(fp_line
			(start 0.8636 0.4064)
			(end 0.8636 0.4572)
			(stroke
				(width 0.1)
				(type default)
			)
			(layer "F.Fab")
		)
		(fp_line
			(start 0.8636 -0.406654)
			(end 1.1938 -0.406654)
			(stroke
				(width 0.1)
				(type default)
			)
			(layer "F.Fab")
		)
		(fp_line
			(start 0.8636 -0.4572)
			(end 0.8636 -0.406654)
			(stroke
				(width 0.1)
				(type default)
			)
			(layer "F.Fab")
		)
		(fp_line
			(start -0.8636 0.4572)
			(end -0.8636 0.4318)
			(stroke
				(width 0.1)
				(type default)
			)
			(layer "F.Fab")
		)
		(fp_line
			(start -0.8636 0.4318)
			(end -0.8636 0.4064)
			(stroke
				(width 0.1)
				(type default)
			)
			(layer "F.Fab")
		)
		(fp_line
			(start -0.8636 0.4064)
			(end -1.1938 0.4064)
			(stroke
				(width 0.1)
				(type default)
			)
			(layer "F.Fab")
		)
		(fp_line
			(start -0.8636 -0.406654)
			(end -0.8636 -0.4572)
			(stroke
				(width 0.1)
				(type default)
			)
			(layer "F.Fab")
		)
		(fp_line
			(start -0.8636 -0.4572)
			(end 0.8636 -0.4572)
			(stroke
				(width 0.1)
				(type default)
			)
			(layer "F.Fab")
		)
		(fp_line
			(start -1.1938 0.4064)
			(end -1.1938 -0.406654)
			(stroke
				(width 0.1)
				(type default)
			)
			(layer "F.Fab")
		)
		(fp_line
			(start -1.1938 -0.406654)
			(end -0.8636 -0.406654)
			(stroke
				(width 0.1)
				(type default)
			)
			(layer "F.Fab")
		)
		(pad "1" smd rect
			(at -0.7366 0 90)
			(size 0.7112 0.8128)
			(layers "F.Cu" "F.Mask" "F.Paste")
			(net "P52V_HS_4287_S1P")
		)
		(pad "2" smd rect
			(at 0.7366 0 90)
			(size 0.7112 0.8128)
			(layers "F.Cu" "F.Mask" "F.Paste")
			(net "P52V_HS1_SENSE_P_R1")
		)
	)
	(footprint ""
		(layer "F.Cu")
		(at 334.631284 -16.51 -90)
		(property "Reference" "PR478"
			(at 0 0 270)
			(layer "F.SilkS")
			(hide yes)
			(effects
				(font
					(size 1.27 1.27)
				)
			)
		)
		(property "Value" ""
			(at 0 0 270)
			(layer "F.Fab")
			(effects
				(font
					(size 1.27 1.27)
				)
			)
		)
		(duplicate_pad_numbers_are_jumpers no)
		(fp_line
			(start -1.2954 0.5842)
			(end -1.2954 -0.5842)
			(stroke
				(width 0.1524)
				(type default)
			)
			(layer "F.SilkS")
		)
		(fp_line
			(start 1.2954 0.5842)
			(end -1.2954 0.5842)
			(stroke
				(width 0.1524)
				(type default)
			)
			(layer "F.SilkS")
		)
		(fp_line
			(start -1.2954 -0.5842)
			(end 1.2954 -0.5842)
			(stroke
				(width 0.1524)
				(type default)
			)
			(layer "F.SilkS")
		)
		(fp_line
			(start 1.2954 -0.5842)
			(end 1.2954 0.5842)
			(stroke
				(width 0.1524)
				(type default)
			)
			(layer "F.SilkS")
		)
		(fp_line
			(start -0.8636 0.4572)
			(end -0.8636 0.4318)
			(stroke
				(width 0.1)
				(type default)
			)
			(layer "F.Fab")
		)
		(fp_line
			(start 0.8636 0.4572)
			(end -0.8636 0.4572)
			(stroke
				(width 0.1)
				(type default)
			)
			(layer "F.Fab")
		)
		(fp_line
			(start -0.8636 0.4318)
			(end -0.8636 0.4064)
			(stroke
				(width 0.1)
				(type default)
			)
			(layer "F.Fab")
		)
		(fp_line
			(start -1.1938 0.4064)
			(end -1.1938 -0.406654)
			(stroke
				(width 0.1)
				(type default)
			)
			(layer "F.Fab")
		)
		(fp_line
			(start -0.8636 0.4064)
			(end -1.1938 0.4064)
			(stroke
				(width 0.1)
				(type default)
			)
			(layer "F.Fab")
		)
		(fp_line
			(start 0.8636 0.4064)
			(end 0.8636 0.4572)
			(stroke
				(width 0.1)
				(type default)
			)
			(layer "F.Fab")
		)
		(fp_line
			(start 1.1938 0.4064)
			(end 0.8636 0.4064)
			(stroke
				(width 0.1)
				(type default)
			)
			(layer "F.Fab")
		)
		(fp_line
			(start -1.1938 -0.406654)
			(end -0.8636 -0.406654)
			(stroke
				(width 0.1)
				(type default)
			)
			(layer "F.Fab")
		)
		(fp_line
			(start -0.8636 -0.406654)
			(end -0.8636 -0.4572)
			(stroke
				(width 0.1)
				(type default)
			)
			(layer "F.Fab")
		)
		(fp_line
			(start 0.8636 -0.406654)
			(end 1.1938 -0.406654)
			(stroke
				(width 0.1)
				(type default)
			)
			(layer "F.Fab")
		)
		(fp_line
			(start 1.1938 -0.406654)
			(end 1.1938 0.4064)
			(stroke
				(width 0.1)
				(type default)
			)
			(layer "F.Fab")
		)
		(fp_line
			(start -0.8636 -0.4572)
			(end 0.8636 -0.4572)
			(stroke
				(width 0.1)
				(type default)
			)
			(layer "F.Fab")
		)
		(fp_line
			(start 0.8636 -0.4572)
			(end 0.8636 -0.406654)
			(stroke
				(width 0.1)
				(type default)
			)
			(layer "F.Fab")
		)
		(pad "1" smd rect
			(at -0.7366 0 180)
			(size 0.7112 0.8128)
			(layers "F.Cu" "F.Mask" "F.Paste")
			(net "P52V_HS1_GATE2_R")
		)
		(pad "2" smd rect
			(at 0.7366 0 180)
			(size 0.7112 0.8128)
			(layers "F.Cu" "F.Mask" "F.Paste")
			(net "P52V_HS1_GATE5")
		)
	)
	(footprint ""
		(layer "F.Cu")
		(at 436.245 -29.083 180)
		(property "Reference" "R329"
			(at 0 0 180)
			(layer "F.SilkS")
			(hide yes)
			(effects
				(font
					(size 1.27 1.27)
				)
			)
		)
		(property "Value" ""
			(at 0 0 180)
			(layer "F.Fab")
			(effects
				(font
					(size 1.27 1.27)
				)
			)
		)
		(duplicate_pad_numbers_are_jumpers no)
		(fp_line
			(start 0.7874 0.4064)
			(end -0.7874 0.4064)
			(stroke
				(width 0.1524)
				(type default)
			)
			(layer "F.SilkS")
		)
		(fp_line
			(start 0.7874 -0.4064)
			(end 0.7874 0.4064)
			(stroke
				(width 0.1524)
				(type default)
			)
			(layer "F.SilkS")
		)
		(fp_line
			(start -0.7874 0.4064)
			(end -0.7874 -0.4064)
			(stroke
				(width 0.1524)
				(type default)
			)
			(layer "F.SilkS")
		)
		(fp_line
			(start -0.7874 -0.4064)
			(end 0.7874 -0.4064)
			(stroke
				(width 0.1524)
				(type default)
			)
			(layer "F.SilkS")
		)
		(fp_line
			(start 0.67945 0.3048)
			(end 0.120396 0.3048)
			(stroke
				(width 0.1)
				(type default)
			)
			(layer "F.Fab")
		)
		(fp_line
			(start 0.67945 -0.3048)
			(end 0.67945 0.3048)
			(stroke
				(width 0.1)
				(type default)
			)
			(layer "F.Fab")
		)
		(fp_line
			(start 0.12065 -0.2794)
			(end 0.12065 -0.3048)
			(stroke
				(width 0.1)
				(type default)
			)
			(layer "F.Fab")
		)
		(fp_line
			(start 0.12065 -0.3048)
			(end 0.67945 -0.3048)
			(stroke
				(width 0.1)
				(type default)
			)
			(layer "F.Fab")
		)
		(fp_line
			(start 0.120396 0.3048)
			(end 0.120396 0.2794)
			(stroke
				(width 0.1)
				(type default)
			)
			(layer "F.Fab")
		)
		(fp_line
			(start 0.120396 0.2794)
			(end -0.12065 0.2794)
			(stroke
				(width 0.1)
				(type default)
			)
			(layer "F.Fab")
		)
		(fp_line
			(start -0.12065 0.3048)
			(end -0.67945 0.3048)
			(stroke
				(width 0.1)
				(type default)
			)
			(layer "F.Fab")
		)
		(fp_line
			(start -0.12065 0.2794)
			(end -0.12065 0.3048)
			(stroke
				(width 0.1)
				(type default)
			)
			(layer "F.Fab")
		)
		(fp_line
			(start -0.12065 -0.2794)
			(end 0.12065 -0.2794)
			(stroke
				(width 0.1)
				(type default)
			)
			(layer "F.Fab")
		)
		(fp_line
			(start -0.12065 -0.305054)
			(end -0.12065 -0.2794)
			(stroke
				(width 0.1)
				(type default)
			)
			(layer "F.Fab")
		)
		(fp_line
			(start -0.67945 0.3048)
			(end -0.67945 -0.305054)
			(stroke
				(width 0.1)
				(type default)
			)
			(layer "F.Fab")
		)
		(fp_line
			(start -0.67945 -0.305054)
			(end -0.12065 -0.305054)
			(stroke
				(width 0.1)
				(type default)
			)
			(layer "F.Fab")
		)
		(pad "1" smd circle
			(at -0.40005 0 180)
			(size 0 0)
			(layers "F.Cu" "F.Mask" "F.Paste")
			(net "SMB_PDB_FAN_0_SDA")
		)
		(pad "2" smd circle
			(at 0.40005 0 180)
			(size 0 0)
			(layers "F.Cu" "F.Mask" "F.Paste")
			(net "P3V3_AUX")
		)
	)
	(footprint ""
		(layer "F.Cu")
		(at 99.568 -11.5062 -90)
		(property "Reference" "R163"
			(at 0 0 270)
			(layer "F.SilkS")
			(hide yes)
			(effects
				(font
					(size 1.27 1.27)
				)
			)
		)
		(property "Value" ""
			(at 0 0 270)
			(layer "F.Fab")
			(effects
				(font
					(size 1.27 1.27)
				)
			)
		)
		(duplicate_pad_numbers_are_jumpers no)
		(fp_line
			(start -0.7874 0.4064)
			(end -0.7874 -0.4064)
			(stroke
				(width 0.1524)
				(type default)
			)
			(layer "F.SilkS")
		)
		(fp_line
			(start 0.7874 0.4064)
			(end -0.7874 0.4064)
			(stroke
				(width 0.1524)
				(type default)
			)
			(layer "F.SilkS")
		)
		(fp_line
			(start -0.7874 -0.4064)
			(end 0.7874 -0.4064)
			(stroke
				(width 0.1524)
				(type default)
			)
			(layer "F.SilkS")
		)
		(fp_line
			(start 0.7874 -0.4064)
			(end 0.7874 0.4064)
			(stroke
				(width 0.1524)
				(type default)
			)
			(layer "F.SilkS")
		)
		(fp_line
			(start -0.67945 0.3048)
			(end -0.67945 -0.305054)
			(stroke
				(width 0.1)
				(type default)
			)
			(layer "F.Fab")
		)
		(fp_line
			(start -0.12065 0.3048)
			(end -0.67945 0.3048)
			(stroke
				(width 0.1)
				(type default)
			)
			(layer "F.Fab")
		)
		(fp_line
			(start 0.120396 0.3048)
			(end 0.120396 0.2794)
			(stroke
				(width 0.1)
				(type default)
			)
			(layer "F.Fab")
		)
		(fp_line
			(start 0.67945 0.3048)
			(end 0.120396 0.3048)
			(stroke
				(width 0.1)
				(type default)
			)
			(layer "F.Fab")
		)
		(fp_line
			(start -0.12065 0.2794)
			(end -0.12065 0.3048)
			(stroke
				(width 0.1)
				(type default)
			)
			(layer "F.Fab")
		)
		(fp_line
			(start 0.120396 0.2794)
			(end -0.12065 0.2794)
			(stroke
				(width 0.1)
				(type default)
			)
			(layer "F.Fab")
		)
		(fp_line
			(start -0.12065 -0.2794)
			(end 0.12065 -0.2794)
			(stroke
				(width 0.1)
				(type default)
			)
			(layer "F.Fab")
		)
		(fp_line
			(start 0.12065 -0.2794)
			(end 0.12065 -0.3048)
			(stroke
				(width 0.1)
				(type default)
			)
			(layer "F.Fab")
		)
		(fp_line
			(start 0.12065 -0.3048)
			(end 0.67945 -0.3048)
			(stroke
				(width 0.1)
				(type default)
			)
			(layer "F.Fab")
		)
		(fp_line
			(start 0.67945 -0.3048)
			(end 0.67945 0.3048)
			(stroke
				(width 0.1)
				(type default)
			)
			(layer "F.Fab")
		)
		(fp_line
			(start -0.67945 -0.305054)
			(end -0.12065 -0.305054)
			(stroke
				(width 0.1)
				(type default)
			)
			(layer "F.Fab")
		)
		(fp_line
			(start -0.12065 -0.305054)
			(end -0.12065 -0.2794)
			(stroke
				(width 0.1)
				(type default)
			)
			(layer "F.Fab")
		)
		(pad "1" smd circle
			(at -0.40005 0 270)
			(size 0 0)
			(layers "F.Cu" "F.Mask" "F.Paste")
			(net "PWRGD_P52V_HS2_4287_PG_R_N")
		)
		(pad "2" smd circle
			(at 0.40005 0 270)
			(size 0 0)
			(layers "F.Cu" "F.Mask" "F.Paste")
			(net "GND")
		)
	)
	(footprint ""
		(layer "F.Cu")
		(at 58.59399 -32.766 90)
		(property "Reference" "PD10"
			(at 2.413 3.91668 90)
			(unlocked yes)
			(layer "F.SilkS")
			(effects
				(font
					(size 0.7874 0.5842)
					(thickness 0.1524)
				)
				(justify left)
			)
		)
		(property "Value" ""
			(at 0 0 90)
			(layer "F.Fab")
			(effects
				(font
					(size 1.27 1.27)
				)
			)
		)
		(duplicate_pad_numbers_are_jumpers no)
		(fp_line
			(start 4.826 -3.109976)
			(end 4.826 0)
			(stroke
				(width 0.1524)
				(type default)
			)
			(layer "F.SilkS")
		)
		(fp_line
			(start 4.8133 -3.109976)
			(end 5.3467 -3.109976)
			(stroke
				(width 0.1524)
				(type default)
			)
			(layer "F.SilkS")
		)
		(fp_line
			(start -4.826 -3.109976)
			(end 4.826 -3.109976)
			(stroke
				(width 0.1524)
				(type default)
			)
			(layer "F.SilkS")
		)
		(fp_line
			(start -1.016 -1.016)
			(end -1.016 1.016)
			(stroke
				(width 0.1524)
				(type default)
			)
			(layer "F.SilkS")
		)
		(fp_line
			(start 5.334 0)
			(end 5.334 -3.109976)
			(stroke
				(width 0.1524)
				(type default)
			)
			(layer "F.SilkS")
		)
		(fp_line
			(start 4.826 0)
			(end 4.826 3.109976)
			(stroke
				(width 0.1524)
				(type default)
			)
			(layer "F.SilkS")
		)
		(fp_line
			(start 1.143 0)
			(end -1.016 -1.016)
			(stroke
				(width 0.1524)
				(type default)
			)
			(layer "F.SilkS")
		)
		(fp_line
			(start 1.143 0)
			(end 1.8034 0)
			(stroke
				(width 0.1524)
				(type default)
			)
			(layer "F.SilkS")
		)
		(fp_line
			(start -1.0922 0)
			(end -1.7018 0)
			(stroke
				(width 0.1524)
				(type default)
			)
			(layer "F.SilkS")
		)
		(fp_line
			(start -4.826 0)
			(end -4.826 -3.109976)
			(stroke
				(width 0.1524)
				(type default)
			)
			(layer "F.SilkS")
		)
		(fp_line
			(start -1.016 1.016)
			(end 1.016 0)
			(stroke
				(width 0.1524)
				(type default)
			)
			(layer "F.SilkS")
		)
		(fp_line
			(start 1.143 1.397)
			(end 1.143 -1.397)
			(stroke
				(width 0.1524)
				(type default)
			)
			(layer "F.SilkS")
		)
		(fp_line
			(start 5.334 3.109976)
			(end 5.334 0)
			(stroke
				(width 0.1524)
				(type default)
			)
			(layer "F.SilkS")
		)
		(fp_line
			(start 5.334 3.109976)
			(end 4.8133 3.109976)
			(stroke
				(width 0.1524)
				(type default)
			)
			(layer "F.SilkS")
		)
		(fp_line
			(start 5.207 3.109976)
			(end 5.207 -3.109976)
			(stroke
				(width 0.1524)
				(type default)
			)
			(layer "F.SilkS")
		)
		(fp_line
			(start 5.1308 3.109976)
			(end 5.1308 -3.109976)
			(stroke
				(width 0.1524)
				(type default)
			)
			(layer "F.SilkS")
		)
		(fp_line
			(start 5.0292 3.109976)
			(end 5.0292 -3.109976)
			(stroke
				(width 0.1524)
				(type default)
			)
			(layer "F.SilkS")
		)
		(fp_line
			(start 4.9276 3.109976)
			(end 4.9276 -3.109976)
			(stroke
				(width 0.1524)
				(type default)
			)
			(layer "F.SilkS")
		)
		(fp_line
			(start 4.826 3.109976)
			(end -4.826 3.109976)
			(stroke
				(width 0.1524)
				(type default)
			)
			(layer "F.SilkS")
		)
		(fp_line
			(start -4.826 3.109976)
			(end -4.826 0)
			(stroke
				(width 0.1524)
				(type default)
			)
			(layer "F.SilkS")
		)
		(fp_line
			(start 3.554984 -3.109976)
			(end 3.554984 3.109976)
			(stroke
				(width 0.1)
				(type default)
			)
			(layer "F.Fab")
		)
		(fp_line
			(start -3.554984 -3.109976)
			(end 3.554984 -3.109976)
			(stroke
				(width 0.1)
				(type default)
			)
			(layer "F.Fab")
		)
		(fp_line
			(start -1.016 -1.016)
			(end -1.016 1.016)
			(stroke
				(width 0.1)
				(type default)
			)
			(layer "F.Fab")
		)
		(fp_line
			(start 1.143 0)
			(end -1.016 -1.016)
			(stroke
				(width 0.1)
				(type default)
			)
			(layer "F.Fab")
		)
		(fp_line
			(start 1.143 0)
			(end 1.8034 0)
			(stroke
				(width 0.1)
				(type default)
			)
			(layer "F.Fab")
		)
		(fp_line
			(start -1.0922 0)
			(end -1.7018 0)
			(stroke
				(width 0.1)
				(type default)
			)
			(layer "F.Fab")
		)
		(fp_line
			(start -1.016 1.016)
			(end 1.016 0)
			(stroke
				(width 0.1)
				(type default)
			)
			(layer "F.Fab")
		)
		(fp_line
			(start 1.143 1.397)
			(end 1.143 -1.397)
			(stroke
				(width 0.1)
				(type default)
			)
			(layer "F.Fab")
		)
		(fp_line
			(start 3.554984 3.109976)
			(end -3.554984 3.109976)
			(stroke
				(width 0.1)
				(type default)
			)
			(layer "F.Fab")
		)
		(fp_line
			(start -3.554984 3.109976)
			(end -3.554984 -3.109976)
			(stroke
				(width 0.1)
				(type default)
			)
			(layer "F.Fab")
		)
		(fp_text user "+"
			(at -4.5466 0.19685 270)
			(unlocked yes)
			(layer "F.SilkS")
			(effects
				(font
					(size 1.905 1.4224)
					(thickness 0.1524)
				)
				(justify left)
			)
		)
		(fp_text user "-"
			(at 6.6802 0.22225 270)
			(unlocked yes)
			(layer "F.SilkS")
			(effects
				(font
					(size 1.905 1.4224)
					(thickness 0.1524)
				)
				(justify left)
			)
		)
		(fp_text user "+"
			(at -4.5466 0.19685 270)
			(unlocked yes)
			(layer "F.Fab")
			(effects
				(font
					(size 1.905 1.4224)
					(thickness 0.1524)
				)
				(justify left)
			)
		)
		(fp_text user "-"
			(at 6.6802 0.22225 270)
			(unlocked yes)
			(layer "F.Fab")
			(effects
				(font
					(size 1.905 1.4224)
					(thickness 0.1524)
				)
				(justify left)
			)
		)
		(pad "A" smd rect
			(at -3.400044 0 270)
			(size 2.5146 3.302)
			(layers "F.Cu" "F.Mask" "F.Paste")
			(net "GND")
		)
		(pad "C" smd rect
			(at 3.400044 0 270)
			(size 2.5146 3.302)
			(layers "F.Cu" "F.Mask" "F.Paste")
			(net "P52V_HS2")
		)
	)
	(footprint ""
		(layer "F.Cu")
		(at 166.543736 -63.881 180)
		(property "Reference" "PR7035"
			(at 0 0 180)
			(layer "F.SilkS")
			(hide yes)
			(effects
				(font
					(size 1.27 1.27)
				)
			)
		)
		(property "Value" ""
			(at 0 0 180)
			(layer "F.Fab")
			(effects
				(font
					(size 1.27 1.27)
				)
			)
		)
		(duplicate_pad_numbers_are_jumpers no)
		(fp_line
			(start 0.7874 0.4064)
			(end -0.7874 0.4064)
			(stroke
				(width 0.1524)
				(type default)
			)
			(layer "F.SilkS")
		)
		(fp_line
			(start 0.7874 -0.4064)
			(end 0.7874 0.4064)
			(stroke
				(width 0.1524)
				(type default)
			)
			(layer "F.SilkS")
		)
		(fp_line
			(start -0.7874 0.4064)
			(end -0.7874 -0.4064)
			(stroke
				(width 0.1524)
				(type default)
			)
			(layer "F.SilkS")
		)
		(fp_line
			(start -0.7874 -0.4064)
			(end 0.7874 -0.4064)
			(stroke
				(width 0.1524)
				(type default)
			)
			(layer "F.SilkS")
		)
		(fp_line
			(start 0.67945 0.3048)
			(end 0.120396 0.3048)
			(stroke
				(width 0.1)
				(type default)
			)
			(layer "F.Fab")
		)
		(fp_line
			(start 0.67945 -0.3048)
			(end 0.67945 0.3048)
			(stroke
				(width 0.1)
				(type default)
			)
			(layer "F.Fab")
		)
		(fp_line
			(start 0.12065 -0.2794)
			(end 0.12065 -0.3048)
			(stroke
				(width 0.1)
				(type default)
			)
			(layer "F.Fab")
		)
		(fp_line
			(start 0.12065 -0.3048)
			(end 0.67945 -0.3048)
			(stroke
				(width 0.1)
				(type default)
			)
			(layer "F.Fab")
		)
		(fp_line
			(start 0.120396 0.3048)
			(end 0.120396 0.2794)
			(stroke
				(width 0.1)
				(type default)
			)
			(layer "F.Fab")
		)
		(fp_line
			(start 0.120396 0.2794)
			(end -0.12065 0.2794)
			(stroke
				(width 0.1)
				(type default)
			)
			(layer "F.Fab")
		)
		(fp_line
			(start -0.12065 0.3048)
			(end -0.67945 0.3048)
			(stroke
				(width 0.1)
				(type default)
			)
			(layer "F.Fab")
		)
		(fp_line
			(start -0.12065 0.2794)
			(end -0.12065 0.3048)
			(stroke
				(width 0.1)
				(type default)
			)
			(layer "F.Fab")
		)
		(fp_line
			(start -0.12065 -0.2794)
			(end 0.12065 -0.2794)
			(stroke
				(width 0.1)
				(type default)
			)
			(layer "F.Fab")
		)
		(fp_line
			(start -0.12065 -0.305054)
			(end -0.12065 -0.2794)
			(stroke
				(width 0.1)
				(type default)
			)
			(layer "F.Fab")
		)
		(fp_line
			(start -0.67945 0.3048)
			(end -0.67945 -0.305054)
			(stroke
				(width 0.1)
				(type default)
			)
			(layer "F.Fab")
		)
		(fp_line
			(start -0.67945 -0.305054)
			(end -0.12065 -0.305054)
			(stroke
				(width 0.1)
				(type default)
			)
			(layer "F.Fab")
		)
		(pad "1" smd circle
			(at -0.40005 0 180)
			(size 0 0)
			(layers "F.Cu" "F.Mask" "F.Paste")
			(net "P52V_HS2_ESTART")
		)
		(pad "2" smd circle
			(at 0.40005 0 180)
			(size 0 0)
			(layers "F.Cu" "F.Mask" "F.Paste")
			(net "GND1_FIELD_SIGNAL")
		)
	)
	(footprint ""
		(layer "F.Cu")
		(at 466.639656 -107.502452 90)
		(property "Reference" "R86"
			(at 0 0 90)
			(layer "F.SilkS")
			(hide yes)
			(effects
				(font
					(size 1.27 1.27)
				)
			)
		)
		(property "Value" ""
			(at 0 0 90)
			(layer "F.Fab")
			(effects
				(font
					(size 1.27 1.27)
				)
			)
		)
		(duplicate_pad_numbers_are_jumpers no)
		(fp_line
			(start 0.7874 -0.4064)
			(end 0.7874 0.4064)
			(stroke
				(width 0.1524)
				(type default)
			)
			(layer "F.SilkS")
		)
		(fp_line
			(start -0.7874 -0.4064)
			(end 0.7874 -0.4064)
			(stroke
				(width 0.1524)
				(type default)
			)
			(layer "F.SilkS")
		)
		(fp_line
			(start 0.7874 0.4064)
			(end -0.7874 0.4064)
			(stroke
				(width 0.1524)
				(type default)
			)
			(layer "F.SilkS")
		)
		(fp_line
			(start -0.7874 0.4064)
			(end -0.7874 -0.4064)
			(stroke
				(width 0.1524)
				(type default)
			)
			(layer "F.SilkS")
		)
		(fp_line
			(start -0.12065 -0.305054)
			(end -0.12065 -0.2794)
			(stroke
				(width 0.1)
				(type default)
			)
			(layer "F.Fab")
		)
		(fp_line
			(start -0.67945 -0.305054)
			(end -0.12065 -0.305054)
			(stroke
				(width 0.1)
				(type default)
			)
			(layer "F.Fab")
		)
		(fp_line
			(start 0.67945 -0.3048)
			(end 0.67945 0.3048)
			(stroke
				(width 0.1)
				(type default)
			)
			(layer "F.Fab")
		)
		(fp_line
			(start 0.12065 -0.3048)
			(end 0.67945 -0.3048)
			(stroke
				(width 0.1)
				(type default)
			)
			(layer "F.Fab")
		)
		(fp_line
			(start 0.12065 -0.2794)
			(end 0.12065 -0.3048)
			(stroke
				(width 0.1)
				(type default)
			)
			(layer "F.Fab")
		)
		(fp_line
			(start -0.12065 -0.2794)
			(end 0.12065 -0.2794)
			(stroke
				(width 0.1)
				(type default)
			)
			(layer "F.Fab")
		)
		(fp_line
			(start 0.120396 0.2794)
			(end -0.12065 0.2794)
			(stroke
				(width 0.1)
				(type default)
			)
			(layer "F.Fab")
		)
		(fp_line
			(start -0.12065 0.2794)
			(end -0.12065 0.3048)
			(stroke
				(width 0.1)
				(type default)
			)
			(layer "F.Fab")
		)
		(fp_line
			(start 0.67945 0.3048)
			(end 0.120396 0.3048)
			(stroke
				(width 0.1)
				(type default)
			)
			(layer "F.Fab")
		)
		(fp_line
			(start 0.120396 0.3048)
			(end 0.120396 0.2794)
			(stroke
				(width 0.1)
				(type default)
			)
			(layer "F.Fab")
		)
		(fp_line
			(start -0.12065 0.3048)
			(end -0.67945 0.3048)
			(stroke
				(width 0.1)
				(type default)
			)
			(layer "F.Fab")
		)
		(fp_line
			(start -0.67945 0.3048)
			(end -0.67945 -0.305054)
			(stroke
				(width 0.1)
				(type default)
			)
			(layer "F.Fab")
		)
		(pad "1" smd circle
			(at -0.40005 0 90)
			(size 0 0)
			(layers "F.Cu" "F.Mask" "F.Paste")
			(net "SMB_P52V_SCL")
		)
		(pad "2" smd circle
			(at 0.40005 0 90)
			(size 0 0)
			(layers "F.Cu" "F.Mask" "F.Paste")
			(net "SMB_P52V_R_SCL")
		)
	)
	(footprint ""
		(layer "F.Cu")
		(at 415.73958 -23.09876 180)
		(property "Reference" "R5918"
			(at 0 0 180)
			(layer "F.SilkS")
			(hide yes)
			(effects
				(font
					(size 1.27 1.27)
				)
			)
		)
		(property "Value" ""
			(at 0 0 180)
			(layer "F.Fab")
			(effects
				(font
					(size 1.27 1.27)
				)
			)
		)
		(duplicate_pad_numbers_are_jumpers no)
		(fp_line
			(start 0.7874 0.4064)
			(end -0.7874 0.4064)
			(stroke
				(width 0.1524)
				(type default)
			)
			(layer "F.SilkS")
		)
		(fp_line
			(start 0.7874 -0.4064)
			(end 0.7874 0.4064)
			(stroke
				(width 0.1524)
				(type default)
			)
			(layer "F.SilkS")
		)
		(fp_line
			(start -0.7874 0.4064)
			(end -0.7874 -0.4064)
			(stroke
				(width 0.1524)
				(type default)
			)
			(layer "F.SilkS")
		)
		(fp_line
			(start -0.7874 -0.4064)
			(end 0.7874 -0.4064)
			(stroke
				(width 0.1524)
				(type default)
			)
			(layer "F.SilkS")
		)
		(fp_line
			(start 0.67945 0.3048)
			(end 0.120396 0.3048)
			(stroke
				(width 0.1)
				(type default)
			)
			(layer "F.Fab")
		)
		(fp_line
			(start 0.67945 -0.3048)
			(end 0.67945 0.3048)
			(stroke
				(width 0.1)
				(type default)
			)
			(layer "F.Fab")
		)
		(fp_line
			(start 0.12065 -0.2794)
			(end 0.12065 -0.3048)
			(stroke
				(width 0.1)
				(type default)
			)
			(layer "F.Fab")
		)
		(fp_line
			(start 0.12065 -0.3048)
			(end 0.67945 -0.3048)
			(stroke
				(width 0.1)
				(type default)
			)
			(layer "F.Fab")
		)
		(fp_line
			(start 0.120396 0.3048)
			(end 0.120396 0.2794)
			(stroke
				(width 0.1)
				(type default)
			)
			(layer "F.Fab")
		)
		(fp_line
			(start 0.120396 0.2794)
			(end -0.12065 0.2794)
			(stroke
				(width 0.1)
				(type default)
			)
			(layer "F.Fab")
		)
		(fp_line
			(start -0.12065 0.3048)
			(end -0.67945 0.3048)
			(stroke
				(width 0.1)
				(type default)
			)
			(layer "F.Fab")
		)
		(fp_line
			(start -0.12065 0.2794)
			(end -0.12065 0.3048)
			(stroke
				(width 0.1)
				(type default)
			)
			(layer "F.Fab")
		)
		(fp_line
			(start -0.12065 -0.2794)
			(end 0.12065 -0.2794)
			(stroke
				(width 0.1)
				(type default)
			)
			(layer "F.Fab")
		)
		(fp_line
			(start -0.12065 -0.305054)
			(end -0.12065 -0.2794)
			(stroke
				(width 0.1)
				(type default)
			)
			(layer "F.Fab")
		)
		(fp_line
			(start -0.67945 0.3048)
			(end -0.67945 -0.305054)
			(stroke
				(width 0.1)
				(type default)
			)
			(layer "F.Fab")
		)
		(fp_line
			(start -0.67945 -0.305054)
			(end -0.12065 -0.305054)
			(stroke
				(width 0.1)
				(type default)
			)
			(layer "F.Fab")
		)
		(pad "1" smd rect
			(at -0.40005 0)
			(size 0.4572 0.508)
			(layers "F.Cu" "F.Mask" "F.Paste")
			(net "P12V_FAN_LED")
		)
		(pad "2" smd rect
			(at 0.40005 0)
			(size 0.4572 0.508)
			(layers "F.Cu" "F.Mask" "F.Paste")
			(net "P12V_LED_PD")
		)
	)
	(footprint ""
		(layer "F.Cu")
		(at 42.36339 -99.06)
		(property "Reference" "PC38"
			(at 6.17601 -5.05333 0)
			(unlocked yes)
			(layer "F.SilkS")
			(effects
				(font
					(size 0.7874 0.5842)
					(thickness 0.1524)
				)
				(justify left)
			)
		)
		(property "Value" ""
			(at 0 0 0)
			(layer "F.Fab")
			(effects
				(font
					(size 1.27 1.27)
				)
			)
		)
		(duplicate_pad_numbers_are_jumpers no)
		(fp_line
			(start -9.253728 3.750056)
			(end 9.249918 3.750056)
			(stroke
				(width 0.1524)
				(type default)
			)
			(layer "F.SilkS")
		)
		(fp_line
			(start 0 3.750056)
			(end -9.253728 3.750056)
			(stroke
				(width 0.1524)
				(type default)
			)
			(layer "F.SilkS")
		)
		(fp_circle
			(center 0 3.750056)
			(end 9.249918 3.750056)
			(stroke
				(width 0.1524)
				(type default)
			)
			(fill no)
			(layer "F.SilkS")
		)
		(fp_poly
			(pts
				(arc
					(start 9.249918 3.750056)
					(mid 0 12.999974)
					(end -9.249918 3.750056)
				)
			)
			(stroke
				(width 0)
				(type default)
			)
			(fill yes)
			(layer "F.SilkS")
		)
		(fp_circle
			(center 0 3.750056)
			(end 9.249918 3.750056)
			(stroke
				(width 0.1)
				(type default)
			)
			(fill no)
			(layer "F.Fab")
		)
		(pad "1" thru_hole rect
			(at 0 0)
			(size 1.778 1.778)
			(drill 1.27)
			(layers "*.Cu" "*.Mask")
			(remove_unused_layers no)
			(net "P52V_HS2")
			(clearance 0)
			(padstack
				(mode front_inner_back)
				(layer "Inner"
					(shape circle)
					(size 1.778 1.778)
					(clearance 0)
				)
				(layer "B.Cu"
					(shape rect)
					(size 1.778 1.778)
					(clearance 0)
				)
			)
		)
		(pad "2" thru_hole circle
			(at 0 7.500112)
			(size 1.778 1.778)
			(drill 1.27)
			(layers "*.Cu" "*.Mask")
			(remove_unused_layers no)
			(net "GND")
			(clearance 0)
		)
	)
	(footprint ""
		(layer "F.Cu")
		(at 76.754482 -63.657226)
		(property "Reference" "ME3"
			(at 0 0 0)
			(layer "F.SilkS")
			(hide yes)
			(effects
				(font
					(size 1.27 1.27)
				)
			)
		)
		(property "Value" ""
			(at 0 0 0)
			(layer "F.Fab")
			(effects
				(font
					(size 1.27 1.27)
				)
			)
		)
		(duplicate_pad_numbers_are_jumpers no)
		(fp_line
			(start 0.089408 -2.660396)
			(end 1.561846 -4.072636)
			(stroke
				(width 0.1)
				(type default)
			)
			(layer "F.SilkS")
		)
		(fp_line
			(start 0.089408 -2.660396)
			(end 1.561846 -4.072636)
			(stroke
				(width 0.1)
				(type default)
			)
			(layer "F.SilkS")
		)
		(fp_line
			(start 0.098806 -2.611628)
			(end 1.482344 -3.938778)
			(stroke
				(width 0.1)
				(type default)
			)
			(layer "F.SilkS")
		)
		(fp_line
			(start 0.098806 -2.611628)
			(end 1.482344 -3.938778)
			(stroke
				(width 0.1)
				(type default)
			)
			(layer "F.SilkS")
		)
		(fp_line
			(start 0.108204 -2.563114)
			(end 1.4224 -3.823716)
			(stroke
				(width 0.1)
				(type default)
			)
			(layer "F.SilkS")
		)
		(fp_line
			(start 0.108204 -2.563114)
			(end 1.4224 -3.823716)
			(stroke
				(width 0.1)
				(type default)
			)
			(layer "F.SilkS")
		)
		(fp_line
			(start 0.117602 -2.514346)
			(end 1.38557 -3.730498)
			(stroke
				(width 0.1)
				(type default)
			)
			(layer "F.SilkS")
		)
		(fp_line
			(start 0.117602 -2.514346)
			(end 1.38557 -3.730498)
			(stroke
				(width 0.1)
				(type default)
			)
			(layer "F.SilkS")
		)
		(fp_line
			(start 0.127254 -2.465832)
			(end 1.360932 -3.649218)
			(stroke
				(width 0.1)
				(type default)
			)
			(layer "F.SilkS")
		)
		(fp_line
			(start 0.127254 -2.465832)
			(end 1.360932 -3.649218)
			(stroke
				(width 0.1)
				(type default)
			)
			(layer "F.SilkS")
		)
		(fp_line
			(start 0.139954 -2.420366)
			(end 1.336548 -3.568192)
			(stroke
				(width 0.1)
				(type default)
			)
			(layer "F.SilkS")
		)
		(fp_line
			(start 0.139954 -2.420366)
			(end 1.336548 -3.568192)
			(stroke
				(width 0.1)
				(type default)
			)
			(layer "F.SilkS")
		)
		(fp_line
			(start 0.152908 -2.3749)
			(end 1.31445 -3.489198)
			(stroke
				(width 0.1)
				(type default)
			)
			(layer "F.SilkS")
		)
		(fp_line
			(start 0.152908 -2.3749)
			(end 1.31445 -3.489198)
			(stroke
				(width 0.1)
				(type default)
			)
			(layer "F.SilkS")
		)
		(fp_line
			(start 0.165608 -2.329434)
			(end 1.307592 -3.424936)
			(stroke
				(width 0.1)
				(type default)
			)
			(layer "F.SilkS")
		)
		(fp_line
			(start 0.165608 -2.329434)
			(end 1.307592 -3.424936)
			(stroke
				(width 0.1)
				(type default)
			)
			(layer "F.SilkS")
		)
		(fp_line
			(start 0.178562 -2.284222)
			(end 1.300988 -3.360674)
			(stroke
				(width 0.1)
				(type default)
			)
			(layer "F.SilkS")
		)
		(fp_line
			(start 0.178562 -2.284222)
			(end 1.300988 -3.360674)
			(stroke
				(width 0.1)
				(type default)
			)
			(layer "F.SilkS")
		)
		(fp_line
			(start 0.191516 -2.238756)
			(end 1.29413 -3.296412)
			(stroke
				(width 0.1)
				(type default)
			)
			(layer "F.SilkS")
		)
		(fp_line
			(start 0.191516 -2.238756)
			(end 1.29413 -3.296412)
			(stroke
				(width 0.1)
				(type default)
			)
			(layer "F.SilkS")
		)
		(fp_line
			(start 0.205994 -2.195068)
			(end 1.287526 -3.232404)
			(stroke
				(width 0.1)
				(type default)
			)
			(layer "F.SilkS")
		)
		(fp_line
			(start 0.205994 -2.195068)
			(end 1.287526 -3.232404)
			(stroke
				(width 0.1)
				(type default)
			)
			(layer "F.SilkS")
		)
		(fp_line
			(start 0.222504 -2.153158)
			(end 1.2827 -3.170174)
			(stroke
				(width 0.1)
				(type default)
			)
			(layer "F.SilkS")
		)
		(fp_line
			(start 0.222504 -2.153158)
			(end 1.2827 -3.170174)
			(stroke
				(width 0.1)
				(type default)
			)
			(layer "F.SilkS")
		)
		(fp_line
			(start 0.239268 -2.111502)
			(end 1.287018 -3.11658)
			(stroke
				(width 0.1)
				(type default)
			)
			(layer "F.SilkS")
		)
		(fp_line
			(start 0.239268 -2.111502)
			(end 1.287018 -3.11658)
			(stroke
				(width 0.1)
				(type default)
			)
			(layer "F.SilkS")
		)
		(fp_line
			(start 0.256032 -2.069846)
			(end 1.291082 -3.062732)
			(stroke
				(width 0.1)
				(type default)
			)
			(layer "F.SilkS")
		)
		(fp_line
			(start 0.256032 -2.069846)
			(end 1.291082 -3.062732)
			(stroke
				(width 0.1)
				(type default)
			)
			(layer "F.SilkS")
		)
		(fp_line
			(start 0.272796 -2.02819)
			(end 1.295146 -3.009138)
			(stroke
				(width 0.1)
				(type default)
			)
			(layer "F.SilkS")
		)
		(fp_line
			(start 0.272796 -2.02819)
			(end 1.295146 -3.009138)
			(stroke
				(width 0.1)
				(type default)
			)
			(layer "F.SilkS")
		)
		(fp_line
			(start 0.289306 -1.986534)
			(end 1.299464 -2.955544)
			(stroke
				(width 0.1)
				(type default)
			)
			(layer "F.SilkS")
		)
		(fp_line
			(start 0.289306 -1.986534)
			(end 1.299464 -2.955544)
			(stroke
				(width 0.1)
				(type default)
			)
			(layer "F.SilkS")
		)
		(fp_line
			(start 0.307086 -1.94564)
			(end 1.303528 -2.901696)
			(stroke
				(width 0.1)
				(type default)
			)
			(layer "F.SilkS")
		)
		(fp_line
			(start 0.307086 -1.94564)
			(end 1.303528 -2.901696)
			(stroke
				(width 0.1)
				(type default)
			)
			(layer "F.SilkS")
		)
		(fp_line
			(start 0.327914 -1.908048)
			(end 1.31318 -2.853182)
			(stroke
				(width 0.1)
				(type default)
			)
			(layer "F.SilkS")
		)
		(fp_line
			(start 0.327914 -1.908048)
			(end 1.31318 -2.853182)
			(stroke
				(width 0.1)
				(type default)
			)
			(layer "F.SilkS")
		)
		(fp_line
			(start 0.348996 -1.870456)
			(end 1.325118 -2.8067)
			(stroke
				(width 0.1)
				(type default)
			)
			(layer "F.SilkS")
		)
		(fp_line
			(start 0.348996 -1.870456)
			(end 1.325118 -2.8067)
			(stroke
				(width 0.1)
				(type default)
			)
			(layer "F.SilkS")
		)
		(fp_line
			(start 0.369824 -1.832864)
			(end 1.336802 -2.760472)
			(stroke
				(width 0.1)
				(type default)
			)
			(layer "F.SilkS")
		)
		(fp_line
			(start 0.369824 -1.832864)
			(end 1.336802 -2.760472)
			(stroke
				(width 0.1)
				(type default)
			)
			(layer "F.SilkS")
		)
		(fp_line
			(start 0.390906 -1.795272)
			(end 1.348486 -2.714244)
			(stroke
				(width 0.1)
				(type default)
			)
			(layer "F.SilkS")
		)
		(fp_line
			(start 0.390906 -1.795272)
			(end 1.348486 -2.714244)
			(stroke
				(width 0.1)
				(type default)
			)
			(layer "F.SilkS")
		)
		(fp_line
			(start 0.411988 -1.75768)
			(end 1.360424 -2.667508)
			(stroke
				(width 0.1)
				(type default)
			)
			(layer "F.SilkS")
		)
		(fp_line
			(start 0.411988 -1.75768)
			(end 1.360424 -2.667508)
			(stroke
				(width 0.1)
				(type default)
			)
			(layer "F.SilkS")
		)
		(fp_line
			(start 0.432816 -1.720088)
			(end 1.372362 -2.62128)
			(stroke
				(width 0.1)
				(type default)
			)
			(layer "F.SilkS")
		)
		(fp_line
			(start 0.432816 -1.720088)
			(end 1.372362 -2.62128)
			(stroke
				(width 0.1)
				(type default)
			)
			(layer "F.SilkS")
		)
		(fp_line
			(start 0.456184 -1.684782)
			(end 1.387856 -2.578608)
			(stroke
				(width 0.1)
				(type default)
			)
			(layer "F.SilkS")
		)
		(fp_line
			(start 0.456184 -1.684782)
			(end 1.387856 -2.578608)
			(stroke
				(width 0.1)
				(type default)
			)
			(layer "F.SilkS")
		)
		(fp_line
			(start 0.481838 -1.651762)
			(end 1.40589 -2.538222)
			(stroke
				(width 0.1)
				(type default)
			)
			(layer "F.SilkS")
		)
		(fp_line
			(start 0.481838 -1.651762)
			(end 1.40589 -2.538222)
			(stroke
				(width 0.1)
				(type default)
			)
			(layer "F.SilkS")
		)
		(fp_line
			(start 0.507746 -1.618742)
			(end 1.423924 -2.497836)
			(stroke
				(width 0.1)
				(type default)
			)
			(layer "F.SilkS")
		)
		(fp_line
			(start 0.507746 -1.618742)
			(end 1.423924 -2.497836)
			(stroke
				(width 0.1)
				(type default)
			)
			(layer "F.SilkS")
		)
		(fp_line
			(start 0.5334 -1.585722)
			(end 1.441958 -2.457196)
			(stroke
				(width 0.1)
				(type default)
			)
			(layer "F.SilkS")
		)
		(fp_line
			(start 0.5334 -1.585722)
			(end 1.441958 -2.457196)
			(stroke
				(width 0.1)
				(type default)
			)
			(layer "F.SilkS")
		)
		(fp_line
			(start 0.559054 -1.552702)
			(end 1.459992 -2.41681)
			(stroke
				(width 0.1)
				(type default)
			)
			(layer "F.SilkS")
		)
		(fp_line
			(start 0.559054 -1.552702)
			(end 1.459992 -2.41681)
			(stroke
				(width 0.1)
				(type default)
			)
			(layer "F.SilkS")
		)
		(fp_line
			(start 0.584962 -1.519682)
			(end 1.477772 -2.376424)
			(stroke
				(width 0.1)
				(type default)
			)
			(layer "F.SilkS")
		)
		(fp_line
			(start 0.584962 -1.519682)
			(end 1.477772 -2.376424)
			(stroke
				(width 0.1)
				(type default)
			)
			(layer "F.SilkS")
		)
		(fp_line
			(start 0.610616 -1.486916)
			(end 1.496568 -2.336546)
			(stroke
				(width 0.1)
				(type default)
			)
			(layer "F.SilkS")
		)
		(fp_line
			(start 0.610616 -1.486916)
			(end 1.496568 -2.336546)
			(stroke
				(width 0.1)
				(type default)
			)
			(layer "F.SilkS")
		)
		(fp_line
			(start 0.637794 -1.455166)
			(end 1.52019 -2.301494)
			(stroke
				(width 0.1)
				(type default)
			)
			(layer "F.SilkS")
		)
		(fp_line
			(start 0.637794 -1.455166)
			(end 1.52019 -2.301494)
			(stroke
				(width 0.1)
				(type default)
			)
			(layer "F.SilkS")
		)
		(fp_line
			(start 0.668274 -1.426464)
			(end 1.543558 -2.266188)
			(stroke
				(width 0.1)
				(type default)
			)
			(layer "F.SilkS")
		)
		(fp_line
			(start 0.668274 -1.426464)
			(end 1.543558 -2.266188)
			(stroke
				(width 0.1)
				(type default)
			)
			(layer "F.SilkS")
		)
		(fp_line
			(start 0.6985 -1.397762)
			(end 1.56718 -2.231136)
			(stroke
				(width 0.1)
				(type default)
			)
			(layer "F.SilkS")
		)
		(fp_line
			(start 0.6985 -1.397762)
			(end 1.56718 -2.231136)
			(stroke
				(width 0.1)
				(type default)
			)
			(layer "F.SilkS")
		)
		(fp_line
			(start 0.728726 -1.36906)
			(end 1.590802 -2.196084)
			(stroke
				(width 0.1)
				(type default)
			)
			(layer "F.SilkS")
		)
		(fp_line
			(start 0.728726 -1.36906)
			(end 1.590802 -2.196084)
			(stroke
				(width 0.1)
				(type default)
			)
			(layer "F.SilkS")
		)
		(fp_line
			(start 0.758952 -1.340358)
			(end 1.61417 -2.160778)
			(stroke
				(width 0.1)
				(type default)
			)
			(layer "F.SilkS")
		)
		(fp_line
			(start 0.758952 -1.340358)
			(end 1.61417 -2.160778)
			(stroke
				(width 0.1)
				(type default)
			)
			(layer "F.SilkS")
		)
		(fp_line
			(start 0.789178 -1.31191)
			(end 1.637792 -2.125726)
			(stroke
				(width 0.1)
				(type default)
			)
			(layer "F.SilkS")
		)
		(fp_line
			(start 0.789178 -1.31191)
			(end 1.637792 -2.125726)
			(stroke
				(width 0.1)
				(type default)
			)
			(layer "F.SilkS")
		)
		(fp_line
			(start 0.819404 -1.282954)
			(end 1.663954 -2.09296)
			(stroke
				(width 0.1)
				(type default)
			)
			(layer "F.SilkS")
		)
		(fp_line
			(start 0.819404 -1.282954)
			(end 1.663954 -2.09296)
			(stroke
				(width 0.1)
				(type default)
			)
			(layer "F.SilkS")
		)
		(fp_line
			(start 0.851408 -1.25603)
			(end 1.69291 -2.063242)
			(stroke
				(width 0.1)
				(type default)
			)
			(layer "F.SilkS")
		)
		(fp_line
			(start 0.851408 -1.25603)
			(end 1.69291 -2.063242)
			(stroke
				(width 0.1)
				(type default)
			)
			(layer "F.SilkS")
		)
		(fp_line
			(start 0.885698 -1.230884)
			(end 1.72212 -2.03327)
			(stroke
				(width 0.1)
				(type default)
			)
			(layer "F.SilkS")
		)
		(fp_line
			(start 0.885698 -1.230884)
			(end 1.72212 -2.03327)
			(stroke
				(width 0.1)
				(type default)
			)
			(layer "F.SilkS")
		)
		(fp_line
			(start 0.919734 -1.206246)
			(end 1.751076 -2.003552)
			(stroke
				(width 0.1)
				(type default)
			)
			(layer "F.SilkS")
		)
		(fp_line
			(start 0.919734 -1.206246)
			(end 1.751076 -2.003552)
			(stroke
				(width 0.1)
				(type default)
			)
			(layer "F.SilkS")
		)
		(fp_line
			(start 0.954024 -1.1811)
			(end 1.780032 -1.973834)
			(stroke
				(width 0.1)
				(type default)
			)
			(layer "F.SilkS")
		)
		(fp_line
			(start 0.954024 -1.1811)
			(end 1.780032 -1.973834)
			(stroke
				(width 0.1)
				(type default)
			)
			(layer "F.SilkS")
		)
		(fp_line
			(start 0.988314 -1.156462)
			(end 1.809242 -1.943862)
			(stroke
				(width 0.1)
				(type default)
			)
			(layer "F.SilkS")
		)
		(fp_line
			(start 0.988314 -1.156462)
			(end 1.809242 -1.943862)
			(stroke
				(width 0.1)
				(type default)
			)
			(layer "F.SilkS")
		)
		(fp_line
			(start 1.02235 -1.13157)
			(end 1.838452 -1.914144)
			(stroke
				(width 0.1)
				(type default)
			)
			(layer "F.SilkS")
		)
		(fp_line
			(start 1.02235 -1.13157)
			(end 1.838452 -1.914144)
			(stroke
				(width 0.1)
				(type default)
			)
			(layer "F.SilkS")
		)
		(fp_line
			(start 1.05664 -1.106678)
			(end 1.872488 -1.889252)
			(stroke
				(width 0.1)
				(type default)
			)
			(layer "F.SilkS")
		)
		(fp_line
			(start 1.05664 -1.106678)
			(end 1.872488 -1.889252)
			(stroke
				(width 0.1)
				(type default)
			)
			(layer "F.SilkS")
		)
		(fp_line
			(start 1.09347 -1.084326)
			(end 1.907794 -1.865376)
			(stroke
				(width 0.1)
				(type default)
			)
			(layer "F.SilkS")
		)
		(fp_line
			(start 1.09347 -1.084326)
			(end 1.907794 -1.865376)
			(stroke
				(width 0.1)
				(type default)
			)
			(layer "F.SilkS")
		)
		(fp_line
			(start 1.131824 -1.063498)
			(end 1.9431 -1.8415)
			(stroke
				(width 0.1)
				(type default)
			)
			(layer "F.SilkS")
		)
		(fp_line
			(start 1.131824 -1.063498)
			(end 1.9431 -1.8415)
			(stroke
				(width 0.1)
				(type default)
			)
			(layer "F.SilkS")
		)
		(fp_line
			(start 1.133856 -5.220462)
			(end 0.47117 -4.5847)
			(stroke
				(width 0.1)
				(type default)
			)
			(layer "F.SilkS")
		)
		(fp_line
			(start 1.133856 -5.220462)
			(end 0.47117 -4.5847)
			(stroke
				(width 0.1)
				(type default)
			)
			(layer "F.SilkS")
		)
		(fp_line
			(start 1.170178 -1.042416)
			(end 1.978406 -1.817624)
			(stroke
				(width 0.1)
				(type default)
			)
			(layer "F.SilkS")
		)
		(fp_line
			(start 1.170178 -1.042416)
			(end 1.978406 -1.817624)
			(stroke
				(width 0.1)
				(type default)
			)
			(layer "F.SilkS")
		)
		(fp_line
			(start 1.208532 -1.021334)
			(end 2.013458 -1.793748)
			(stroke
				(width 0.1)
				(type default)
			)
			(layer "F.SilkS")
		)
		(fp_line
			(start 1.208532 -1.021334)
			(end 2.013458 -1.793748)
			(stroke
				(width 0.1)
				(type default)
			)
			(layer "F.SilkS")
		)
		(fp_line
			(start 1.246886 -1.000506)
			(end 2.048764 -1.769872)
			(stroke
				(width 0.1)
				(type default)
			)
			(layer "F.SilkS")
		)
		(fp_line
			(start 1.246886 -1.000506)
			(end 2.048764 -1.769872)
			(stroke
				(width 0.1)
				(type default)
			)
			(layer "F.SilkS")
		)
		(fp_line
			(start 1.28524 -0.979424)
			(end 2.087626 -1.749298)
			(stroke
				(width 0.1)
				(type default)
			)
			(layer "F.SilkS")
		)
		(fp_line
			(start 1.28524 -0.979424)
			(end 2.087626 -1.749298)
			(stroke
				(width 0.1)
				(type default)
			)
			(layer "F.SilkS")
		)
		(fp_line
			(start 1.293368 -5.315966)
			(end 0.37465 -4.434332)
			(stroke
				(width 0.1)
				(type default)
			)
			(layer "F.SilkS")
		)
		(fp_line
			(start 1.293368 -5.315966)
			(end 0.37465 -4.434332)
			(stroke
				(width 0.1)
				(type default)
			)
			(layer "F.SilkS")
		)
		(fp_line
			(start 1.323594 -0.958596)
			(end 2.130552 -1.732788)
			(stroke
				(width 0.1)
				(type default)
			)
			(layer "F.SilkS")
		)
		(fp_line
			(start 1.323594 -0.958596)
			(end 2.130552 -1.732788)
			(stroke
				(width 0.1)
				(type default)
			)
			(layer "F.SilkS")
		)
		(fp_line
			(start 1.366266 -0.941832)
			(end 2.173478 -1.716024)
			(stroke
				(width 0.1)
				(type default)
			)
			(layer "F.SilkS")
		)
		(fp_line
			(start 1.366266 -0.941832)
			(end 2.173478 -1.716024)
			(stroke
				(width 0.1)
				(type default)
			)
			(layer "F.SilkS")
		)
		(fp_line
			(start 1.408684 -0.924814)
			(end 2.21615 -1.699514)
			(stroke
				(width 0.1)
				(type default)
			)
			(layer "F.SilkS")
		)
		(fp_line
			(start 1.408684 -0.924814)
			(end 2.21615 -1.699514)
			(stroke
				(width 0.1)
				(type default)
			)
			(layer "F.SilkS")
		)
		(fp_line
			(start 1.41224 -5.3721)
			(end 0.302768 -4.307586)
			(stroke
				(width 0.1)
				(type default)
			)
			(layer "F.SilkS")
		)
		(fp_line
			(start 1.41224 -5.3721)
			(end 0.302768 -4.307586)
			(stroke
				(width 0.1)
				(type default)
			)
			(layer "F.SilkS")
		)
		(fp_line
			(start 1.451356 -0.90805)
			(end 2.259076 -1.68275)
			(stroke
				(width 0.1)
				(type default)
			)
			(layer "F.SilkS")
		)
		(fp_line
			(start 1.451356 -0.90805)
			(end 2.259076 -1.68275)
			(stroke
				(width 0.1)
				(type default)
			)
			(layer "F.SilkS")
		)
		(fp_line
			(start 1.493774 -0.891032)
			(end 2.301748 -1.66624)
			(stroke
				(width 0.1)
				(type default)
			)
			(layer "F.SilkS")
		)
		(fp_line
			(start 1.493774 -0.891032)
			(end 2.301748 -1.66624)
			(stroke
				(width 0.1)
				(type default)
			)
			(layer "F.SilkS")
		)
		(fp_line
			(start 1.52781 -5.425186)
			(end 0.256794 -4.205732)
			(stroke
				(width 0.1)
				(type default)
			)
			(layer "F.SilkS")
		)
		(fp_line
			(start 1.52781 -5.425186)
			(end 0.256794 -4.205732)
			(stroke
				(width 0.1)
				(type default)
			)
			(layer "F.SilkS")
		)
		(fp_line
			(start 1.536446 -0.874268)
			(end 2.351024 -1.655826)
			(stroke
				(width 0.1)
				(type default)
			)
			(layer "F.SilkS")
		)
		(fp_line
			(start 1.536446 -0.874268)
			(end 2.351024 -1.655826)
			(stroke
				(width 0.1)
				(type default)
			)
			(layer "F.SilkS")
		)
		(fp_line
			(start 1.578864 -0.857504)
			(end 2.404364 -1.649222)
			(stroke
				(width 0.1)
				(type default)
			)
			(layer "F.SilkS")
		)
		(fp_line
			(start 1.578864 -0.857504)
			(end 2.404364 -1.649222)
			(stroke
				(width 0.1)
				(type default)
			)
			(layer "F.SilkS")
		)
		(fp_line
			(start 1.62306 -5.458714)
			(end 0.211328 -4.10464)
			(stroke
				(width 0.1)
				(type default)
			)
			(layer "F.SilkS")
		)
		(fp_line
			(start 1.62306 -5.458714)
			(end 0.211328 -4.10464)
			(stroke
				(width 0.1)
				(type default)
			)
			(layer "F.SilkS")
		)
		(fp_line
			(start 1.623314 -0.842264)
			(end 2.457704 -1.642618)
			(stroke
				(width 0.1)
				(type default)
			)
			(layer "F.SilkS")
		)
		(fp_line
			(start 1.623314 -0.842264)
			(end 2.457704 -1.642618)
			(stroke
				(width 0.1)
				(type default)
			)
			(layer "F.SilkS")
		)
		(fp_line
			(start 1.67005 -0.829564)
			(end 2.511044 -1.636014)
			(stroke
				(width 0.1)
				(type default)
			)
			(layer "F.SilkS")
		)
		(fp_line
			(start 1.67005 -0.829564)
			(end 2.511044 -1.636014)
			(stroke
				(width 0.1)
				(type default)
			)
			(layer "F.SilkS")
		)
		(fp_line
			(start 1.716786 -0.816356)
			(end 2.56413 -1.62941)
			(stroke
				(width 0.1)
				(type default)
			)
			(layer "F.SilkS")
		)
		(fp_line
			(start 1.716786 -0.816356)
			(end 2.56413 -1.62941)
			(stroke
				(width 0.1)
				(type default)
			)
			(layer "F.SilkS")
		)
		(fp_line
			(start 1.717802 -5.492242)
			(end 0.181356 -4.018026)
			(stroke
				(width 0.1)
				(type default)
			)
			(layer "F.SilkS")
		)
		(fp_line
			(start 1.717802 -5.492242)
			(end 0.181356 -4.018026)
			(stroke
				(width 0.1)
				(type default)
			)
			(layer "F.SilkS")
		)
		(fp_line
			(start 1.763522 -0.803656)
			(end 2.624582 -1.629664)
			(stroke
				(width 0.1)
				(type default)
			)
			(layer "F.SilkS")
		)
		(fp_line
			(start 1.763522 -0.803656)
			(end 2.624582 -1.629664)
			(stroke
				(width 0.1)
				(type default)
			)
			(layer "F.SilkS")
		)
		(fp_line
			(start 1.805686 -5.518658)
			(end 0.1524 -3.932682)
			(stroke
				(width 0.1)
				(type default)
			)
			(layer "F.SilkS")
		)
		(fp_line
			(start 1.805686 -5.518658)
			(end 0.1524 -3.932682)
			(stroke
				(width 0.1)
				(type default)
			)
			(layer "F.SilkS")
		)
		(fp_line
			(start 1.810512 -0.790956)
			(end 2.692654 -1.637284)
			(stroke
				(width 0.1)
				(type default)
			)
			(layer "F.SilkS")
		)
		(fp_line
			(start 1.810512 -0.790956)
			(end 2.692654 -1.637284)
			(stroke
				(width 0.1)
				(type default)
			)
			(layer "F.SilkS")
		)
		(fp_line
			(start 1.856994 -0.777748)
			(end 2.760726 -1.64465)
			(stroke
				(width 0.1)
				(type default)
			)
			(layer "F.SilkS")
		)
		(fp_line
			(start 1.856994 -0.777748)
			(end 2.760726 -1.64465)
			(stroke
				(width 0.1)
				(type default)
			)
			(layer "F.SilkS")
		)
		(fp_line
			(start 1.886458 -5.538216)
			(end 0.128016 -3.851402)
			(stroke
				(width 0.1)
				(type default)
			)
			(layer "F.SilkS")
		)
		(fp_line
			(start 1.886458 -5.538216)
			(end 0.128016 -3.851402)
			(stroke
				(width 0.1)
				(type default)
			)
			(layer "F.SilkS")
		)
		(fp_line
			(start 1.90373 -0.765048)
			(end 2.828544 -1.65227)
			(stroke
				(width 0.1)
				(type default)
			)
			(layer "F.SilkS")
		)
		(fp_line
			(start 1.90373 -0.765048)
			(end 2.828544 -1.65227)
			(stroke
				(width 0.1)
				(type default)
			)
			(layer "F.SilkS")
		)
		(fp_line
			(start 1.954276 -0.75565)
			(end 2.906014 -1.66878)
			(stroke
				(width 0.1)
				(type default)
			)
			(layer "F.SilkS")
		)
		(fp_line
			(start 1.954276 -0.75565)
			(end 2.906014 -1.66878)
			(stroke
				(width 0.1)
				(type default)
			)
			(layer "F.SilkS")
		)
		(fp_line
			(start 1.966722 -5.557774)
			(end 0.110236 -3.776726)
			(stroke
				(width 0.1)
				(type default)
			)
			(layer "F.SilkS")
		)
		(fp_line
			(start 1.966722 -5.557774)
			(end 0.110236 -3.776726)
			(stroke
				(width 0.1)
				(type default)
			)
			(layer "F.SilkS")
		)
		(fp_line
			(start 2.00533 -0.74676)
			(end 3.000248 -1.701546)
			(stroke
				(width 0.1)
				(type default)
			)
			(layer "F.SilkS")
		)
		(fp_line
			(start 2.00533 -0.74676)
			(end 3.000248 -1.701546)
			(stroke
				(width 0.1)
				(type default)
			)
			(layer "F.SilkS")
		)
		(fp_line
			(start 2.04597 -5.576062)
			(end 0.092456 -3.70205)
			(stroke
				(width 0.1)
				(type default)
			)
			(layer "F.SilkS")
		)
		(fp_line
			(start 2.04597 -5.576062)
			(end 0.092456 -3.70205)
			(stroke
				(width 0.1)
				(type default)
			)
			(layer "F.SilkS")
		)
		(fp_line
			(start 2.05613 -0.73787)
			(end 3.094228 -1.733804)
			(stroke
				(width 0.1)
				(type default)
			)
			(layer "F.SilkS")
		)
		(fp_line
			(start 2.05613 -0.73787)
			(end 3.094228 -1.733804)
			(stroke
				(width 0.1)
				(type default)
			)
			(layer "F.SilkS")
		)
		(fp_line
			(start 2.10693 -0.72898)
			(end 3.238246 -1.814322)
			(stroke
				(width 0.1)
				(type default)
			)
			(layer "F.SilkS")
		)
		(fp_line
			(start 2.10693 -0.72898)
			(end 3.238246 -1.814322)
			(stroke
				(width 0.1)
				(type default)
			)
			(layer "F.SilkS")
		)
		(fp_line
			(start 2.116328 -5.585968)
			(end 0.07874 -3.631184)
			(stroke
				(width 0.1)
				(type default)
			)
			(layer "F.SilkS")
		)
		(fp_line
			(start 2.116328 -5.585968)
			(end 0.07874 -3.631184)
			(stroke
				(width 0.1)
				(type default)
			)
			(layer "F.SilkS")
		)
		(fp_line
			(start 2.18694 -5.595874)
			(end 0.069342 -3.564382)
			(stroke
				(width 0.1)
				(type default)
			)
			(layer "F.SilkS")
		)
		(fp_line
			(start 2.18694 -5.595874)
			(end 0.069342 -3.564382)
			(stroke
				(width 0.1)
				(type default)
			)
			(layer "F.SilkS")
		)
		(fp_line
			(start 2.208784 -0.710946)
			(end 5.142484 -3.52552)
			(stroke
				(width 0.1)
				(type default)
			)
			(layer "F.SilkS")
		)
		(fp_line
			(start 2.208784 -0.710946)
			(end 5.142484 -3.52552)
			(stroke
				(width 0.1)
				(type default)
			)
			(layer "F.SilkS")
		)
		(fp_line
			(start 2.257552 -5.60578)
			(end 0.059944 -3.49758)
			(stroke
				(width 0.1)
				(type default)
			)
			(layer "F.SilkS")
		)
		(fp_line
			(start 2.257552 -5.60578)
			(end 0.059944 -3.49758)
			(stroke
				(width 0.1)
				(type default)
			)
			(layer "F.SilkS")
		)
		(fp_line
			(start 2.2606 -0.703326)
			(end 5.147564 -3.472942)
			(stroke
				(width 0.1)
				(type default)
			)
			(layer "F.SilkS")
		)
		(fp_line
			(start 2.2606 -0.703326)
			(end 5.147564 -3.472942)
			(stroke
				(width 0.1)
				(type default)
			)
			(layer "F.SilkS")
		)
		(fp_line
			(start 2.315464 -0.698246)
			(end 5.152898 -3.42011)
			(stroke
				(width 0.1)
				(type default)
			)
			(layer "F.SilkS")
		)
		(fp_line
			(start 2.315464 -0.698246)
			(end 5.152898 -3.42011)
			(stroke
				(width 0.1)
				(type default)
			)
			(layer "F.SilkS")
		)
		(fp_line
			(start 2.32791 -5.615686)
			(end 0.051308 -3.431794)
			(stroke
				(width 0.1)
				(type default)
			)
			(layer "F.SilkS")
		)
		(fp_line
			(start 2.32791 -5.615686)
			(end 0.051308 -3.431794)
			(stroke
				(width 0.1)
				(type default)
			)
			(layer "F.SilkS")
		)
		(fp_line
			(start 2.370328 -0.693166)
			(end 5.156708 -3.366262)
			(stroke
				(width 0.1)
				(type default)
			)
			(layer "F.SilkS")
		)
		(fp_line
			(start 2.370328 -0.693166)
			(end 5.156708 -3.366262)
			(stroke
				(width 0.1)
				(type default)
			)
			(layer "F.SilkS")
		)
		(fp_line
			(start 2.390902 -5.61848)
			(end 0.048514 -3.371342)
			(stroke
				(width 0.1)
				(type default)
			)
			(layer "F.SilkS")
		)
		(fp_line
			(start 2.390902 -5.61848)
			(end 0.048514 -3.371342)
			(stroke
				(width 0.1)
				(type default)
			)
			(layer "F.SilkS")
		)
		(fp_line
			(start 2.424938 -0.687832)
			(end 5.158994 -3.310382)
			(stroke
				(width 0.1)
				(type default)
			)
			(layer "F.SilkS")
		)
		(fp_line
			(start 2.424938 -0.687832)
			(end 5.158994 -3.310382)
			(stroke
				(width 0.1)
				(type default)
			)
			(layer "F.SilkS")
		)
		(fp_line
			(start 2.454148 -5.621274)
			(end 0.04572 -3.31089)
			(stroke
				(width 0.1)
				(type default)
			)
			(layer "F.SilkS")
		)
		(fp_line
			(start 2.454148 -5.621274)
			(end 0.04572 -3.31089)
			(stroke
				(width 0.1)
				(type default)
			)
			(layer "F.SilkS")
		)
		(fp_line
			(start 2.479802 -0.682752)
			(end 5.16001 -3.25374)
			(stroke
				(width 0.1)
				(type default)
			)
			(layer "F.SilkS")
		)
		(fp_line
			(start 2.479802 -0.682752)
			(end 5.16001 -3.25374)
			(stroke
				(width 0.1)
				(type default)
			)
			(layer "F.SilkS")
		)
		(fp_line
			(start 2.517394 -5.624322)
			(end 0.042926 -3.250438)
			(stroke
				(width 0.1)
				(type default)
			)
			(layer "F.SilkS")
		)
		(fp_line
			(start 2.517394 -5.624322)
			(end 0.042926 -3.250438)
			(stroke
				(width 0.1)
				(type default)
			)
			(layer "F.SilkS")
		)
		(fp_line
			(start 2.534666 -0.677672)
			(end 5.15747 -3.193796)
			(stroke
				(width 0.1)
				(type default)
			)
			(layer "F.SilkS")
		)
		(fp_line
			(start 2.534666 -0.677672)
			(end 5.15747 -3.193796)
			(stroke
				(width 0.1)
				(type default)
			)
			(layer "F.SilkS")
		)
		(fp_line
			(start 2.580386 -5.626862)
			(end 0.041656 -3.19151)
			(stroke
				(width 0.1)
				(type default)
			)
			(layer "F.SilkS")
		)
		(fp_line
			(start 2.580386 -5.626862)
			(end 0.041656 -3.19151)
			(stroke
				(width 0.1)
				(type default)
			)
			(layer "F.SilkS")
		)
		(fp_line
			(start 2.589276 -0.672338)
			(end 5.15493 -3.133598)
			(stroke
				(width 0.1)
				(type default)
			)
			(layer "F.SilkS")
		)
		(fp_line
			(start 2.589276 -0.672338)
			(end 5.15493 -3.133598)
			(stroke
				(width 0.1)
				(type default)
			)
			(layer "F.SilkS")
		)
		(fp_line
			(start 2.64287 -5.629148)
			(end 0.042672 -3.135122)
			(stroke
				(width 0.1)
				(type default)
			)
			(layer "F.SilkS")
		)
		(fp_line
			(start 2.64287 -5.629148)
			(end 0.042672 -3.135122)
			(stroke
				(width 0.1)
				(type default)
			)
			(layer "F.SilkS")
		)
		(fp_line
			(start 2.646426 -0.669544)
			(end 5.15239 -3.073146)
			(stroke
				(width 0.1)
				(type default)
			)
			(layer "F.SilkS")
		)
		(fp_line
			(start 2.646426 -0.669544)
			(end 5.15239 -3.073146)
			(stroke
				(width 0.1)
				(type default)
			)
			(layer "F.SilkS")
		)
		(fp_line
			(start 2.700528 -5.626862)
			(end 0.04445 -3.078734)
			(stroke
				(width 0.1)
				(type default)
			)
			(layer "F.SilkS")
		)
		(fp_line
			(start 2.700528 -5.626862)
			(end 0.04445 -3.078734)
			(stroke
				(width 0.1)
				(type default)
			)
			(layer "F.SilkS")
		)
		(fp_line
			(start 2.704846 -0.66802)
			(end 5.14985 -3.013202)
			(stroke
				(width 0.1)
				(type default)
			)
			(layer "F.SilkS")
		)
		(fp_line
			(start 2.704846 -0.66802)
			(end 5.14985 -3.013202)
			(stroke
				(width 0.1)
				(type default)
			)
			(layer "F.SilkS")
		)
		(fp_line
			(start 2.75844 -5.62483)
			(end 0.048006 -3.024632)
			(stroke
				(width 0.1)
				(type default)
			)
			(layer "F.SilkS")
		)
		(fp_line
			(start 2.75844 -5.62483)
			(end 0.048006 -3.024632)
			(stroke
				(width 0.1)
				(type default)
			)
			(layer "F.SilkS")
		)
		(fp_line
			(start 2.76352 -0.666242)
			(end 5.14731 -2.953258)
			(stroke
				(width 0.1)
				(type default)
			)
			(layer "F.SilkS")
		)
		(fp_line
			(start 2.76352 -0.666242)
			(end 5.14731 -2.953258)
			(stroke
				(width 0.1)
				(type default)
			)
			(layer "F.SilkS")
		)
		(fp_line
			(start 2.816098 -5.622544)
			(end 0.051562 -2.970276)
			(stroke
				(width 0.1)
				(type default)
			)
			(layer "F.SilkS")
		)
		(fp_line
			(start 2.816098 -5.622544)
			(end 0.051562 -2.970276)
			(stroke
				(width 0.1)
				(type default)
			)
			(layer "F.SilkS")
		)
		(fp_line
			(start 2.82194 -0.664718)
			(end 5.145024 -2.89306)
			(stroke
				(width 0.1)
				(type default)
			)
			(layer "F.SilkS")
		)
		(fp_line
			(start 2.82194 -0.664718)
			(end 5.145024 -2.89306)
			(stroke
				(width 0.1)
				(type default)
			)
			(layer "F.SilkS")
		)
		(fp_line
			(start 2.87401 -5.620258)
			(end 0.054864 -2.91592)
			(stroke
				(width 0.1)
				(type default)
			)
			(layer "F.SilkS")
		)
		(fp_line
			(start 2.87401 -5.620258)
			(end 0.054864 -2.91592)
			(stroke
				(width 0.1)
				(type default)
			)
			(layer "F.SilkS")
		)
		(fp_line
			(start 2.88036 -0.662686)
			(end 5.13588 -2.826512)
			(stroke
				(width 0.1)
				(type default)
			)
			(layer "F.SilkS")
		)
		(fp_line
			(start 2.88036 -0.662686)
			(end 5.13588 -2.826512)
			(stroke
				(width 0.1)
				(type default)
			)
			(layer "F.SilkS")
		)
		(fp_line
			(start 2.92989 -5.616194)
			(end 0.061468 -2.864358)
			(stroke
				(width 0.1)
				(type default)
			)
			(layer "F.SilkS")
		)
		(fp_line
			(start 2.92989 -5.616194)
			(end 0.061468 -2.864358)
			(stroke
				(width 0.1)
				(type default)
			)
			(layer "F.SilkS")
		)
		(fp_line
			(start 2.93878 -0.661416)
			(end 5.126736 -2.760218)
			(stroke
				(width 0.1)
				(type default)
			)
			(layer "F.SilkS")
		)
		(fp_line
			(start 2.93878 -0.661416)
			(end 5.126736 -2.760218)
			(stroke
				(width 0.1)
				(type default)
			)
			(layer "F.SilkS")
		)
		(fp_line
			(start 2.98323 -5.609336)
			(end 0.067818 -2.812542)
			(stroke
				(width 0.1)
				(type default)
			)
			(layer "F.SilkS")
		)
		(fp_line
			(start 2.98323 -5.609336)
			(end 0.067818 -2.812542)
			(stroke
				(width 0.1)
				(type default)
			)
			(layer "F.SilkS")
		)
		(fp_line
			(start 2.9972 -0.659638)
			(end 5.117592 -2.69367)
			(stroke
				(width 0.1)
				(type default)
			)
			(layer "F.SilkS")
		)
		(fp_line
			(start 2.9972 -0.659638)
			(end 5.117592 -2.69367)
			(stroke
				(width 0.1)
				(type default)
			)
			(layer "F.SilkS")
		)
		(fp_line
			(start 3.03657 -5.602732)
			(end 0.073914 -2.76098)
			(stroke
				(width 0.1)
				(type default)
			)
			(layer "F.SilkS")
		)
		(fp_line
			(start 3.03657 -5.602732)
			(end 0.073914 -2.76098)
			(stroke
				(width 0.1)
				(type default)
			)
			(layer "F.SilkS")
		)
		(fp_line
			(start 3.048 -0.651002)
			(end 5.108194 -2.627122)
			(stroke
				(width 0.1)
				(type default)
			)
			(layer "F.SilkS")
		)
		(fp_line
			(start 3.048 -0.651002)
			(end 5.108194 -2.627122)
			(stroke
				(width 0.1)
				(type default)
			)
			(layer "F.SilkS")
		)
		(fp_line
			(start 3.089656 -5.596382)
			(end 0.080264 -2.709418)
			(stroke
				(width 0.1)
				(type default)
			)
			(layer "F.SilkS")
		)
		(fp_line
			(start 3.089656 -5.596382)
			(end 0.080264 -2.709418)
			(stroke
				(width 0.1)
				(type default)
			)
			(layer "F.SilkS")
		)
		(fp_line
			(start 3.094482 -0.637286)
			(end 5.09905 -2.560574)
			(stroke
				(width 0.1)
				(type default)
			)
			(layer "F.SilkS")
		)
		(fp_line
			(start 3.094482 -0.637286)
			(end 5.09905 -2.560574)
			(stroke
				(width 0.1)
				(type default)
			)
			(layer "F.SilkS")
		)
		(fp_line
			(start 3.13944 -0.622808)
			(end 5.081524 -2.485898)
			(stroke
				(width 0.1)
				(type default)
			)
			(layer "F.SilkS")
		)
		(fp_line
			(start 3.13944 -0.622808)
			(end 5.081524 -2.485898)
			(stroke
				(width 0.1)
				(type default)
			)
			(layer "F.SilkS")
		)
		(fp_line
			(start 3.14325 -5.589778)
			(end 1.972818 -4.467098)
			(stroke
				(width 0.1)
				(type default)
			)
			(layer "F.SilkS")
		)
		(fp_line
			(start 3.14325 -5.589778)
			(end 1.972818 -4.467098)
			(stroke
				(width 0.1)
				(type default)
			)
			(layer "F.SilkS")
		)
		(fp_line
			(start 3.184144 -0.60833)
			(end 5.061966 -2.409698)
			(stroke
				(width 0.1)
				(type default)
			)
			(layer "F.SilkS")
		)
		(fp_line
			(start 3.184144 -0.60833)
			(end 5.061966 -2.409698)
			(stroke
				(width 0.1)
				(type default)
			)
			(layer "F.SilkS")
		)
		(fp_line
			(start 3.19405 -5.580888)
			(end 2.123694 -4.553966)
			(stroke
				(width 0.1)
				(type default)
			)
			(layer "F.SilkS")
		)
		(fp_line
			(start 3.19405 -5.580888)
			(end 2.123694 -4.553966)
			(stroke
				(width 0.1)
				(type default)
			)
			(layer "F.SilkS")
		)
		(fp_line
			(start 3.22834 -0.592836)
			(end 5.042408 -2.33299)
			(stroke
				(width 0.1)
				(type default)
			)
			(layer "F.SilkS")
		)
		(fp_line
			(start 3.22834 -0.592836)
			(end 5.042408 -2.33299)
			(stroke
				(width 0.1)
				(type default)
			)
			(layer "F.SilkS")
		)
		(fp_line
			(start 3.243072 -5.57022)
			(end 2.217166 -4.586224)
			(stroke
				(width 0.1)
				(type default)
			)
			(layer "F.SilkS")
		)
		(fp_line
			(start 3.243072 -5.57022)
			(end 2.217166 -4.586224)
			(stroke
				(width 0.1)
				(type default)
			)
			(layer "F.SilkS")
		)
		(fp_line
			(start 3.272536 -0.577342)
			(end 5.02285 -2.256536)
			(stroke
				(width 0.1)
				(type default)
			)
			(layer "F.SilkS")
		)
		(fp_line
			(start 3.272536 -0.577342)
			(end 5.02285 -2.256536)
			(stroke
				(width 0.1)
				(type default)
			)
			(layer "F.SilkS")
		)
		(fp_line
			(start 3.292094 -5.559552)
			(end 2.310892 -4.618228)
			(stroke
				(width 0.1)
				(type default)
			)
			(layer "F.SilkS")
		)
		(fp_line
			(start 3.292094 -5.559552)
			(end 2.310892 -4.618228)
			(stroke
				(width 0.1)
				(type default)
			)
			(layer "F.SilkS")
		)
		(fp_line
			(start 3.316224 -0.561848)
			(end 4.990338 -2.167636)
			(stroke
				(width 0.1)
				(type default)
			)
			(layer "F.SilkS")
		)
		(fp_line
			(start 3.316224 -0.561848)
			(end 4.990338 -2.167636)
			(stroke
				(width 0.1)
				(type default)
			)
			(layer "F.SilkS")
		)
		(fp_line
			(start 3.34137 -5.549138)
			(end 2.389632 -4.636262)
			(stroke
				(width 0.1)
				(type default)
			)
			(layer "F.SilkS")
		)
		(fp_line
			(start 3.34137 -5.549138)
			(end 2.389632 -4.636262)
			(stroke
				(width 0.1)
				(type default)
			)
			(layer "F.SilkS")
		)
		(fp_line
			(start 3.359912 -0.545846)
			(end 4.953254 -2.074418)
			(stroke
				(width 0.1)
				(type default)
			)
			(layer "F.SilkS")
		)
		(fp_line
			(start 3.359912 -0.545846)
			(end 4.953254 -2.074418)
			(stroke
				(width 0.1)
				(type default)
			)
			(layer "F.SilkS")
		)
		(fp_line
			(start 3.390392 -5.53847)
			(end 2.458212 -4.644136)
			(stroke
				(width 0.1)
				(type default)
			)
			(layer "F.SilkS")
		)
		(fp_line
			(start 3.390392 -5.53847)
			(end 2.458212 -4.644136)
			(stroke
				(width 0.1)
				(type default)
			)
			(layer "F.SilkS")
		)
		(fp_line
			(start 3.4036 -0.530098)
			(end 4.915916 -1.980946)
			(stroke
				(width 0.1)
				(type default)
			)
			(layer "F.SilkS")
		)
		(fp_line
			(start 3.4036 -0.530098)
			(end 4.915916 -1.980946)
			(stroke
				(width 0.1)
				(type default)
			)
			(layer "F.SilkS")
		)
		(fp_line
			(start 3.437382 -5.52577)
			(end 2.526538 -4.65201)
			(stroke
				(width 0.1)
				(type default)
			)
			(layer "F.SilkS")
		)
		(fp_line
			(start 3.437382 -5.52577)
			(end 2.526538 -4.65201)
			(stroke
				(width 0.1)
				(type default)
			)
			(layer "F.SilkS")
		)
		(fp_line
			(start 3.447034 -0.513842)
			(end 4.85267 -1.862582)
			(stroke
				(width 0.1)
				(type default)
			)
			(layer "F.SilkS")
		)
		(fp_line
			(start 3.447034 -0.513842)
			(end 4.85267 -1.862582)
			(stroke
				(width 0.1)
				(type default)
			)
			(layer "F.SilkS")
		)
		(fp_line
			(start 3.482594 -5.511292)
			(end 2.593086 -4.658106)
			(stroke
				(width 0.1)
				(type default)
			)
			(layer "F.SilkS")
		)
		(fp_line
			(start 3.482594 -5.511292)
			(end 2.593086 -4.658106)
			(stroke
				(width 0.1)
				(type default)
			)
			(layer "F.SilkS")
		)
		(fp_line
			(start 3.490468 -0.498094)
			(end 4.77901 -1.734058)
			(stroke
				(width 0.1)
				(type default)
			)
			(layer "F.SilkS")
		)
		(fp_line
			(start 3.490468 -0.498094)
			(end 4.77901 -1.734058)
			(stroke
				(width 0.1)
				(type default)
			)
			(layer "F.SilkS")
		)
		(fp_line
			(start 3.527806 -5.497068)
			(end 2.647188 -4.652264)
			(stroke
				(width 0.1)
				(type default)
			)
			(layer "F.SilkS")
		)
		(fp_line
			(start 3.527806 -5.497068)
			(end 2.647188 -4.652264)
			(stroke
				(width 0.1)
				(type default)
			)
			(layer "F.SilkS")
		)
		(fp_line
			(start 3.533648 -0.481838)
			(end 4.147312 -1.070356)
			(stroke
				(width 0.1)
				(type default)
			)
			(layer "F.SilkS")
		)
		(fp_line
			(start 3.533648 -0.481838)
			(end 4.147312 -1.070356)
			(stroke
				(width 0.1)
				(type default)
			)
			(layer "F.SilkS")
		)
		(fp_line
			(start 3.573018 -5.482844)
			(end 2.700782 -4.645914)
			(stroke
				(width 0.1)
				(type default)
			)
			(layer "F.SilkS")
		)
		(fp_line
			(start 3.573018 -5.482844)
			(end 2.700782 -4.645914)
			(stroke
				(width 0.1)
				(type default)
			)
			(layer "F.SilkS")
		)
		(fp_line
			(start 3.61823 -5.468366)
			(end 2.75463 -4.639818)
			(stroke
				(width 0.1)
				(type default)
			)
			(layer "F.SilkS")
		)
		(fp_line
			(start 3.61823 -5.468366)
			(end 2.75463 -4.639818)
			(stroke
				(width 0.1)
				(type default)
			)
			(layer "F.SilkS")
		)
		(fp_line
			(start 3.620008 -0.449072)
			(end 4.2164 -1.02108)
			(stroke
				(width 0.1)
				(type default)
			)
			(layer "F.SilkS")
		)
		(fp_line
			(start 3.620008 -0.449072)
			(end 4.2164 -1.02108)
			(stroke
				(width 0.1)
				(type default)
			)
			(layer "F.SilkS")
		)
		(fp_line
			(start 3.662426 -5.452872)
			(end 2.808478 -4.633976)
			(stroke
				(width 0.1)
				(type default)
			)
			(layer "F.SilkS")
		)
		(fp_line
			(start 3.662426 -5.452872)
			(end 2.808478 -4.633976)
			(stroke
				(width 0.1)
				(type default)
			)
			(layer "F.SilkS")
		)
		(fp_line
			(start 3.663442 -0.43307)
			(end 4.250944 -0.996696)
			(stroke
				(width 0.1)
				(type default)
			)
			(layer "F.SilkS")
		)
		(fp_line
			(start 3.663442 -0.43307)
			(end 4.250944 -0.996696)
			(stroke
				(width 0.1)
				(type default)
			)
			(layer "F.SilkS")
		)
		(fp_line
			(start 3.703828 -5.435092)
			(end 2.860548 -4.626102)
			(stroke
				(width 0.1)
				(type default)
			)
			(layer "F.SilkS")
		)
		(fp_line
			(start 3.703828 -5.435092)
			(end 2.860548 -4.626102)
			(stroke
				(width 0.1)
				(type default)
			)
			(layer "F.SilkS")
		)
		(fp_line
			(start 3.706368 -0.416814)
			(end 4.285488 -0.972058)
			(stroke
				(width 0.1)
				(type default)
			)
			(layer "F.SilkS")
		)
		(fp_line
			(start 3.706368 -0.416814)
			(end 4.285488 -0.972058)
			(stroke
				(width 0.1)
				(type default)
			)
			(layer "F.SilkS")
		)
		(fp_line
			(start 3.745484 -5.417058)
			(end 2.90449 -4.610354)
			(stroke
				(width 0.1)
				(type default)
			)
			(layer "F.SilkS")
		)
		(fp_line
			(start 3.745484 -5.417058)
			(end 2.90449 -4.610354)
			(stroke
				(width 0.1)
				(type default)
			)
			(layer "F.SilkS")
		)
		(fp_line
			(start 3.749548 -0.400304)
			(end 4.320286 -0.947674)
			(stroke
				(width 0.1)
				(type default)
			)
			(layer "F.SilkS")
		)
		(fp_line
			(start 3.749548 -0.400304)
			(end 4.320286 -0.947674)
			(stroke
				(width 0.1)
				(type default)
			)
			(layer "F.SilkS")
		)
		(fp_line
			(start 3.786886 -5.399278)
			(end 2.948432 -4.595114)
			(stroke
				(width 0.1)
				(type default)
			)
			(layer "F.SilkS")
		)
		(fp_line
			(start 3.786886 -5.399278)
			(end 2.948432 -4.595114)
			(stroke
				(width 0.1)
				(type default)
			)
			(layer "F.SilkS")
		)
		(fp_line
			(start 3.792474 -0.383794)
			(end 4.35483 -0.923036)
			(stroke
				(width 0.1)
				(type default)
			)
			(layer "F.SilkS")
		)
		(fp_line
			(start 3.792474 -0.383794)
			(end 4.35483 -0.923036)
			(stroke
				(width 0.1)
				(type default)
			)
			(layer "F.SilkS")
		)
		(fp_line
			(start 3.828288 -5.381498)
			(end 2.992628 -4.57962)
			(stroke
				(width 0.1)
				(type default)
			)
			(layer "F.SilkS")
		)
		(fp_line
			(start 3.828288 -5.381498)
			(end 2.992628 -4.57962)
			(stroke
				(width 0.1)
				(type default)
			)
			(layer "F.SilkS")
		)
		(fp_line
			(start 3.8354 -0.36703)
			(end 4.389374 -0.898398)
			(stroke
				(width 0.1)
				(type default)
			)
			(layer "F.SilkS")
		)
		(fp_line
			(start 3.8354 -0.36703)
			(end 4.389374 -0.898398)
			(stroke
				(width 0.1)
				(type default)
			)
			(layer "F.SilkS")
		)
		(fp_line
			(start 3.870198 -5.363464)
			(end 3.036824 -4.56438)
			(stroke
				(width 0.1)
				(type default)
			)
			(layer "F.SilkS")
		)
		(fp_line
			(start 3.870198 -5.363464)
			(end 3.036824 -4.56438)
			(stroke
				(width 0.1)
				(type default)
			)
			(layer "F.SilkS")
		)
		(fp_line
			(start 3.878326 -0.35052)
			(end 4.423918 -0.874014)
			(stroke
				(width 0.1)
				(type default)
			)
			(layer "F.SilkS")
		)
		(fp_line
			(start 3.878326 -0.35052)
			(end 4.423918 -0.874014)
			(stroke
				(width 0.1)
				(type default)
			)
			(layer "F.SilkS")
		)
		(fp_line
			(start 3.908552 -5.34289)
			(end 3.080766 -4.548886)
			(stroke
				(width 0.1)
				(type default)
			)
			(layer "F.SilkS")
		)
		(fp_line
			(start 3.908552 -5.34289)
			(end 3.080766 -4.548886)
			(stroke
				(width 0.1)
				(type default)
			)
			(layer "F.SilkS")
		)
		(fp_line
			(start 3.921252 -0.33401)
			(end 4.458462 -0.849376)
			(stroke
				(width 0.1)
				(type default)
			)
			(layer "F.SilkS")
		)
		(fp_line
			(start 3.921252 -0.33401)
			(end 4.458462 -0.849376)
			(stroke
				(width 0.1)
				(type default)
			)
			(layer "F.SilkS")
		)
		(fp_line
			(start 3.946652 -5.321808)
			(end 3.12039 -4.529074)
			(stroke
				(width 0.1)
				(type default)
			)
			(layer "F.SilkS")
		)
		(fp_line
			(start 3.946652 -5.321808)
			(end 3.12039 -4.529074)
			(stroke
				(width 0.1)
				(type default)
			)
			(layer "F.SilkS")
		)
		(fp_line
			(start 3.964178 -0.3175)
			(end 4.493006 -0.824738)
			(stroke
				(width 0.1)
				(type default)
			)
			(layer "F.SilkS")
		)
		(fp_line
			(start 3.964178 -0.3175)
			(end 4.493006 -0.824738)
			(stroke
				(width 0.1)
				(type default)
			)
			(layer "F.SilkS")
		)
		(fp_line
			(start 3.984752 -5.300472)
			(end 3.15722 -4.506722)
			(stroke
				(width 0.1)
				(type default)
			)
			(layer "F.SilkS")
		)
		(fp_line
			(start 3.984752 -5.300472)
			(end 3.15722 -4.506722)
			(stroke
				(width 0.1)
				(type default)
			)
			(layer "F.SilkS")
		)
		(fp_line
			(start 4.00685 -0.30099)
			(end 4.52755 -0.800608)
			(stroke
				(width 0.1)
				(type default)
			)
			(layer "F.SilkS")
		)
		(fp_line
			(start 4.00685 -0.30099)
			(end 4.52755 -0.800608)
			(stroke
				(width 0.1)
				(type default)
			)
			(layer "F.SilkS")
		)
		(fp_line
			(start 4.022852 -5.27939)
			(end 3.193796 -4.484116)
			(stroke
				(width 0.1)
				(type default)
			)
			(layer "F.SilkS")
		)
		(fp_line
			(start 4.022852 -5.27939)
			(end 3.193796 -4.484116)
			(stroke
				(width 0.1)
				(type default)
			)
			(layer "F.SilkS")
		)
		(fp_line
			(start 4.049776 -0.284226)
			(end 4.562094 -0.775716)
			(stroke
				(width 0.1)
				(type default)
			)
			(layer "F.SilkS")
		)
		(fp_line
			(start 4.049776 -0.284226)
			(end 4.562094 -0.775716)
			(stroke
				(width 0.1)
				(type default)
			)
			(layer "F.SilkS")
		)
		(fp_line
			(start 4.060952 -5.258054)
			(end 3.230372 -4.461256)
			(stroke
				(width 0.1)
				(type default)
			)
			(layer "F.SilkS")
		)
		(fp_line
			(start 4.060952 -5.258054)
			(end 3.230372 -4.461256)
			(stroke
				(width 0.1)
				(type default)
			)
			(layer "F.SilkS")
		)
		(fp_line
			(start 4.092448 -0.267462)
			(end 4.596892 -0.751332)
			(stroke
				(width 0.1)
				(type default)
			)
			(layer "F.SilkS")
		)
		(fp_line
			(start 4.092448 -0.267462)
			(end 4.596892 -0.751332)
			(stroke
				(width 0.1)
				(type default)
			)
			(layer "F.SilkS")
		)
		(fp_line
			(start 4.09829 -5.23621)
			(end 3.266948 -4.438904)
			(stroke
				(width 0.1)
				(type default)
			)
			(layer "F.SilkS")
		)
		(fp_line
			(start 4.09829 -5.23621)
			(end 3.266948 -4.438904)
			(stroke
				(width 0.1)
				(type default)
			)
			(layer "F.SilkS")
		)
		(fp_line
			(start 4.133088 -5.21208)
			(end 3.303524 -4.416044)
			(stroke
				(width 0.1)
				(type default)
			)
			(layer "F.SilkS")
		)
		(fp_line
			(start 4.133088 -5.21208)
			(end 3.303524 -4.416044)
			(stroke
				(width 0.1)
				(type default)
			)
			(layer "F.SilkS")
		)
		(fp_line
			(start 4.135374 -0.250698)
			(end 4.631436 -0.726694)
			(stroke
				(width 0.1)
				(type default)
			)
			(layer "F.SilkS")
		)
		(fp_line
			(start 4.135374 -0.250698)
			(end 4.631436 -0.726694)
			(stroke
				(width 0.1)
				(type default)
			)
			(layer "F.SilkS")
		)
		(fp_line
			(start 4.16814 -5.187696)
			(end 3.337052 -4.390644)
			(stroke
				(width 0.1)
				(type default)
			)
			(layer "F.SilkS")
		)
		(fp_line
			(start 4.16814 -5.187696)
			(end 3.337052 -4.390644)
			(stroke
				(width 0.1)
				(type default)
			)
			(layer "F.SilkS")
		)
		(fp_line
			(start 4.178046 -0.234188)
			(end 4.66598 -0.702056)
			(stroke
				(width 0.1)
				(type default)
			)
			(layer "F.SilkS")
		)
		(fp_line
			(start 4.178046 -0.234188)
			(end 4.66598 -0.702056)
			(stroke
				(width 0.1)
				(type default)
			)
			(layer "F.SilkS")
		)
		(fp_line
			(start 4.181856 -1.045718)
			(end 3.576828 -0.465582)
			(stroke
				(width 0.1)
				(type default)
			)
			(layer "F.SilkS")
		)
		(fp_line
			(start 4.181856 -1.045718)
			(end 3.576828 -0.465582)
			(stroke
				(width 0.1)
				(type default)
			)
			(layer "F.SilkS")
		)
		(fp_line
			(start 4.202938 -5.163312)
			(end 3.367532 -4.362196)
			(stroke
				(width 0.1)
				(type default)
			)
			(layer "F.SilkS")
		)
		(fp_line
			(start 4.202938 -5.163312)
			(end 3.367532 -4.362196)
			(stroke
				(width 0.1)
				(type default)
			)
			(layer "F.SilkS")
		)
		(fp_line
			(start 4.220718 -0.217678)
			(end 4.700524 -0.677926)
			(stroke
				(width 0.1)
				(type default)
			)
			(layer "F.SilkS")
		)
		(fp_line
			(start 4.220718 -0.217678)
			(end 4.700524 -0.677926)
			(stroke
				(width 0.1)
				(type default)
			)
			(layer "F.SilkS")
		)
		(fp_line
			(start 4.237736 -5.139182)
			(end 3.397504 -4.33324)
			(stroke
				(width 0.1)
				(type default)
			)
			(layer "F.SilkS")
		)
		(fp_line
			(start 4.237736 -5.139182)
			(end 3.397504 -4.33324)
			(stroke
				(width 0.1)
				(type default)
			)
			(layer "F.SilkS")
		)
		(fp_line
			(start 4.26339 -0.200406)
			(end 4.735068 -0.653034)
			(stroke
				(width 0.1)
				(type default)
			)
			(layer "F.SilkS")
		)
		(fp_line
			(start 4.26339 -0.200406)
			(end 4.735068 -0.653034)
			(stroke
				(width 0.1)
				(type default)
			)
			(layer "F.SilkS")
		)
		(fp_line
			(start 4.272534 -5.115052)
			(end 3.427984 -4.304792)
			(stroke
				(width 0.1)
				(type default)
			)
			(layer "F.SilkS")
		)
		(fp_line
			(start 4.272534 -5.115052)
			(end 3.427984 -4.304792)
			(stroke
				(width 0.1)
				(type default)
			)
			(layer "F.SilkS")
		)
		(fp_line
			(start 4.306062 -0.183896)
			(end 4.769866 -0.62865)
			(stroke
				(width 0.1)
				(type default)
			)
			(layer "F.SilkS")
		)
		(fp_line
			(start 4.306062 -0.183896)
			(end 4.769866 -0.62865)
			(stroke
				(width 0.1)
				(type default)
			)
			(layer "F.SilkS")
		)
		(fp_line
			(start 4.306316 -5.089398)
			(end 3.45821 -4.275836)
			(stroke
				(width 0.1)
				(type default)
			)
			(layer "F.SilkS")
		)
		(fp_line
			(start 4.306316 -5.089398)
			(end 3.45821 -4.275836)
			(stroke
				(width 0.1)
				(type default)
			)
			(layer "F.SilkS")
		)
		(fp_line
			(start 4.338066 -5.06222)
			(end 3.488436 -4.247388)
			(stroke
				(width 0.1)
				(type default)
			)
			(layer "F.SilkS")
		)
		(fp_line
			(start 4.338066 -5.06222)
			(end 3.488436 -4.247388)
			(stroke
				(width 0.1)
				(type default)
			)
			(layer "F.SilkS")
		)
		(fp_line
			(start 4.348734 -0.166878)
			(end 4.80441 -0.604266)
			(stroke
				(width 0.1)
				(type default)
			)
			(layer "F.SilkS")
		)
		(fp_line
			(start 4.348734 -0.166878)
			(end 4.80441 -0.604266)
			(stroke
				(width 0.1)
				(type default)
			)
			(layer "F.SilkS")
		)
		(fp_line
			(start 4.37007 -5.035296)
			(end 3.518408 -4.218432)
			(stroke
				(width 0.1)
				(type default)
			)
			(layer "F.SilkS")
		)
		(fp_line
			(start 4.37007 -5.035296)
			(end 3.518408 -4.218432)
			(stroke
				(width 0.1)
				(type default)
			)
			(layer "F.SilkS")
		)
		(fp_line
			(start 4.391406 -0.150114)
			(end 4.838954 -0.579628)
			(stroke
				(width 0.1)
				(type default)
			)
			(layer "F.SilkS")
		)
		(fp_line
			(start 4.391406 -0.150114)
			(end 4.838954 -0.579628)
			(stroke
				(width 0.1)
				(type default)
			)
			(layer "F.SilkS")
		)
		(fp_line
			(start 4.401566 -5.008118)
			(end 3.542792 -4.183888)
			(stroke
				(width 0.1)
				(type default)
			)
			(layer "F.SilkS")
		)
		(fp_line
			(start 4.401566 -5.008118)
			(end 3.542792 -4.183888)
			(stroke
				(width 0.1)
				(type default)
			)
			(layer "F.SilkS")
		)
		(fp_line
			(start 4.43357 -4.98094)
			(end 3.567176 -4.149598)
			(stroke
				(width 0.1)
				(type default)
			)
			(layer "F.SilkS")
		)
		(fp_line
			(start 4.43357 -4.98094)
			(end 3.567176 -4.149598)
			(stroke
				(width 0.1)
				(type default)
			)
			(layer "F.SilkS")
		)
		(fp_line
			(start 4.433824 -0.133604)
			(end 4.873752 -0.555244)
			(stroke
				(width 0.1)
				(type default)
			)
			(layer "F.SilkS")
		)
		(fp_line
			(start 4.433824 -0.133604)
			(end 4.873752 -0.555244)
			(stroke
				(width 0.1)
				(type default)
			)
			(layer "F.SilkS")
		)
		(fp_line
			(start 4.46532 -4.953508)
			(end 3.59156 -4.115308)
			(stroke
				(width 0.1)
				(type default)
			)
			(layer "F.SilkS")
		)
		(fp_line
			(start 4.46532 -4.953508)
			(end 3.59156 -4.115308)
			(stroke
				(width 0.1)
				(type default)
			)
			(layer "F.SilkS")
		)
		(fp_line
			(start 4.476496 -0.116332)
			(end 4.908296 -0.530352)
			(stroke
				(width 0.1)
				(type default)
			)
			(layer "F.SilkS")
		)
		(fp_line
			(start 4.476496 -0.116332)
			(end 4.908296 -0.530352)
			(stroke
				(width 0.1)
				(type default)
			)
			(layer "F.SilkS")
		)
		(fp_line
			(start 4.4958 -4.92506)
			(end 3.615944 -4.081018)
			(stroke
				(width 0.1)
				(type default)
			)
			(layer "F.SilkS")
		)
		(fp_line
			(start 4.4958 -4.92506)
			(end 3.615944 -4.081018)
			(stroke
				(width 0.1)
				(type default)
			)
			(layer "F.SilkS")
		)
		(fp_line
			(start 4.519168 -0.099822)
			(end 4.94284 -0.506222)
			(stroke
				(width 0.1)
				(type default)
			)
			(layer "F.SilkS")
		)
		(fp_line
			(start 4.519168 -0.099822)
			(end 4.94284 -0.506222)
			(stroke
				(width 0.1)
				(type default)
			)
			(layer "F.SilkS")
		)
		(fp_line
			(start 4.52374 -4.894072)
			(end 3.640328 -4.046728)
			(stroke
				(width 0.1)
				(type default)
			)
			(layer "F.SilkS")
		)
		(fp_line
			(start 4.52374 -4.894072)
			(end 3.640328 -4.046728)
			(stroke
				(width 0.1)
				(type default)
			)
			(layer "F.SilkS")
		)
		(fp_line
			(start 4.55168 -4.863338)
			(end 3.664712 -4.012438)
			(stroke
				(width 0.1)
				(type default)
			)
			(layer "F.SilkS")
		)
		(fp_line
			(start 4.55168 -4.863338)
			(end 3.664712 -4.012438)
			(stroke
				(width 0.1)
				(type default)
			)
			(layer "F.SilkS")
		)
		(fp_line
			(start 4.561586 -0.08255)
			(end 4.977384 -0.481584)
			(stroke
				(width 0.1)
				(type default)
			)
			(layer "F.SilkS")
		)
		(fp_line
			(start 4.561586 -0.08255)
			(end 4.977384 -0.481584)
			(stroke
				(width 0.1)
				(type default)
			)
			(layer "F.SilkS")
		)
		(fp_line
			(start 4.57962 -4.83235)
			(end 3.686556 -3.975608)
			(stroke
				(width 0.1)
				(type default)
			)
			(layer "F.SilkS")
		)
		(fp_line
			(start 4.57962 -4.83235)
			(end 3.686556 -3.975608)
			(stroke
				(width 0.1)
				(type default)
			)
			(layer "F.SilkS")
		)
		(fp_line
			(start 4.60756 -4.801362)
			(end 3.704844 -3.935476)
			(stroke
				(width 0.1)
				(type default)
			)
			(layer "F.SilkS")
		)
		(fp_line
			(start 4.60756 -4.801362)
			(end 3.704844 -3.935476)
			(stroke
				(width 0.1)
				(type default)
			)
			(layer "F.SilkS")
		)
		(fp_line
			(start 4.631182 -0.091948)
			(end 4.713478 -0.112776)
			(stroke
				(width 0.1)
				(type default)
			)
			(layer "F.SilkS")
		)
		(fp_line
			(start 4.631182 -0.091948)
			(end 4.713478 -0.112776)
			(stroke
				(width 0.1)
				(type default)
			)
			(layer "F.SilkS")
		)
		(fp_line
			(start 4.631182 -0.091948)
			(end 5.012182 -0.456946)
			(stroke
				(width 0.1)
				(type default)
			)
			(layer "F.SilkS")
		)
		(fp_line
			(start 4.631182 -0.091948)
			(end 5.012182 -0.456946)
			(stroke
				(width 0.1)
				(type default)
			)
			(layer "F.SilkS")
		)
		(fp_line
			(start 4.635246 -4.770374)
			(end 3.723386 -3.895598)
			(stroke
				(width 0.1)
				(type default)
			)
			(layer "F.SilkS")
		)
		(fp_line
			(start 4.635246 -4.770374)
			(end 3.723386 -3.895598)
			(stroke
				(width 0.1)
				(type default)
			)
			(layer "F.SilkS")
		)
		(fp_line
			(start 4.663186 -4.739386)
			(end 3.741928 -3.85572)
			(stroke
				(width 0.1)
				(type default)
			)
			(layer "F.SilkS")
		)
		(fp_line
			(start 4.663186 -4.739386)
			(end 3.741928 -3.85572)
			(stroke
				(width 0.1)
				(type default)
			)
			(layer "F.SilkS")
		)
		(fp_line
			(start 4.690618 -4.70789)
			(end 3.76047 -3.815588)
			(stroke
				(width 0.1)
				(type default)
			)
			(layer "F.SilkS")
		)
		(fp_line
			(start 4.690618 -4.70789)
			(end 3.76047 -3.815588)
			(stroke
				(width 0.1)
				(type default)
			)
			(layer "F.SilkS")
		)
		(fp_line
			(start 4.713478 -0.112776)
			(end 4.795266 -0.133604)
			(stroke
				(width 0.1)
				(type default)
			)
			(layer "F.SilkS")
		)
		(fp_line
			(start 4.713478 -0.112776)
			(end 4.795266 -0.133604)
			(stroke
				(width 0.1)
				(type default)
			)
			(layer "F.SilkS")
		)
		(fp_line
			(start 4.713478 -0.112776)
			(end 5.046726 -0.432562)
			(stroke
				(width 0.1)
				(type default)
			)
			(layer "F.SilkS")
		)
		(fp_line
			(start 4.713478 -0.112776)
			(end 5.046726 -0.432562)
			(stroke
				(width 0.1)
				(type default)
			)
			(layer "F.SilkS")
		)
		(fp_line
			(start 4.713732 -4.672584)
			(end 3.778758 -3.775456)
			(stroke
				(width 0.1)
				(type default)
			)
			(layer "F.SilkS")
		)
		(fp_line
			(start 4.713732 -4.672584)
			(end 3.778758 -3.775456)
			(stroke
				(width 0.1)
				(type default)
			)
			(layer "F.SilkS")
		)
		(fp_line
			(start 4.7371 -4.637278)
			(end 3.7973 -3.735578)
			(stroke
				(width 0.1)
				(type default)
			)
			(layer "F.SilkS")
		)
		(fp_line
			(start 4.7371 -4.637278)
			(end 3.7973 -3.735578)
			(stroke
				(width 0.1)
				(type default)
			)
			(layer "F.SilkS")
		)
		(fp_line
			(start 4.760214 -4.601718)
			(end 3.81 -3.689858)
			(stroke
				(width 0.1)
				(type default)
			)
			(layer "F.SilkS")
		)
		(fp_line
			(start 4.760214 -4.601718)
			(end 3.81 -3.689858)
			(stroke
				(width 0.1)
				(type default)
			)
			(layer "F.SilkS")
		)
		(fp_line
			(start 4.783582 -4.566158)
			(end 3.821938 -3.643884)
			(stroke
				(width 0.1)
				(type default)
			)
			(layer "F.SilkS")
		)
		(fp_line
			(start 4.783582 -4.566158)
			(end 3.821938 -3.643884)
			(stroke
				(width 0.1)
				(type default)
			)
			(layer "F.SilkS")
		)
		(fp_line
			(start 4.795266 -0.133604)
			(end 4.877308 -0.15494)
			(stroke
				(width 0.1)
				(type default)
			)
			(layer "F.SilkS")
		)
		(fp_line
			(start 4.795266 -0.133604)
			(end 4.877308 -0.15494)
			(stroke
				(width 0.1)
				(type default)
			)
			(layer "F.SilkS")
		)
		(fp_line
			(start 4.795266 -0.133604)
			(end 5.08127 -0.408178)
			(stroke
				(width 0.1)
				(type default)
			)
			(layer "F.SilkS")
		)
		(fp_line
			(start 4.795266 -0.133604)
			(end 5.08127 -0.408178)
			(stroke
				(width 0.1)
				(type default)
			)
			(layer "F.SilkS")
		)
		(fp_line
			(start 4.806696 -4.530852)
			(end 3.83413 -3.59791)
			(stroke
				(width 0.1)
				(type default)
			)
			(layer "F.SilkS")
		)
		(fp_line
			(start 4.806696 -4.530852)
			(end 3.83413 -3.59791)
			(stroke
				(width 0.1)
				(type default)
			)
			(layer "F.SilkS")
		)
		(fp_line
			(start 4.82981 -4.495292)
			(end 3.846068 -3.551682)
			(stroke
				(width 0.1)
				(type default)
			)
			(layer "F.SilkS")
		)
		(fp_line
			(start 4.82981 -4.495292)
			(end 3.846068 -3.551682)
			(stroke
				(width 0.1)
				(type default)
			)
			(layer "F.SilkS")
		)
		(fp_line
			(start 4.851654 -4.458462)
			(end 3.858006 -3.505454)
			(stroke
				(width 0.1)
				(type default)
			)
			(layer "F.SilkS")
		)
		(fp_line
			(start 4.851654 -4.458462)
			(end 3.858006 -3.505454)
			(stroke
				(width 0.1)
				(type default)
			)
			(layer "F.SilkS")
		)
		(fp_line
			(start 4.870958 -4.419092)
			(end 3.870198 -3.459226)
			(stroke
				(width 0.1)
				(type default)
			)
			(layer "F.SilkS")
		)
		(fp_line
			(start 4.870958 -4.419092)
			(end 3.870198 -3.459226)
			(stroke
				(width 0.1)
				(type default)
			)
			(layer "F.SilkS")
		)
		(fp_line
			(start 4.877308 -0.15494)
			(end 4.95935 -0.175514)
			(stroke
				(width 0.1)
				(type default)
			)
			(layer "F.SilkS")
		)
		(fp_line
			(start 4.877308 -0.15494)
			(end 4.95935 -0.175514)
			(stroke
				(width 0.1)
				(type default)
			)
			(layer "F.SilkS")
		)
		(fp_line
			(start 4.877308 -0.15494)
			(end 5.115814 -0.383794)
			(stroke
				(width 0.1)
				(type default)
			)
			(layer "F.SilkS")
		)
		(fp_line
			(start 4.877308 -0.15494)
			(end 5.115814 -0.383794)
			(stroke
				(width 0.1)
				(type default)
			)
			(layer "F.SilkS")
		)
		(fp_line
			(start 4.889754 -4.379722)
			(end 3.878072 -3.409188)
			(stroke
				(width 0.1)
				(type default)
			)
			(layer "F.SilkS")
		)
		(fp_line
			(start 4.889754 -4.379722)
			(end 3.878072 -3.409188)
			(stroke
				(width 0.1)
				(type default)
			)
			(layer "F.SilkS")
		)
		(fp_line
			(start 4.908804 -4.340098)
			(end 3.88239 -3.355848)
			(stroke
				(width 0.1)
				(type default)
			)
			(layer "F.SilkS")
		)
		(fp_line
			(start 4.908804 -4.340098)
			(end 3.88239 -3.355848)
			(stroke
				(width 0.1)
				(type default)
			)
			(layer "F.SilkS")
		)
		(fp_line
			(start 4.927854 -4.300728)
			(end 3.886962 -3.302254)
			(stroke
				(width 0.1)
				(type default)
			)
			(layer "F.SilkS")
		)
		(fp_line
			(start 4.927854 -4.300728)
			(end 3.886962 -3.302254)
			(stroke
				(width 0.1)
				(type default)
			)
			(layer "F.SilkS")
		)
		(fp_line
			(start 4.946904 -4.261358)
			(end 3.891534 -3.248914)
			(stroke
				(width 0.1)
				(type default)
			)
			(layer "F.SilkS")
		)
		(fp_line
			(start 4.946904 -4.261358)
			(end 3.891534 -3.248914)
			(stroke
				(width 0.1)
				(type default)
			)
			(layer "F.SilkS")
		)
		(fp_line
			(start 4.95935 -0.175514)
			(end 5.041392 -0.196596)
			(stroke
				(width 0.1)
				(type default)
			)
			(layer "F.SilkS")
		)
		(fp_line
			(start 4.95935 -0.175514)
			(end 5.041392 -0.196596)
			(stroke
				(width 0.1)
				(type default)
			)
			(layer "F.SilkS")
		)
		(fp_line
			(start 4.95935 -0.175514)
			(end 5.150612 -0.359156)
			(stroke
				(width 0.1)
				(type default)
			)
			(layer "F.SilkS")
		)
		(fp_line
			(start 4.95935 -0.175514)
			(end 5.150612 -0.359156)
			(stroke
				(width 0.1)
				(type default)
			)
			(layer "F.SilkS")
		)
		(fp_line
			(start 4.965446 -4.221226)
			(end 3.895852 -3.19532)
			(stroke
				(width 0.1)
				(type default)
			)
			(layer "F.SilkS")
		)
		(fp_line
			(start 4.965446 -4.221226)
			(end 3.895852 -3.19532)
			(stroke
				(width 0.1)
				(type default)
			)
			(layer "F.SilkS")
		)
		(fp_line
			(start 4.980686 -4.1783)
			(end 3.900424 -3.14198)
			(stroke
				(width 0.1)
				(type default)
			)
			(layer "F.SilkS")
		)
		(fp_line
			(start 4.980686 -4.1783)
			(end 3.900424 -3.14198)
			(stroke
				(width 0.1)
				(type default)
			)
			(layer "F.SilkS")
		)
		(fp_line
			(start 4.995672 -4.13512)
			(end 3.899408 -3.083306)
			(stroke
				(width 0.1)
				(type default)
			)
			(layer "F.SilkS")
		)
		(fp_line
			(start 4.995672 -4.13512)
			(end 3.899408 -3.083306)
			(stroke
				(width 0.1)
				(type default)
			)
			(layer "F.SilkS")
		)
		(fp_line
			(start 5.011166 -4.09194)
			(end 3.894328 -3.020822)
			(stroke
				(width 0.1)
				(type default)
			)
			(layer "F.SilkS")
		)
		(fp_line
			(start 5.011166 -4.09194)
			(end 3.894328 -3.020822)
			(stroke
				(width 0.1)
				(type default)
			)
			(layer "F.SilkS")
		)
		(fp_line
			(start 5.026152 -4.04876)
			(end 3.889248 -2.958084)
			(stroke
				(width 0.1)
				(type default)
			)
			(layer "F.SilkS")
		)
		(fp_line
			(start 5.026152 -4.04876)
			(end 3.889248 -2.958084)
			(stroke
				(width 0.1)
				(type default)
			)
			(layer "F.SilkS")
		)
		(fp_line
			(start 5.041392 -4.00558)
			(end 3.884168 -2.8956)
			(stroke
				(width 0.1)
				(type default)
			)
			(layer "F.SilkS")
		)
		(fp_line
			(start 5.041392 -4.00558)
			(end 3.884168 -2.8956)
			(stroke
				(width 0.1)
				(type default)
			)
			(layer "F.SilkS")
		)
		(fp_line
			(start 5.041392 -0.196596)
			(end 5.12318 -0.217678)
			(stroke
				(width 0.1)
				(type default)
			)
			(layer "F.SilkS")
		)
		(fp_line
			(start 5.041392 -0.196596)
			(end 5.12318 -0.217678)
			(stroke
				(width 0.1)
				(type default)
			)
			(layer "F.SilkS")
		)
		(fp_line
			(start 5.041392 -0.196596)
			(end 5.185156 -0.334772)
			(stroke
				(width 0.1)
				(type default)
			)
			(layer "F.SilkS")
		)
		(fp_line
			(start 5.041392 -0.196596)
			(end 5.185156 -0.334772)
			(stroke
				(width 0.1)
				(type default)
			)
			(layer "F.SilkS")
		)
		(fp_line
			(start 5.0546 -3.960622)
			(end 3.879088 -2.832862)
			(stroke
				(width 0.1)
				(type default)
			)
			(layer "F.SilkS")
		)
		(fp_line
			(start 5.0546 -3.960622)
			(end 3.879088 -2.832862)
			(stroke
				(width 0.1)
				(type default)
			)
			(layer "F.SilkS")
		)
		(fp_line
			(start 5.066284 -3.91414)
			(end 3.863086 -2.75971)
			(stroke
				(width 0.1)
				(type default)
			)
			(layer "F.SilkS")
		)
		(fp_line
			(start 5.066284 -3.91414)
			(end 3.863086 -2.75971)
			(stroke
				(width 0.1)
				(type default)
			)
			(layer "F.SilkS")
		)
		(fp_line
			(start 5.078222 -3.867658)
			(end 3.843782 -2.68351)
			(stroke
				(width 0.1)
				(type default)
			)
			(layer "F.SilkS")
		)
		(fp_line
			(start 5.078222 -3.867658)
			(end 3.843782 -2.68351)
			(stroke
				(width 0.1)
				(type default)
			)
			(layer "F.SilkS")
		)
		(fp_line
			(start 5.089652 -3.821176)
			(end 3.824478 -2.607564)
			(stroke
				(width 0.1)
				(type default)
			)
			(layer "F.SilkS")
		)
		(fp_line
			(start 5.089652 -3.821176)
			(end 3.824478 -2.607564)
			(stroke
				(width 0.1)
				(type default)
			)
			(layer "F.SilkS")
		)
		(fp_line
			(start 5.101336 -3.774694)
			(end 3.802126 -2.528316)
			(stroke
				(width 0.1)
				(type default)
			)
			(layer "F.SilkS")
		)
		(fp_line
			(start 5.101336 -3.774694)
			(end 3.802126 -2.528316)
			(stroke
				(width 0.1)
				(type default)
			)
			(layer "F.SilkS")
		)
		(fp_line
			(start 5.110734 -3.72618)
			(end 3.756406 -2.426716)
			(stroke
				(width 0.1)
				(type default)
			)
			(layer "F.SilkS")
		)
		(fp_line
			(start 5.110734 -3.72618)
			(end 3.756406 -2.426716)
			(stroke
				(width 0.1)
				(type default)
			)
			(layer "F.SilkS")
		)
		(fp_line
			(start 5.11937 -3.676396)
			(end 3.710686 -2.32537)
			(stroke
				(width 0.1)
				(type default)
			)
			(layer "F.SilkS")
		)
		(fp_line
			(start 5.11937 -3.676396)
			(end 3.710686 -2.32537)
			(stroke
				(width 0.1)
				(type default)
			)
			(layer "F.SilkS")
		)
		(fp_line
			(start 5.12318 -0.217678)
			(end 5.205222 -0.238252)
			(stroke
				(width 0.1)
				(type default)
			)
			(layer "F.SilkS")
		)
		(fp_line
			(start 5.12318 -0.217678)
			(end 5.205222 -0.238252)
			(stroke
				(width 0.1)
				(type default)
			)
			(layer "F.SilkS")
		)
		(fp_line
			(start 5.12318 -0.217678)
			(end 5.219954 -0.310388)
			(stroke
				(width 0.1)
				(type default)
			)
			(layer "F.SilkS")
		)
		(fp_line
			(start 5.12318 -0.217678)
			(end 5.219954 -0.310388)
			(stroke
				(width 0.1)
				(type default)
			)
			(layer "F.SilkS")
		)
		(fp_line
			(start 5.127498 -3.626612)
			(end 3.618992 -2.17932)
			(stroke
				(width 0.1)
				(type default)
			)
			(layer "F.SilkS")
		)
		(fp_line
			(start 5.127498 -3.626612)
			(end 3.618992 -2.17932)
			(stroke
				(width 0.1)
				(type default)
			)
			(layer "F.SilkS")
		)
		(fp_line
			(start 5.13588 -3.576828)
			(end 2.15773 -0.719836)
			(stroke
				(width 0.1)
				(type default)
			)
			(layer "F.SilkS")
		)
		(fp_line
			(start 5.13588 -3.576828)
			(end 2.15773 -0.719836)
			(stroke
				(width 0.1)
				(type default)
			)
			(layer "F.SilkS")
		)
		(fp_line
			(start 5.205222 -0.238252)
			(end 5.254752 -0.28575)
			(stroke
				(width 0.1)
				(type default)
			)
			(layer "F.SilkS")
		)
		(fp_line
			(start 5.205222 -0.238252)
			(end 5.254752 -0.28575)
			(stroke
				(width 0.1)
				(type default)
			)
			(layer "F.SilkS")
		)
		(fp_line
			(start 5.287264 -0.259588)
			(end 5.205222 -0.238252)
			(stroke
				(width 0.1)
				(type default)
			)
			(layer "F.SilkS")
		)
		(fp_line
			(start 5.287264 -0.259588)
			(end 5.205222 -0.238252)
			(stroke
				(width 0.1)
				(type default)
			)
			(layer "F.SilkS")
		)
		(fp_line
			(start 5.287264 -0.259588)
			(end 5.289296 -0.261366)
			(stroke
				(width 0.1)
				(type default)
			)
			(layer "F.SilkS")
		)
		(fp_line
			(start 5.287264 -0.259588)
			(end 5.289296 -0.261366)
			(stroke
				(width 0.1)
				(type default)
			)
			(layer "F.SilkS")
		)
		(fp_line
			(start 5.507482 -2.281682)
			(end 6.825488 -3.54584)
			(stroke
				(width 0.1)
				(type default)
			)
			(layer "F.SilkS")
		)
		(fp_line
			(start 5.507482 -2.281682)
			(end 6.825488 -3.54584)
			(stroke
				(width 0.1)
				(type default)
			)
			(layer "F.SilkS")
		)
		(fp_line
			(start 5.50799 -2.224278)
			(end 6.81355 -3.476498)
			(stroke
				(width 0.1)
				(type default)
			)
			(layer "F.SilkS")
		)
		(fp_line
			(start 5.50799 -2.224278)
			(end 6.81355 -3.476498)
			(stroke
				(width 0.1)
				(type default)
			)
			(layer "F.SilkS")
		)
		(fp_line
			(start 5.508498 -2.167128)
			(end 6.801104 -3.407156)
			(stroke
				(width 0.1)
				(type default)
			)
			(layer "F.SilkS")
		)
		(fp_line
			(start 5.508498 -2.167128)
			(end 6.801104 -3.407156)
			(stroke
				(width 0.1)
				(type default)
			)
			(layer "F.SilkS")
		)
		(fp_line
			(start 5.508752 -2.109724)
			(end 6.788912 -3.337814)
			(stroke
				(width 0.1)
				(type default)
			)
			(layer "F.SilkS")
		)
		(fp_line
			(start 5.508752 -2.109724)
			(end 6.788912 -3.337814)
			(stroke
				(width 0.1)
				(type default)
			)
			(layer "F.SilkS")
		)
		(fp_line
			(start 5.50926 -2.052574)
			(end 6.776974 -3.268472)
			(stroke
				(width 0.1)
				(type default)
			)
			(layer "F.SilkS")
		)
		(fp_line
			(start 5.50926 -2.052574)
			(end 6.776974 -3.268472)
			(stroke
				(width 0.1)
				(type default)
			)
			(layer "F.SilkS")
		)
		(fp_line
			(start 5.509768 -1.99517)
			(end 6.764782 -3.19913)
			(stroke
				(width 0.1)
				(type default)
			)
			(layer "F.SilkS")
		)
		(fp_line
			(start 5.509768 -1.99517)
			(end 6.764782 -3.19913)
			(stroke
				(width 0.1)
				(type default)
			)
			(layer "F.SilkS")
		)
		(fp_line
			(start 5.510276 -1.937766)
			(end 6.75259 -3.129534)
			(stroke
				(width 0.1)
				(type default)
			)
			(layer "F.SilkS")
		)
		(fp_line
			(start 5.510276 -1.937766)
			(end 6.75259 -3.129534)
			(stroke
				(width 0.1)
				(type default)
			)
			(layer "F.SilkS")
		)
		(fp_line
			(start 5.518912 -1.88849)
			(end 6.740144 -3.060192)
			(stroke
				(width 0.1)
				(type default)
			)
			(layer "F.SilkS")
		)
		(fp_line
			(start 5.518912 -1.88849)
			(end 6.740144 -3.060192)
			(stroke
				(width 0.1)
				(type default)
			)
			(layer "F.SilkS")
		)
		(fp_line
			(start 5.527802 -1.839214)
			(end 6.728206 -2.99085)
			(stroke
				(width 0.1)
				(type default)
			)
			(layer "F.SilkS")
		)
		(fp_line
			(start 5.527802 -1.839214)
			(end 6.728206 -2.99085)
			(stroke
				(width 0.1)
				(type default)
			)
			(layer "F.SilkS")
		)
		(fp_line
			(start 5.536438 -1.789938)
			(end 6.716014 -2.921254)
			(stroke
				(width 0.1)
				(type default)
			)
			(layer "F.SilkS")
		)
		(fp_line
			(start 5.536438 -1.789938)
			(end 6.716014 -2.921254)
			(stroke
				(width 0.1)
				(type default)
			)
			(layer "F.SilkS")
		)
		(fp_line
			(start 5.545582 -1.740916)
			(end 6.703822 -2.852166)
			(stroke
				(width 0.1)
				(type default)
			)
			(layer "F.SilkS")
		)
		(fp_line
			(start 5.545582 -1.740916)
			(end 6.703822 -2.852166)
			(stroke
				(width 0.1)
				(type default)
			)
			(layer "F.SilkS")
		)
		(fp_line
			(start 5.554218 -1.69164)
			(end 6.695186 -2.786126)
			(stroke
				(width 0.1)
				(type default)
			)
			(layer "F.SilkS")
		)
		(fp_line
			(start 5.554218 -1.69164)
			(end 6.695186 -2.786126)
			(stroke
				(width 0.1)
				(type default)
			)
			(layer "F.SilkS")
		)
		(fp_line
			(start 5.563108 -1.642364)
			(end 6.68655 -2.720086)
			(stroke
				(width 0.1)
				(type default)
			)
			(layer "F.SilkS")
		)
		(fp_line
			(start 5.563108 -1.642364)
			(end 6.68655 -2.720086)
			(stroke
				(width 0.1)
				(type default)
			)
			(layer "F.SilkS")
		)
		(fp_line
			(start 5.573522 -1.594612)
			(end 6.678168 -2.6543)
			(stroke
				(width 0.1)
				(type default)
			)
			(layer "F.SilkS")
		)
		(fp_line
			(start 5.573522 -1.594612)
			(end 6.678168 -2.6543)
			(stroke
				(width 0.1)
				(type default)
			)
			(layer "F.SilkS")
		)
		(fp_line
			(start 5.58038 -2.870962)
			(end 5.568188 -2.801366)
			(stroke
				(width 0.1)
				(type default)
			)
			(layer "F.SilkS")
		)
		(fp_line
			(start 5.58038 -2.870962)
			(end 5.568188 -2.801366)
			(stroke
				(width 0.1)
				(type default)
			)
			(layer "F.SilkS")
		)
		(fp_line
			(start 5.591048 -1.553718)
			(end 6.669532 -2.58826)
			(stroke
				(width 0.1)
				(type default)
			)
			(layer "F.SilkS")
		)
		(fp_line
			(start 5.591048 -1.553718)
			(end 6.669532 -2.58826)
			(stroke
				(width 0.1)
				(type default)
			)
			(layer "F.SilkS")
		)
		(fp_line
			(start 5.592572 -2.940304)
			(end 5.58038 -2.870962)
			(stroke
				(width 0.1)
				(type default)
			)
			(layer "F.SilkS")
		)
		(fp_line
			(start 5.592572 -2.940304)
			(end 5.58038 -2.870962)
			(stroke
				(width 0.1)
				(type default)
			)
			(layer "F.SilkS")
		)
		(fp_line
			(start 5.604764 -3.009646)
			(end 5.592572 -2.940304)
			(stroke
				(width 0.1)
				(type default)
			)
			(layer "F.SilkS")
		)
		(fp_line
			(start 5.604764 -3.009646)
			(end 5.592572 -2.940304)
			(stroke
				(width 0.1)
				(type default)
			)
			(layer "F.SilkS")
		)
		(fp_line
			(start 5.60832 -1.51257)
			(end 6.669024 -2.530094)
			(stroke
				(width 0.1)
				(type default)
			)
			(layer "F.SilkS")
		)
		(fp_line
			(start 5.60832 -1.51257)
			(end 6.669024 -2.530094)
			(stroke
				(width 0.1)
				(type default)
			)
			(layer "F.SilkS")
		)
		(fp_line
			(start 5.616956 -3.079242)
			(end 5.604764 -3.009646)
			(stroke
				(width 0.1)
				(type default)
			)
			(layer "F.SilkS")
		)
		(fp_line
			(start 5.616956 -3.079242)
			(end 5.604764 -3.009646)
			(stroke
				(width 0.1)
				(type default)
			)
			(layer "F.SilkS")
		)
		(fp_line
			(start 5.625846 -1.471676)
			(end 6.668516 -2.471928)
			(stroke
				(width 0.1)
				(type default)
			)
			(layer "F.SilkS")
		)
		(fp_line
			(start 5.625846 -1.471676)
			(end 6.668516 -2.471928)
			(stroke
				(width 0.1)
				(type default)
			)
			(layer "F.SilkS")
		)
		(fp_line
			(start 5.629148 -3.148584)
			(end 5.616956 -3.079242)
			(stroke
				(width 0.1)
				(type default)
			)
			(layer "F.SilkS")
		)
		(fp_line
			(start 5.629148 -3.148584)
			(end 5.616956 -3.079242)
			(stroke
				(width 0.1)
				(type default)
			)
			(layer "F.SilkS")
		)
		(fp_line
			(start 5.64134 -3.217926)
			(end 5.629148 -3.148584)
			(stroke
				(width 0.1)
				(type default)
			)
			(layer "F.SilkS")
		)
		(fp_line
			(start 5.64134 -3.217926)
			(end 5.629148 -3.148584)
			(stroke
				(width 0.1)
				(type default)
			)
			(layer "F.SilkS")
		)
		(fp_line
			(start 5.643118 -1.430528)
			(end 6.668008 -2.413762)
			(stroke
				(width 0.1)
				(type default)
			)
			(layer "F.SilkS")
		)
		(fp_line
			(start 5.643118 -1.430528)
			(end 6.668008 -2.413762)
			(stroke
				(width 0.1)
				(type default)
			)
			(layer "F.SilkS")
		)
		(fp_line
			(start 5.653532 -3.287268)
			(end 5.64134 -3.217926)
			(stroke
				(width 0.1)
				(type default)
			)
			(layer "F.SilkS")
		)
		(fp_line
			(start 5.653532 -3.287268)
			(end 5.64134 -3.217926)
			(stroke
				(width 0.1)
				(type default)
			)
			(layer "F.SilkS")
		)
		(fp_line
			(start 5.660644 -1.389634)
			(end 6.67004 -2.357882)
			(stroke
				(width 0.1)
				(type default)
			)
			(layer "F.SilkS")
		)
		(fp_line
			(start 5.660644 -1.389634)
			(end 6.67004 -2.357882)
			(stroke
				(width 0.1)
				(type default)
			)
			(layer "F.SilkS")
		)
		(fp_line
			(start 5.665724 -3.35661)
			(end 5.653532 -3.287268)
			(stroke
				(width 0.1)
				(type default)
			)
			(layer "F.SilkS")
		)
		(fp_line
			(start 5.665724 -3.35661)
			(end 5.653532 -3.287268)
			(stroke
				(width 0.1)
				(type default)
			)
			(layer "F.SilkS")
		)
		(fp_line
			(start 5.677662 -3.425952)
			(end 5.665724 -3.35661)
			(stroke
				(width 0.1)
				(type default)
			)
			(layer "F.SilkS")
		)
		(fp_line
			(start 5.677662 -3.425952)
			(end 5.665724 -3.35661)
			(stroke
				(width 0.1)
				(type default)
			)
			(layer "F.SilkS")
		)
		(fp_line
			(start 5.677916 -1.34874)
			(end 6.678168 -2.308352)
			(stroke
				(width 0.1)
				(type default)
			)
			(layer "F.SilkS")
		)
		(fp_line
			(start 5.677916 -1.34874)
			(end 6.678168 -2.308352)
			(stroke
				(width 0.1)
				(type default)
			)
			(layer "F.SilkS")
		)
		(fp_line
			(start 5.690108 -3.495548)
			(end 5.677662 -3.425952)
			(stroke
				(width 0.1)
				(type default)
			)
			(layer "F.SilkS")
		)
		(fp_line
			(start 5.690108 -3.495548)
			(end 5.677662 -3.425952)
			(stroke
				(width 0.1)
				(type default)
			)
			(layer "F.SilkS")
		)
		(fp_line
			(start 5.697982 -1.310132)
			(end 6.68655 -2.258568)
			(stroke
				(width 0.1)
				(type default)
			)
			(layer "F.SilkS")
		)
		(fp_line
			(start 5.697982 -1.310132)
			(end 6.68655 -2.258568)
			(stroke
				(width 0.1)
				(type default)
			)
			(layer "F.SilkS")
		)
		(fp_line
			(start 5.7023 -3.56489)
			(end 5.690108 -3.495548)
			(stroke
				(width 0.1)
				(type default)
			)
			(layer "F.SilkS")
		)
		(fp_line
			(start 5.7023 -3.56489)
			(end 5.690108 -3.495548)
			(stroke
				(width 0.1)
				(type default)
			)
			(layer "F.SilkS")
		)
		(fp_line
			(start 5.714238 -3.634232)
			(end 5.7023 -3.56489)
			(stroke
				(width 0.1)
				(type default)
			)
			(layer "F.SilkS")
		)
		(fp_line
			(start 5.714238 -3.634232)
			(end 5.7023 -3.56489)
			(stroke
				(width 0.1)
				(type default)
			)
			(layer "F.SilkS")
		)
		(fp_line
			(start 5.724398 -1.27762)
			(end 6.694932 -2.20853)
			(stroke
				(width 0.1)
				(type default)
			)
			(layer "F.SilkS")
		)
		(fp_line
			(start 5.724398 -1.27762)
			(end 6.694932 -2.20853)
			(stroke
				(width 0.1)
				(type default)
			)
			(layer "F.SilkS")
		)
		(fp_line
			(start 5.72643 -3.703828)
			(end 5.714238 -3.634232)
			(stroke
				(width 0.1)
				(type default)
			)
			(layer "F.SilkS")
		)
		(fp_line
			(start 5.72643 -3.703828)
			(end 5.714238 -3.634232)
			(stroke
				(width 0.1)
				(type default)
			)
			(layer "F.SilkS")
		)
		(fp_line
			(start 5.738876 -3.772916)
			(end 5.72643 -3.703828)
			(stroke
				(width 0.1)
				(type default)
			)
			(layer "F.SilkS")
		)
		(fp_line
			(start 5.738876 -3.772916)
			(end 5.72643 -3.703828)
			(stroke
				(width 0.1)
				(type default)
			)
			(layer "F.SilkS")
		)
		(fp_line
			(start 5.750306 -1.244854)
			(end 6.710934 -2.166366)
			(stroke
				(width 0.1)
				(type default)
			)
			(layer "F.SilkS")
		)
		(fp_line
			(start 5.750306 -1.244854)
			(end 6.710934 -2.166366)
			(stroke
				(width 0.1)
				(type default)
			)
			(layer "F.SilkS")
		)
		(fp_line
			(start 5.751068 -3.842512)
			(end 5.738876 -3.772916)
			(stroke
				(width 0.1)
				(type default)
			)
			(layer "F.SilkS")
		)
		(fp_line
			(start 5.751068 -3.842512)
			(end 5.738876 -3.772916)
			(stroke
				(width 0.1)
				(type default)
			)
			(layer "F.SilkS")
		)
		(fp_line
			(start 5.763006 -3.911854)
			(end 5.751068 -3.842512)
			(stroke
				(width 0.1)
				(type default)
			)
			(layer "F.SilkS")
		)
		(fp_line
			(start 5.763006 -3.911854)
			(end 5.751068 -3.842512)
			(stroke
				(width 0.1)
				(type default)
			)
			(layer "F.SilkS")
		)
		(fp_line
			(start 5.775198 -3.98145)
			(end 5.763006 -3.911854)
			(stroke
				(width 0.1)
				(type default)
			)
			(layer "F.SilkS")
		)
		(fp_line
			(start 5.775198 -3.98145)
			(end 5.763006 -3.911854)
			(stroke
				(width 0.1)
				(type default)
			)
			(layer "F.SilkS")
		)
		(fp_line
			(start 5.776468 -1.212342)
			(end 6.728714 -2.125726)
			(stroke
				(width 0.1)
				(type default)
			)
			(layer "F.SilkS")
		)
		(fp_line
			(start 5.776468 -1.212342)
			(end 6.728714 -2.125726)
			(stroke
				(width 0.1)
				(type default)
			)
			(layer "F.SilkS")
		)
		(fp_line
			(start 5.78739 -4.050538)
			(end 5.775198 -3.98145)
			(stroke
				(width 0.1)
				(type default)
			)
			(layer "F.SilkS")
		)
		(fp_line
			(start 5.78739 -4.050538)
			(end 5.775198 -3.98145)
			(stroke
				(width 0.1)
				(type default)
			)
			(layer "F.SilkS")
		)
		(fp_line
			(start 5.799582 -4.11988)
			(end 5.78739 -4.050538)
			(stroke
				(width 0.1)
				(type default)
			)
			(layer "F.SilkS")
		)
		(fp_line
			(start 5.799582 -4.11988)
			(end 5.78739 -4.050538)
			(stroke
				(width 0.1)
				(type default)
			)
			(layer "F.SilkS")
		)
		(fp_line
			(start 5.80263 -1.179576)
			(end 6.746494 -2.084832)
			(stroke
				(width 0.1)
				(type default)
			)
			(layer "F.SilkS")
		)
		(fp_line
			(start 5.80263 -1.179576)
			(end 6.746494 -2.084832)
			(stroke
				(width 0.1)
				(type default)
			)
			(layer "F.SilkS")
		)
		(fp_line
			(start 5.811774 -4.189476)
			(end 5.799582 -4.11988)
			(stroke
				(width 0.1)
				(type default)
			)
			(layer "F.SilkS")
		)
		(fp_line
			(start 5.811774 -4.189476)
			(end 5.799582 -4.11988)
			(stroke
				(width 0.1)
				(type default)
			)
			(layer "F.SilkS")
		)
		(fp_line
			(start 5.823966 -4.258818)
			(end 5.811774 -4.189476)
			(stroke
				(width 0.1)
				(type default)
			)
			(layer "F.SilkS")
		)
		(fp_line
			(start 5.823966 -4.258818)
			(end 5.811774 -4.189476)
			(stroke
				(width 0.1)
				(type default)
			)
			(layer "F.SilkS")
		)
		(fp_line
			(start 5.828792 -1.147064)
			(end 6.769608 -2.049272)
			(stroke
				(width 0.1)
				(type default)
			)
			(layer "F.SilkS")
		)
		(fp_line
			(start 5.828792 -1.147064)
			(end 6.769608 -2.049272)
			(stroke
				(width 0.1)
				(type default)
			)
			(layer "F.SilkS")
		)
		(fp_line
			(start 5.836158 -4.328414)
			(end 5.823966 -4.258818)
			(stroke
				(width 0.1)
				(type default)
			)
			(layer "F.SilkS")
		)
		(fp_line
			(start 5.836158 -4.328414)
			(end 5.823966 -4.258818)
			(stroke
				(width 0.1)
				(type default)
			)
			(layer "F.SilkS")
		)
		(fp_line
			(start 5.84835 -4.397502)
			(end 5.836158 -4.328414)
			(stroke
				(width 0.1)
				(type default)
			)
			(layer "F.SilkS")
		)
		(fp_line
			(start 5.84835 -4.397502)
			(end 5.836158 -4.328414)
			(stroke
				(width 0.1)
				(type default)
			)
			(layer "F.SilkS")
		)
		(fp_line
			(start 5.854954 -1.114298)
			(end 6.79704 -2.018284)
			(stroke
				(width 0.1)
				(type default)
			)
			(layer "F.SilkS")
		)
		(fp_line
			(start 5.854954 -1.114298)
			(end 6.79704 -2.018284)
			(stroke
				(width 0.1)
				(type default)
			)
			(layer "F.SilkS")
		)
		(fp_line
			(start 5.860542 -4.467098)
			(end 5.84835 -4.397502)
			(stroke
				(width 0.1)
				(type default)
			)
			(layer "F.SilkS")
		)
		(fp_line
			(start 5.860542 -4.467098)
			(end 5.84835 -4.397502)
			(stroke
				(width 0.1)
				(type default)
			)
			(layer "F.SilkS")
		)
		(fp_line
			(start 5.872734 -4.53644)
			(end 5.860542 -4.467098)
			(stroke
				(width 0.1)
				(type default)
			)
			(layer "F.SilkS")
		)
		(fp_line
			(start 5.872734 -4.53644)
			(end 5.860542 -4.467098)
			(stroke
				(width 0.1)
				(type default)
			)
			(layer "F.SilkS")
		)
		(fp_line
			(start 5.872734 -4.53644)
			(end 5.884926 -4.605782)
			(stroke
				(width 0.1)
				(type default)
			)
			(layer "F.SilkS")
		)
		(fp_line
			(start 5.872734 -4.53644)
			(end 5.884926 -4.605782)
			(stroke
				(width 0.1)
				(type default)
			)
			(layer "F.SilkS")
		)
		(fp_line
			(start 5.884926 -4.605782)
			(end 5.897118 -4.675124)
			(stroke
				(width 0.1)
				(type default)
			)
			(layer "F.SilkS")
		)
		(fp_line
			(start 5.884926 -4.605782)
			(end 5.897118 -4.675124)
			(stroke
				(width 0.1)
				(type default)
			)
			(layer "F.SilkS")
		)
		(fp_line
			(start 5.884926 -1.085342)
			(end 6.824726 -1.987042)
			(stroke
				(width 0.1)
				(type default)
			)
			(layer "F.SilkS")
		)
		(fp_line
			(start 5.884926 -1.085342)
			(end 6.824726 -1.987042)
			(stroke
				(width 0.1)
				(type default)
			)
			(layer "F.SilkS")
		)
		(fp_line
			(start 5.897118 -4.675124)
			(end 5.90931 -4.74472)
			(stroke
				(width 0.1)
				(type default)
			)
			(layer "F.SilkS")
		)
		(fp_line
			(start 5.897118 -4.675124)
			(end 5.90931 -4.74472)
			(stroke
				(width 0.1)
				(type default)
			)
			(layer "F.SilkS")
		)
		(fp_line
			(start 5.90931 -4.74472)
			(end 5.921502 -4.814062)
			(stroke
				(width 0.1)
				(type default)
			)
			(layer "F.SilkS")
		)
		(fp_line
			(start 5.90931 -4.74472)
			(end 5.921502 -4.814062)
			(stroke
				(width 0.1)
				(type default)
			)
			(layer "F.SilkS")
		)
		(fp_line
			(start 5.919978 -1.061212)
			(end 6.856222 -1.95961)
			(stroke
				(width 0.1)
				(type default)
			)
			(layer "F.SilkS")
		)
		(fp_line
			(start 5.919978 -1.061212)
			(end 6.856222 -1.95961)
			(stroke
				(width 0.1)
				(type default)
			)
			(layer "F.SilkS")
		)
		(fp_line
			(start 5.921502 -4.814062)
			(end 5.933694 -4.883404)
			(stroke
				(width 0.1)
				(type default)
			)
			(layer "F.SilkS")
		)
		(fp_line
			(start 5.921502 -4.814062)
			(end 5.933694 -4.883404)
			(stroke
				(width 0.1)
				(type default)
			)
			(layer "F.SilkS")
		)
		(fp_line
			(start 5.933694 -4.883404)
			(end 5.945886 -4.952746)
			(stroke
				(width 0.1)
				(type default)
			)
			(layer "F.SilkS")
		)
		(fp_line
			(start 5.933694 -4.883404)
			(end 5.945886 -4.952746)
			(stroke
				(width 0.1)
				(type default)
			)
			(layer "F.SilkS")
		)
		(fp_line
			(start 5.945886 -4.952746)
			(end 5.958078 -5.022088)
			(stroke
				(width 0.1)
				(type default)
			)
			(layer "F.SilkS")
		)
		(fp_line
			(start 5.945886 -4.952746)
			(end 5.958078 -5.022088)
			(stroke
				(width 0.1)
				(type default)
			)
			(layer "F.SilkS")
		)
		(fp_line
			(start 5.955284 -1.03759)
			(end 6.894068 -1.93802)
			(stroke
				(width 0.1)
				(type default)
			)
			(layer "F.SilkS")
		)
		(fp_line
			(start 5.955284 -1.03759)
			(end 6.894068 -1.93802)
			(stroke
				(width 0.1)
				(type default)
			)
			(layer "F.SilkS")
		)
		(fp_line
			(start 5.958078 -5.022088)
			(end 5.97027 -5.091684)
			(stroke
				(width 0.1)
				(type default)
			)
			(layer "F.SilkS")
		)
		(fp_line
			(start 5.958078 -5.022088)
			(end 5.97027 -5.091684)
			(stroke
				(width 0.1)
				(type default)
			)
			(layer "F.SilkS")
		)
		(fp_line
			(start 5.97027 -5.091684)
			(end 5.982208 -5.161026)
			(stroke
				(width 0.1)
				(type default)
			)
			(layer "F.SilkS")
		)
		(fp_line
			(start 5.97027 -5.091684)
			(end 5.982208 -5.161026)
			(stroke
				(width 0.1)
				(type default)
			)
			(layer "F.SilkS")
		)
		(fp_line
			(start 5.98424 -5.171694)
			(end 5.982208 -5.161026)
			(stroke
				(width 0.1)
				(type default)
			)
			(layer "F.SilkS")
		)
		(fp_line
			(start 5.98424 -5.171694)
			(end 5.982208 -5.161026)
			(stroke
				(width 0.1)
				(type default)
			)
			(layer "F.SilkS")
		)
		(fp_line
			(start 5.99059 -1.013714)
			(end 6.93166 -1.91643)
			(stroke
				(width 0.1)
				(type default)
			)
			(layer "F.SilkS")
		)
		(fp_line
			(start 5.99059 -1.013714)
			(end 6.93166 -1.91643)
			(stroke
				(width 0.1)
				(type default)
			)
			(layer "F.SilkS")
		)
		(fp_line
			(start 5.993638 -5.171694)
			(end 5.982208 -5.161026)
			(stroke
				(width 0.1)
				(type default)
			)
			(layer "F.SilkS")
		)
		(fp_line
			(start 5.993638 -5.171694)
			(end 5.982208 -5.161026)
			(stroke
				(width 0.1)
				(type default)
			)
			(layer "F.SilkS")
		)
		(fp_line
			(start 5.993638 -5.171694)
			(end 5.98424 -5.171694)
			(stroke
				(width 0.1)
				(type default)
			)
			(layer "F.SilkS")
		)
		(fp_line
			(start 5.993638 -5.171694)
			(end 5.98424 -5.171694)
			(stroke
				(width 0.1)
				(type default)
			)
			(layer "F.SilkS")
		)
		(fp_line
			(start 6.025642 -0.989584)
			(end 6.973062 -1.898396)
			(stroke
				(width 0.1)
				(type default)
			)
			(layer "F.SilkS")
		)
		(fp_line
			(start 6.025642 -0.989584)
			(end 6.973062 -1.898396)
			(stroke
				(width 0.1)
				(type default)
			)
			(layer "F.SilkS")
		)
		(fp_line
			(start 6.053582 -5.171694)
			(end 5.97027 -5.091684)
			(stroke
				(width 0.1)
				(type default)
			)
			(layer "F.SilkS")
		)
		(fp_line
			(start 6.053582 -5.171694)
			(end 5.97027 -5.091684)
			(stroke
				(width 0.1)
				(type default)
			)
			(layer "F.SilkS")
		)
		(fp_line
			(start 6.053582 -5.171694)
			(end 5.993638 -5.171694)
			(stroke
				(width 0.1)
				(type default)
			)
			(layer "F.SilkS")
		)
		(fp_line
			(start 6.053582 -5.171694)
			(end 5.993638 -5.171694)
			(stroke
				(width 0.1)
				(type default)
			)
			(layer "F.SilkS")
		)
		(fp_line
			(start 6.060948 -0.965962)
			(end 7.020306 -1.88595)
			(stroke
				(width 0.1)
				(type default)
			)
			(layer "F.SilkS")
		)
		(fp_line
			(start 6.060948 -0.965962)
			(end 7.020306 -1.88595)
			(stroke
				(width 0.1)
				(type default)
			)
			(layer "F.SilkS")
		)
		(fp_line
			(start 6.096254 -0.942086)
			(end 7.06755 -1.873504)
			(stroke
				(width 0.1)
				(type default)
			)
			(layer "F.SilkS")
		)
		(fp_line
			(start 6.096254 -0.942086)
			(end 7.06755 -1.873504)
			(stroke
				(width 0.1)
				(type default)
			)
			(layer "F.SilkS")
		)
		(fp_line
			(start 6.11378 -5.171694)
			(end 5.958078 -5.022088)
			(stroke
				(width 0.1)
				(type default)
			)
			(layer "F.SilkS")
		)
		(fp_line
			(start 6.11378 -5.171694)
			(end 5.958078 -5.022088)
			(stroke
				(width 0.1)
				(type default)
			)
			(layer "F.SilkS")
		)
		(fp_line
			(start 6.11378 -5.171694)
			(end 6.053582 -5.171694)
			(stroke
				(width 0.1)
				(type default)
			)
			(layer "F.SilkS")
		)
		(fp_line
			(start 6.11378 -5.171694)
			(end 6.053582 -5.171694)
			(stroke
				(width 0.1)
				(type default)
			)
			(layer "F.SilkS")
		)
		(fp_line
			(start 6.136132 -0.922528)
			(end 7.118604 -1.865122)
			(stroke
				(width 0.1)
				(type default)
			)
			(layer "F.SilkS")
		)
		(fp_line
			(start 6.136132 -0.922528)
			(end 7.118604 -1.865122)
			(stroke
				(width 0.1)
				(type default)
			)
			(layer "F.SilkS")
		)
		(fp_line
			(start 6.173978 -5.171694)
			(end 5.945886 -4.952746)
			(stroke
				(width 0.1)
				(type default)
			)
			(layer "F.SilkS")
		)
		(fp_line
			(start 6.173978 -5.171694)
			(end 5.945886 -4.952746)
			(stroke
				(width 0.1)
				(type default)
			)
			(layer "F.SilkS")
		)
		(fp_line
			(start 6.173978 -5.171694)
			(end 6.11378 -5.171694)
			(stroke
				(width 0.1)
				(type default)
			)
			(layer "F.SilkS")
		)
		(fp_line
			(start 6.173978 -5.171694)
			(end 6.11378 -5.171694)
			(stroke
				(width 0.1)
				(type default)
			)
			(layer "F.SilkS")
		)
		(fp_line
			(start 6.180836 -0.907796)
			(end 7.174738 -1.861058)
			(stroke
				(width 0.1)
				(type default)
			)
			(layer "F.SilkS")
		)
		(fp_line
			(start 6.180836 -0.907796)
			(end 7.174738 -1.861058)
			(stroke
				(width 0.1)
				(type default)
			)
			(layer "F.SilkS")
		)
		(fp_line
			(start 6.225794 -0.89281)
			(end 7.231126 -1.857248)
			(stroke
				(width 0.1)
				(type default)
			)
			(layer "F.SilkS")
		)
		(fp_line
			(start 6.225794 -0.89281)
			(end 7.231126 -1.857248)
			(stroke
				(width 0.1)
				(type default)
			)
			(layer "F.SilkS")
		)
		(fp_line
			(start 6.234176 -5.171694)
			(end 5.933694 -4.883404)
			(stroke
				(width 0.1)
				(type default)
			)
			(layer "F.SilkS")
		)
		(fp_line
			(start 6.234176 -5.171694)
			(end 5.933694 -4.883404)
			(stroke
				(width 0.1)
				(type default)
			)
			(layer "F.SilkS")
		)
		(fp_line
			(start 6.234176 -5.171694)
			(end 6.173978 -5.171694)
			(stroke
				(width 0.1)
				(type default)
			)
			(layer "F.SilkS")
		)
		(fp_line
			(start 6.234176 -5.171694)
			(end 6.173978 -5.171694)
			(stroke
				(width 0.1)
				(type default)
			)
			(layer "F.SilkS")
		)
		(fp_line
			(start 6.270752 -0.878332)
			(end 7.291832 -1.857756)
			(stroke
				(width 0.1)
				(type default)
			)
			(layer "F.SilkS")
		)
		(fp_line
			(start 6.270752 -0.878332)
			(end 7.291832 -1.857756)
			(stroke
				(width 0.1)
				(type default)
			)
			(layer "F.SilkS")
		)
		(fp_line
			(start 6.294374 -5.171694)
			(end 5.921502 -4.814062)
			(stroke
				(width 0.1)
				(type default)
			)
			(layer "F.SilkS")
		)
		(fp_line
			(start 6.294374 -5.171694)
			(end 5.921502 -4.814062)
			(stroke
				(width 0.1)
				(type default)
			)
			(layer "F.SilkS")
		)
		(fp_line
			(start 6.294374 -5.171694)
			(end 6.234176 -5.171694)
			(stroke
				(width 0.1)
				(type default)
			)
			(layer "F.SilkS")
		)
		(fp_line
			(start 6.294374 -5.171694)
			(end 6.234176 -5.171694)
			(stroke
				(width 0.1)
				(type default)
			)
			(layer "F.SilkS")
		)
		(fp_line
			(start 6.315456 -0.8636)
			(end 7.356348 -1.862074)
			(stroke
				(width 0.1)
				(type default)
			)
			(layer "F.SilkS")
		)
		(fp_line
			(start 6.315456 -0.8636)
			(end 7.356348 -1.862074)
			(stroke
				(width 0.1)
				(type default)
			)
			(layer "F.SilkS")
		)
		(fp_line
			(start 6.354318 -5.171694)
			(end 5.90931 -4.74472)
			(stroke
				(width 0.1)
				(type default)
			)
			(layer "F.SilkS")
		)
		(fp_line
			(start 6.354318 -5.171694)
			(end 5.90931 -4.74472)
			(stroke
				(width 0.1)
				(type default)
			)
			(layer "F.SilkS")
		)
		(fp_line
			(start 6.354318 -5.171694)
			(end 6.294374 -5.171694)
			(stroke
				(width 0.1)
				(type default)
			)
			(layer "F.SilkS")
		)
		(fp_line
			(start 6.354318 -5.171694)
			(end 6.294374 -5.171694)
			(stroke
				(width 0.1)
				(type default)
			)
			(layer "F.SilkS")
		)
		(fp_line
			(start 6.36016 -0.848868)
			(end 7.421118 -1.866392)
			(stroke
				(width 0.1)
				(type default)
			)
			(layer "F.SilkS")
		)
		(fp_line
			(start 6.36016 -0.848868)
			(end 7.421118 -1.866392)
			(stroke
				(width 0.1)
				(type default)
			)
			(layer "F.SilkS")
		)
		(fp_line
			(start 6.405118 -0.833882)
			(end 7.500366 -1.884934)
			(stroke
				(width 0.1)
				(type default)
			)
			(layer "F.SilkS")
		)
		(fp_line
			(start 6.405118 -0.833882)
			(end 7.500366 -1.884934)
			(stroke
				(width 0.1)
				(type default)
			)
			(layer "F.SilkS")
		)
		(fp_line
			(start 6.41477 -5.171694)
			(end 5.897118 -4.675124)
			(stroke
				(width 0.1)
				(type default)
			)
			(layer "F.SilkS")
		)
		(fp_line
			(start 6.41477 -5.171694)
			(end 5.897118 -4.675124)
			(stroke
				(width 0.1)
				(type default)
			)
			(layer "F.SilkS")
		)
		(fp_line
			(start 6.41477 -5.171694)
			(end 6.354318 -5.171694)
			(stroke
				(width 0.1)
				(type default)
			)
			(layer "F.SilkS")
		)
		(fp_line
			(start 6.41477 -5.171694)
			(end 6.354318 -5.171694)
			(stroke
				(width 0.1)
				(type default)
			)
			(layer "F.SilkS")
		)
		(fp_line
			(start 6.455664 -0.824738)
			(end 7.582662 -1.906016)
			(stroke
				(width 0.1)
				(type default)
			)
			(layer "F.SilkS")
		)
		(fp_line
			(start 6.455664 -0.824738)
			(end 7.582662 -1.906016)
			(stroke
				(width 0.1)
				(type default)
			)
			(layer "F.SilkS")
		)
		(fp_line
			(start 6.474714 -5.171694)
			(end 5.884926 -4.605782)
			(stroke
				(width 0.1)
				(type default)
			)
			(layer "F.SilkS")
		)
		(fp_line
			(start 6.474714 -5.171694)
			(end 5.884926 -4.605782)
			(stroke
				(width 0.1)
				(type default)
			)
			(layer "F.SilkS")
		)
		(fp_line
			(start 6.474714 -5.171694)
			(end 6.41477 -5.171694)
			(stroke
				(width 0.1)
				(type default)
			)
			(layer "F.SilkS")
		)
		(fp_line
			(start 6.474714 -5.171694)
			(end 6.41477 -5.171694)
			(stroke
				(width 0.1)
				(type default)
			)
			(layer "F.SilkS")
		)
		(fp_line
			(start 6.510528 -0.819912)
			(end 7.699756 -1.96088)
			(stroke
				(width 0.1)
				(type default)
			)
			(layer "F.SilkS")
		)
		(fp_line
			(start 6.510528 -0.819912)
			(end 7.699756 -1.96088)
			(stroke
				(width 0.1)
				(type default)
			)
			(layer "F.SilkS")
		)
		(fp_line
			(start 6.534912 -5.171694)
			(end 5.872734 -4.53644)
			(stroke
				(width 0.1)
				(type default)
			)
			(layer "F.SilkS")
		)
		(fp_line
			(start 6.534912 -5.171694)
			(end 5.872734 -4.53644)
			(stroke
				(width 0.1)
				(type default)
			)
			(layer "F.SilkS")
		)
		(fp_line
			(start 6.534912 -5.171694)
			(end 6.474714 -5.171694)
			(stroke
				(width 0.1)
				(type default)
			)
			(layer "F.SilkS")
		)
		(fp_line
			(start 6.534912 -5.171694)
			(end 6.474714 -5.171694)
			(stroke
				(width 0.1)
				(type default)
			)
			(layer "F.SilkS")
		)
		(fp_line
			(start 6.59511 -5.171694)
			(end 5.860542 -4.467098)
			(stroke
				(width 0.1)
				(type default)
			)
			(layer "F.SilkS")
		)
		(fp_line
			(start 6.59511 -5.171694)
			(end 5.860542 -4.467098)
			(stroke
				(width 0.1)
				(type default)
			)
			(layer "F.SilkS")
		)
		(fp_line
			(start 6.59511 -5.171694)
			(end 6.534912 -5.171694)
			(stroke
				(width 0.1)
				(type default)
			)
			(layer "F.SilkS")
		)
		(fp_line
			(start 6.59511 -5.171694)
			(end 6.534912 -5.171694)
			(stroke
				(width 0.1)
				(type default)
			)
			(layer "F.SilkS")
		)
		(fp_line
			(start 6.620256 -0.809498)
			(end 9.404096 -3.480054)
			(stroke
				(width 0.1)
				(type default)
			)
			(layer "F.SilkS")
		)
		(fp_line
			(start 6.620256 -0.809498)
			(end 9.404096 -3.480054)
			(stroke
				(width 0.1)
				(type default)
			)
			(layer "F.SilkS")
		)
		(fp_line
			(start 6.655308 -5.171694)
			(end 5.84835 -4.397502)
			(stroke
				(width 0.1)
				(type default)
			)
			(layer "F.SilkS")
		)
		(fp_line
			(start 6.655308 -5.171694)
			(end 5.84835 -4.397502)
			(stroke
				(width 0.1)
				(type default)
			)
			(layer "F.SilkS")
		)
		(fp_line
			(start 6.655308 -5.171694)
			(end 6.59511 -5.171694)
			(stroke
				(width 0.1)
				(type default)
			)
			(layer "F.SilkS")
		)
		(fp_line
			(start 6.655308 -5.171694)
			(end 6.59511 -5.171694)
			(stroke
				(width 0.1)
				(type default)
			)
			(layer "F.SilkS")
		)
		(fp_line
			(start 6.67512 -0.804672)
			(end 9.391904 -3.410712)
			(stroke
				(width 0.1)
				(type default)
			)
			(layer "F.SilkS")
		)
		(fp_line
			(start 6.67512 -0.804672)
			(end 9.391904 -3.410712)
			(stroke
				(width 0.1)
				(type default)
			)
			(layer "F.SilkS")
		)
		(fp_line
			(start 6.703822 -2.852166)
			(end 6.716014 -2.921254)
			(stroke
				(width 0.1)
				(type default)
			)
			(layer "F.SilkS")
		)
		(fp_line
			(start 6.703822 -2.852166)
			(end 6.716014 -2.921254)
			(stroke
				(width 0.1)
				(type default)
			)
			(layer "F.SilkS")
		)
		(fp_line
			(start 6.715506 -5.171694)
			(end 5.836158 -4.328414)
			(stroke
				(width 0.1)
				(type default)
			)
			(layer "F.SilkS")
		)
		(fp_line
			(start 6.715506 -5.171694)
			(end 5.836158 -4.328414)
			(stroke
				(width 0.1)
				(type default)
			)
			(layer "F.SilkS")
		)
		(fp_line
			(start 6.715506 -5.171694)
			(end 6.655308 -5.171694)
			(stroke
				(width 0.1)
				(type default)
			)
			(layer "F.SilkS")
		)
		(fp_line
			(start 6.715506 -5.171694)
			(end 6.655308 -5.171694)
			(stroke
				(width 0.1)
				(type default)
			)
			(layer "F.SilkS")
		)
		(fp_line
			(start 6.716014 -2.921254)
			(end 6.728206 -2.99085)
			(stroke
				(width 0.1)
				(type default)
			)
			(layer "F.SilkS")
		)
		(fp_line
			(start 6.716014 -2.921254)
			(end 6.728206 -2.99085)
			(stroke
				(width 0.1)
				(type default)
			)
			(layer "F.SilkS")
		)
		(fp_line
			(start 6.728206 -2.99085)
			(end 6.740144 -3.060192)
			(stroke
				(width 0.1)
				(type default)
			)
			(layer "F.SilkS")
		)
		(fp_line
			(start 6.728206 -2.99085)
			(end 6.740144 -3.060192)
			(stroke
				(width 0.1)
				(type default)
			)
			(layer "F.SilkS")
		)
		(fp_line
			(start 6.729984 -0.799592)
			(end 9.379712 -3.34137)
			(stroke
				(width 0.1)
				(type default)
			)
			(layer "F.SilkS")
		)
		(fp_line
			(start 6.729984 -0.799592)
			(end 9.379712 -3.34137)
			(stroke
				(width 0.1)
				(type default)
			)
			(layer "F.SilkS")
		)
		(fp_line
			(start 6.740144 -3.060192)
			(end 6.75259 -3.129534)
			(stroke
				(width 0.1)
				(type default)
			)
			(layer "F.SilkS")
		)
		(fp_line
			(start 6.740144 -3.060192)
			(end 6.75259 -3.129534)
			(stroke
				(width 0.1)
				(type default)
			)
			(layer "F.SilkS")
		)
		(fp_line
			(start 6.75259 -3.129534)
			(end 6.764782 -3.19913)
			(stroke
				(width 0.1)
				(type default)
			)
			(layer "F.SilkS")
		)
		(fp_line
			(start 6.75259 -3.129534)
			(end 6.764782 -3.19913)
			(stroke
				(width 0.1)
				(type default)
			)
			(layer "F.SilkS")
		)
		(fp_line
			(start 6.764782 -3.19913)
			(end 6.776974 -3.268472)
			(stroke
				(width 0.1)
				(type default)
			)
			(layer "F.SilkS")
		)
		(fp_line
			(start 6.764782 -3.19913)
			(end 6.776974 -3.268472)
			(stroke
				(width 0.1)
				(type default)
			)
			(layer "F.SilkS")
		)
		(fp_line
			(start 6.77545 -5.171694)
			(end 5.823966 -4.258818)
			(stroke
				(width 0.1)
				(type default)
			)
			(layer "F.SilkS")
		)
		(fp_line
			(start 6.77545 -5.171694)
			(end 5.823966 -4.258818)
			(stroke
				(width 0.1)
				(type default)
			)
			(layer "F.SilkS")
		)
		(fp_line
			(start 6.77545 -5.171694)
			(end 6.715506 -5.171694)
			(stroke
				(width 0.1)
				(type default)
			)
			(layer "F.SilkS")
		)
		(fp_line
			(start 6.77545 -5.171694)
			(end 6.715506 -5.171694)
			(stroke
				(width 0.1)
				(type default)
			)
			(layer "F.SilkS")
		)
		(fp_line
			(start 6.776974 -3.268472)
			(end 6.788912 -3.337814)
			(stroke
				(width 0.1)
				(type default)
			)
			(layer "F.SilkS")
		)
		(fp_line
			(start 6.776974 -3.268472)
			(end 6.788912 -3.337814)
			(stroke
				(width 0.1)
				(type default)
			)
			(layer "F.SilkS")
		)
		(fp_line
			(start 6.784848 -0.794258)
			(end 9.36752 -3.272028)
			(stroke
				(width 0.1)
				(type default)
			)
			(layer "F.SilkS")
		)
		(fp_line
			(start 6.784848 -0.794258)
			(end 9.36752 -3.272028)
			(stroke
				(width 0.1)
				(type default)
			)
			(layer "F.SilkS")
		)
		(fp_line
			(start 6.788912 -3.337814)
			(end 6.801104 -3.407156)
			(stroke
				(width 0.1)
				(type default)
			)
			(layer "F.SilkS")
		)
		(fp_line
			(start 6.788912 -3.337814)
			(end 6.801104 -3.407156)
			(stroke
				(width 0.1)
				(type default)
			)
			(layer "F.SilkS")
		)
		(fp_line
			(start 6.801104 -3.407156)
			(end 6.81355 -3.476498)
			(stroke
				(width 0.1)
				(type default)
			)
			(layer "F.SilkS")
		)
		(fp_line
			(start 6.801104 -3.407156)
			(end 6.81355 -3.476498)
			(stroke
				(width 0.1)
				(type default)
			)
			(layer "F.SilkS")
		)
		(fp_line
			(start 6.825488 -3.54584)
			(end 6.81355 -3.476498)
			(stroke
				(width 0.1)
				(type default)
			)
			(layer "F.SilkS")
		)
		(fp_line
			(start 6.825488 -3.54584)
			(end 6.81355 -3.476498)
			(stroke
				(width 0.1)
				(type default)
			)
			(layer "F.SilkS")
		)
		(fp_line
			(start 6.825488 -3.54584)
			(end 6.83768 -3.615436)
			(stroke
				(width 0.1)
				(type default)
			)
			(layer "F.SilkS")
		)
		(fp_line
			(start 6.825488 -3.54584)
			(end 6.83768 -3.615436)
			(stroke
				(width 0.1)
				(type default)
			)
			(layer "F.SilkS")
		)
		(fp_line
			(start 6.835648 -5.171694)
			(end 5.811774 -4.189476)
			(stroke
				(width 0.1)
				(type default)
			)
			(layer "F.SilkS")
		)
		(fp_line
			(start 6.835648 -5.171694)
			(end 5.811774 -4.189476)
			(stroke
				(width 0.1)
				(type default)
			)
			(layer "F.SilkS")
		)
		(fp_line
			(start 6.835648 -5.171694)
			(end 6.77545 -5.171694)
			(stroke
				(width 0.1)
				(type default)
			)
			(layer "F.SilkS")
		)
		(fp_line
			(start 6.835648 -5.171694)
			(end 6.77545 -5.171694)
			(stroke
				(width 0.1)
				(type default)
			)
			(layer "F.SilkS")
		)
		(fp_line
			(start 6.83768 -3.615436)
			(end 5.509514 -2.341372)
			(stroke
				(width 0.1)
				(type default)
			)
			(layer "F.SilkS")
		)
		(fp_line
			(start 6.83768 -3.615436)
			(end 5.509514 -2.341372)
			(stroke
				(width 0.1)
				(type default)
			)
			(layer "F.SilkS")
		)
		(fp_line
			(start 6.83768 -3.615436)
			(end 6.849872 -3.684778)
			(stroke
				(width 0.1)
				(type default)
			)
			(layer "F.SilkS")
		)
		(fp_line
			(start 6.83768 -3.615436)
			(end 6.849872 -3.684778)
			(stroke
				(width 0.1)
				(type default)
			)
			(layer "F.SilkS")
		)
		(fp_line
			(start 6.848348 -0.797814)
			(end 9.355328 -3.202432)
			(stroke
				(width 0.1)
				(type default)
			)
			(layer "F.SilkS")
		)
		(fp_line
			(start 6.848348 -0.797814)
			(end 9.355328 -3.202432)
			(stroke
				(width 0.1)
				(type default)
			)
			(layer "F.SilkS")
		)
		(fp_line
			(start 6.849872 -3.684778)
			(end 5.517642 -2.40665)
			(stroke
				(width 0.1)
				(type default)
			)
			(layer "F.SilkS")
		)
		(fp_line
			(start 6.849872 -3.684778)
			(end 5.517642 -2.40665)
			(stroke
				(width 0.1)
				(type default)
			)
			(layer "F.SilkS")
		)
		(fp_line
			(start 6.849872 -3.684778)
			(end 6.862318 -3.75412)
			(stroke
				(width 0.1)
				(type default)
			)
			(layer "F.SilkS")
		)
		(fp_line
			(start 6.849872 -3.684778)
			(end 6.862318 -3.75412)
			(stroke
				(width 0.1)
				(type default)
			)
			(layer "F.SilkS")
		)
		(fp_line
			(start 6.862318 -3.75412)
			(end 5.525516 -2.471928)
			(stroke
				(width 0.1)
				(type default)
			)
			(layer "F.SilkS")
		)
		(fp_line
			(start 6.862318 -3.75412)
			(end 5.525516 -2.471928)
			(stroke
				(width 0.1)
				(type default)
			)
			(layer "F.SilkS")
		)
		(fp_line
			(start 6.862318 -3.75412)
			(end 6.874256 -3.823716)
			(stroke
				(width 0.1)
				(type default)
			)
			(layer "F.SilkS")
		)
		(fp_line
			(start 6.862318 -3.75412)
			(end 6.874256 -3.823716)
			(stroke
				(width 0.1)
				(type default)
			)
			(layer "F.SilkS")
		)
		(fp_line
			(start 6.874256 -3.823716)
			(end 5.53339 -2.537206)
			(stroke
				(width 0.1)
				(type default)
			)
			(layer "F.SilkS")
		)
		(fp_line
			(start 6.874256 -3.823716)
			(end 5.53339 -2.537206)
			(stroke
				(width 0.1)
				(type default)
			)
			(layer "F.SilkS")
		)
		(fp_line
			(start 6.874256 -3.823716)
			(end 6.886448 -3.893058)
			(stroke
				(width 0.1)
				(type default)
			)
			(layer "F.SilkS")
		)
		(fp_line
			(start 6.874256 -3.823716)
			(end 6.886448 -3.893058)
			(stroke
				(width 0.1)
				(type default)
			)
			(layer "F.SilkS")
		)
		(fp_line
			(start 6.886448 -3.893058)
			(end 5.541264 -2.602738)
			(stroke
				(width 0.1)
				(type default)
			)
			(layer "F.SilkS")
		)
		(fp_line
			(start 6.886448 -3.893058)
			(end 5.541264 -2.602738)
			(stroke
				(width 0.1)
				(type default)
			)
			(layer "F.SilkS")
		)
		(fp_line
			(start 6.886448 -3.893058)
			(end 6.89864 -3.9624)
			(stroke
				(width 0.1)
				(type default)
			)
			(layer "F.SilkS")
		)
		(fp_line
			(start 6.886448 -3.893058)
			(end 6.89864 -3.9624)
			(stroke
				(width 0.1)
				(type default)
			)
			(layer "F.SilkS")
		)
		(fp_line
			(start 6.895846 -5.171694)
			(end 5.799582 -4.11988)
			(stroke
				(width 0.1)
				(type default)
			)
			(layer "F.SilkS")
		)
		(fp_line
			(start 6.895846 -5.171694)
			(end 5.799582 -4.11988)
			(stroke
				(width 0.1)
				(type default)
			)
			(layer "F.SilkS")
		)
		(fp_line
			(start 6.895846 -5.171694)
			(end 6.835648 -5.171694)
			(stroke
				(width 0.1)
				(type default)
			)
			(layer "F.SilkS")
		)
		(fp_line
			(start 6.895846 -5.171694)
			(end 6.835648 -5.171694)
			(stroke
				(width 0.1)
				(type default)
			)
			(layer "F.SilkS")
		)
		(fp_line
			(start 6.89864 -3.9624)
			(end 5.549392 -2.668016)
			(stroke
				(width 0.1)
				(type default)
			)
			(layer "F.SilkS")
		)
		(fp_line
			(start 6.89864 -3.9624)
			(end 5.549392 -2.668016)
			(stroke
				(width 0.1)
				(type default)
			)
			(layer "F.SilkS")
		)
		(fp_line
			(start 6.89864 -3.9624)
			(end 6.910832 -4.031742)
			(stroke
				(width 0.1)
				(type default)
			)
			(layer "F.SilkS")
		)
		(fp_line
			(start 6.89864 -3.9624)
			(end 6.910832 -4.031742)
			(stroke
				(width 0.1)
				(type default)
			)
			(layer "F.SilkS")
		)
		(fp_line
			(start 6.910832 -4.031742)
			(end 5.557266 -2.733294)
			(stroke
				(width 0.1)
				(type default)
			)
			(layer "F.SilkS")
		)
		(fp_line
			(start 6.910832 -4.031742)
			(end 5.557266 -2.733294)
			(stroke
				(width 0.1)
				(type default)
			)
			(layer "F.SilkS")
		)
		(fp_line
			(start 6.910832 -4.031742)
			(end 6.923024 -4.101084)
			(stroke
				(width 0.1)
				(type default)
			)
			(layer "F.SilkS")
		)
		(fp_line
			(start 6.910832 -4.031742)
			(end 6.923024 -4.101084)
			(stroke
				(width 0.1)
				(type default)
			)
			(layer "F.SilkS")
		)
		(fp_line
			(start 6.914896 -0.80391)
			(end 9.343136 -3.13309)
			(stroke
				(width 0.1)
				(type default)
			)
			(layer "F.SilkS")
		)
		(fp_line
			(start 6.914896 -0.80391)
			(end 9.343136 -3.13309)
			(stroke
				(width 0.1)
				(type default)
			)
			(layer "F.SilkS")
		)
		(fp_line
			(start 6.923024 -4.101084)
			(end 5.568188 -2.801366)
			(stroke
				(width 0.1)
				(type default)
			)
			(layer "F.SilkS")
		)
		(fp_line
			(start 6.923024 -4.101084)
			(end 5.568188 -2.801366)
			(stroke
				(width 0.1)
				(type default)
			)
			(layer "F.SilkS")
		)
		(fp_line
			(start 6.923024 -4.101084)
			(end 6.935216 -4.170426)
			(stroke
				(width 0.1)
				(type default)
			)
			(layer "F.SilkS")
		)
		(fp_line
			(start 6.923024 -4.101084)
			(end 6.935216 -4.170426)
			(stroke
				(width 0.1)
				(type default)
			)
			(layer "F.SilkS")
		)
		(fp_line
			(start 6.935216 -4.170426)
			(end 5.58038 -2.870962)
			(stroke
				(width 0.1)
				(type default)
			)
			(layer "F.SilkS")
		)
		(fp_line
			(start 6.935216 -4.170426)
			(end 5.58038 -2.870962)
			(stroke
				(width 0.1)
				(type default)
			)
			(layer "F.SilkS")
		)
		(fp_line
			(start 6.935216 -4.170426)
			(end 6.947408 -4.240022)
			(stroke
				(width 0.1)
				(type default)
			)
			(layer "F.SilkS")
		)
		(fp_line
			(start 6.935216 -4.170426)
			(end 6.947408 -4.240022)
			(stroke
				(width 0.1)
				(type default)
			)
			(layer "F.SilkS")
		)
		(fp_line
			(start 6.947408 -4.240022)
			(end 5.592572 -2.940304)
			(stroke
				(width 0.1)
				(type default)
			)
			(layer "F.SilkS")
		)
		(fp_line
			(start 6.947408 -4.240022)
			(end 5.592572 -2.940304)
			(stroke
				(width 0.1)
				(type default)
			)
			(layer "F.SilkS")
		)
		(fp_line
			(start 6.947408 -4.240022)
			(end 6.9596 -4.309364)
			(stroke
				(width 0.1)
				(type default)
			)
			(layer "F.SilkS")
		)
		(fp_line
			(start 6.947408 -4.240022)
			(end 6.9596 -4.309364)
			(stroke
				(width 0.1)
				(type default)
			)
			(layer "F.SilkS")
		)
		(fp_line
			(start 6.956044 -5.171694)
			(end 5.78739 -4.050538)
			(stroke
				(width 0.1)
				(type default)
			)
			(layer "F.SilkS")
		)
		(fp_line
			(start 6.956044 -5.171694)
			(end 5.78739 -4.050538)
			(stroke
				(width 0.1)
				(type default)
			)
			(layer "F.SilkS")
		)
		(fp_line
			(start 6.956044 -5.171694)
			(end 6.895846 -5.171694)
			(stroke
				(width 0.1)
				(type default)
			)
			(layer "F.SilkS")
		)
		(fp_line
			(start 6.956044 -5.171694)
			(end 6.895846 -5.171694)
			(stroke
				(width 0.1)
				(type default)
			)
			(layer "F.SilkS")
		)
		(fp_line
			(start 6.9596 -4.309364)
			(end 5.604764 -3.009646)
			(stroke
				(width 0.1)
				(type default)
			)
			(layer "F.SilkS")
		)
		(fp_line
			(start 6.9596 -4.309364)
			(end 5.604764 -3.009646)
			(stroke
				(width 0.1)
				(type default)
			)
			(layer "F.SilkS")
		)
		(fp_line
			(start 6.9596 -4.309364)
			(end 6.971792 -4.378706)
			(stroke
				(width 0.1)
				(type default)
			)
			(layer "F.SilkS")
		)
		(fp_line
			(start 6.9596 -4.309364)
			(end 6.971792 -4.378706)
			(stroke
				(width 0.1)
				(type default)
			)
			(layer "F.SilkS")
		)
		(fp_line
			(start 6.971792 -4.378706)
			(end 5.616956 -3.079242)
			(stroke
				(width 0.1)
				(type default)
			)
			(layer "F.SilkS")
		)
		(fp_line
			(start 6.971792 -4.378706)
			(end 5.616956 -3.079242)
			(stroke
				(width 0.1)
				(type default)
			)
			(layer "F.SilkS")
		)
		(fp_line
			(start 6.971792 -4.378706)
			(end 6.983984 -4.448302)
			(stroke
				(width 0.1)
				(type default)
			)
			(layer "F.SilkS")
		)
		(fp_line
			(start 6.971792 -4.378706)
			(end 6.983984 -4.448302)
			(stroke
				(width 0.1)
				(type default)
			)
			(layer "F.SilkS")
		)
		(fp_line
			(start 6.981444 -0.809752)
			(end 9.330944 -3.063748)
			(stroke
				(width 0.1)
				(type default)
			)
			(layer "F.SilkS")
		)
		(fp_line
			(start 6.981444 -0.809752)
			(end 9.330944 -3.063748)
			(stroke
				(width 0.1)
				(type default)
			)
			(layer "F.SilkS")
		)
		(fp_line
			(start 6.983984 -4.448302)
			(end 5.629148 -3.148584)
			(stroke
				(width 0.1)
				(type default)
			)
			(layer "F.SilkS")
		)
		(fp_line
			(start 6.983984 -4.448302)
			(end 5.629148 -3.148584)
			(stroke
				(width 0.1)
				(type default)
			)
			(layer "F.SilkS")
		)
		(fp_line
			(start 6.983984 -4.448302)
			(end 6.996176 -4.51739)
			(stroke
				(width 0.1)
				(type default)
			)
			(layer "F.SilkS")
		)
		(fp_line
			(start 6.983984 -4.448302)
			(end 6.996176 -4.51739)
			(stroke
				(width 0.1)
				(type default)
			)
			(layer "F.SilkS")
		)
		(fp_line
			(start 6.996176 -4.51739)
			(end 5.64134 -3.217926)
			(stroke
				(width 0.1)
				(type default)
			)
			(layer "F.SilkS")
		)
		(fp_line
			(start 6.996176 -4.51739)
			(end 5.64134 -3.217926)
			(stroke
				(width 0.1)
				(type default)
			)
			(layer "F.SilkS")
		)
		(fp_line
			(start 6.996176 -4.51739)
			(end 7.008368 -4.586986)
			(stroke
				(width 0.1)
				(type default)
			)
			(layer "F.SilkS")
		)
		(fp_line
			(start 6.996176 -4.51739)
			(end 7.008368 -4.586986)
			(stroke
				(width 0.1)
				(type default)
			)
			(layer "F.SilkS")
		)
		(fp_line
			(start 7.008368 -4.586986)
			(end 5.653532 -3.287268)
			(stroke
				(width 0.1)
				(type default)
			)
			(layer "F.SilkS")
		)
		(fp_line
			(start 7.008368 -4.586986)
			(end 5.653532 -3.287268)
			(stroke
				(width 0.1)
				(type default)
			)
			(layer "F.SilkS")
		)
		(fp_line
			(start 7.008368 -4.586986)
			(end 7.02056 -4.656328)
			(stroke
				(width 0.1)
				(type default)
			)
			(layer "F.SilkS")
		)
		(fp_line
			(start 7.008368 -4.586986)
			(end 7.02056 -4.656328)
			(stroke
				(width 0.1)
				(type default)
			)
			(layer "F.SilkS")
		)
		(fp_line
			(start 7.016242 -5.171694)
			(end 5.775198 -3.98145)
			(stroke
				(width 0.1)
				(type default)
			)
			(layer "F.SilkS")
		)
		(fp_line
			(start 7.016242 -5.171694)
			(end 5.775198 -3.98145)
			(stroke
				(width 0.1)
				(type default)
			)
			(layer "F.SilkS")
		)
		(fp_line
			(start 7.016242 -5.171694)
			(end 6.956044 -5.171694)
			(stroke
				(width 0.1)
				(type default)
			)
			(layer "F.SilkS")
		)
		(fp_line
			(start 7.016242 -5.171694)
			(end 6.956044 -5.171694)
			(stroke
				(width 0.1)
				(type default)
			)
			(layer "F.SilkS")
		)
		(fp_line
			(start 7.02056 -4.656328)
			(end 5.665724 -3.35661)
			(stroke
				(width 0.1)
				(type default)
			)
			(layer "F.SilkS")
		)
		(fp_line
			(start 7.02056 -4.656328)
			(end 5.665724 -3.35661)
			(stroke
				(width 0.1)
				(type default)
			)
			(layer "F.SilkS")
		)
		(fp_line
			(start 7.02056 -4.656328)
			(end 7.032752 -4.725924)
			(stroke
				(width 0.1)
				(type default)
			)
			(layer "F.SilkS")
		)
		(fp_line
			(start 7.02056 -4.656328)
			(end 7.032752 -4.725924)
			(stroke
				(width 0.1)
				(type default)
			)
			(layer "F.SilkS")
		)
		(fp_line
			(start 7.032752 -4.725924)
			(end 5.677662 -3.425952)
			(stroke
				(width 0.1)
				(type default)
			)
			(layer "F.SilkS")
		)
		(fp_line
			(start 7.032752 -4.725924)
			(end 5.677662 -3.425952)
			(stroke
				(width 0.1)
				(type default)
			)
			(layer "F.SilkS")
		)
		(fp_line
			(start 7.032752 -4.725924)
			(end 7.04469 -4.795012)
			(stroke
				(width 0.1)
				(type default)
			)
			(layer "F.SilkS")
		)
		(fp_line
			(start 7.032752 -4.725924)
			(end 7.04469 -4.795012)
			(stroke
				(width 0.1)
				(type default)
			)
			(layer "F.SilkS")
		)
		(fp_line
			(start 7.04469 -4.795012)
			(end 5.690108 -3.495548)
			(stroke
				(width 0.1)
				(type default)
			)
			(layer "F.SilkS")
		)
		(fp_line
			(start 7.04469 -4.795012)
			(end 5.690108 -3.495548)
			(stroke
				(width 0.1)
				(type default)
			)
			(layer "F.SilkS")
		)
		(fp_line
			(start 7.04469 -4.795012)
			(end 7.057136 -4.864354)
			(stroke
				(width 0.1)
				(type default)
			)
			(layer "F.SilkS")
		)
		(fp_line
			(start 7.04469 -4.795012)
			(end 7.057136 -4.864354)
			(stroke
				(width 0.1)
				(type default)
			)
			(layer "F.SilkS")
		)
		(fp_line
			(start 7.047992 -0.816102)
			(end 9.318752 -2.994406)
			(stroke
				(width 0.1)
				(type default)
			)
			(layer "F.SilkS")
		)
		(fp_line
			(start 7.047992 -0.816102)
			(end 9.318752 -2.994406)
			(stroke
				(width 0.1)
				(type default)
			)
			(layer "F.SilkS")
		)
		(fp_line
			(start 7.057136 -4.864354)
			(end 5.7023 -3.56489)
			(stroke
				(width 0.1)
				(type default)
			)
			(layer "F.SilkS")
		)
		(fp_line
			(start 7.057136 -4.864354)
			(end 5.7023 -3.56489)
			(stroke
				(width 0.1)
				(type default)
			)
			(layer "F.SilkS")
		)
		(fp_line
			(start 7.057136 -4.864354)
			(end 7.069328 -4.93395)
			(stroke
				(width 0.1)
				(type default)
			)
			(layer "F.SilkS")
		)
		(fp_line
			(start 7.057136 -4.864354)
			(end 7.069328 -4.93395)
			(stroke
				(width 0.1)
				(type default)
			)
			(layer "F.SilkS")
		)
		(fp_line
			(start 7.069328 -4.93395)
			(end 5.714238 -3.634232)
			(stroke
				(width 0.1)
				(type default)
			)
			(layer "F.SilkS")
		)
		(fp_line
			(start 7.069328 -4.93395)
			(end 5.714238 -3.634232)
			(stroke
				(width 0.1)
				(type default)
			)
			(layer "F.SilkS")
		)
		(fp_line
			(start 7.069328 -4.93395)
			(end 7.081266 -5.003292)
			(stroke
				(width 0.1)
				(type default)
			)
			(layer "F.SilkS")
		)
		(fp_line
			(start 7.069328 -4.93395)
			(end 7.081266 -5.003292)
			(stroke
				(width 0.1)
				(type default)
			)
			(layer "F.SilkS")
		)
		(fp_line
			(start 7.07644 -5.171694)
			(end 5.763006 -3.911854)
			(stroke
				(width 0.1)
				(type default)
			)
			(layer "F.SilkS")
		)
		(fp_line
			(start 7.07644 -5.171694)
			(end 5.763006 -3.911854)
			(stroke
				(width 0.1)
				(type default)
			)
			(layer "F.SilkS")
		)
		(fp_line
			(start 7.07644 -5.171694)
			(end 7.016242 -5.171694)
			(stroke
				(width 0.1)
				(type default)
			)
			(layer "F.SilkS")
		)
		(fp_line
			(start 7.07644 -5.171694)
			(end 7.016242 -5.171694)
			(stroke
				(width 0.1)
				(type default)
			)
			(layer "F.SilkS")
		)
		(fp_line
			(start 7.081266 -5.003292)
			(end 5.72643 -3.703828)
			(stroke
				(width 0.1)
				(type default)
			)
			(layer "F.SilkS")
		)
		(fp_line
			(start 7.081266 -5.003292)
			(end 5.72643 -3.703828)
			(stroke
				(width 0.1)
				(type default)
			)
			(layer "F.SilkS")
		)
		(fp_line
			(start 7.081266 -5.003292)
			(end 7.093458 -5.072888)
			(stroke
				(width 0.1)
				(type default)
			)
			(layer "F.SilkS")
		)
		(fp_line
			(start 7.081266 -5.003292)
			(end 7.093458 -5.072888)
			(stroke
				(width 0.1)
				(type default)
			)
			(layer "F.SilkS")
		)
		(fp_line
			(start 7.093458 -5.072888)
			(end 5.738876 -3.772916)
			(stroke
				(width 0.1)
				(type default)
			)
			(layer "F.SilkS")
		)
		(fp_line
			(start 7.093458 -5.072888)
			(end 5.738876 -3.772916)
			(stroke
				(width 0.1)
				(type default)
			)
			(layer "F.SilkS")
		)
		(fp_line
			(start 7.093458 -5.072888)
			(end 7.10565 -5.141976)
			(stroke
				(width 0.1)
				(type default)
			)
			(layer "F.SilkS")
		)
		(fp_line
			(start 7.093458 -5.072888)
			(end 7.10565 -5.141976)
			(stroke
				(width 0.1)
				(type default)
			)
			(layer "F.SilkS")
		)
		(fp_line
			(start 7.10565 -5.141976)
			(end 5.751068 -3.842512)
			(stroke
				(width 0.1)
				(type default)
			)
			(layer "F.SilkS")
		)
		(fp_line
			(start 7.10565 -5.141976)
			(end 5.751068 -3.842512)
			(stroke
				(width 0.1)
				(type default)
			)
			(layer "F.SilkS")
		)
		(fp_line
			(start 7.10565 -5.141976)
			(end 7.110984 -5.171694)
			(stroke
				(width 0.1)
				(type default)
			)
			(layer "F.SilkS")
		)
		(fp_line
			(start 7.10565 -5.141976)
			(end 7.110984 -5.171694)
			(stroke
				(width 0.1)
				(type default)
			)
			(layer "F.SilkS")
		)
		(fp_line
			(start 7.110984 -5.171694)
			(end 7.07644 -5.171694)
			(stroke
				(width 0.1)
				(type default)
			)
			(layer "F.SilkS")
		)
		(fp_line
			(start 7.110984 -5.171694)
			(end 7.07644 -5.171694)
			(stroke
				(width 0.1)
				(type default)
			)
			(layer "F.SilkS")
		)
		(fp_line
			(start 7.11454 -0.822198)
			(end 9.30656 -2.925064)
			(stroke
				(width 0.1)
				(type default)
			)
			(layer "F.SilkS")
		)
		(fp_line
			(start 7.11454 -0.822198)
			(end 9.30656 -2.925064)
			(stroke
				(width 0.1)
				(type default)
			)
			(layer "F.SilkS")
		)
		(fp_line
			(start 7.196582 -0.84328)
			(end 9.294368 -2.855468)
			(stroke
				(width 0.1)
				(type default)
			)
			(layer "F.SilkS")
		)
		(fp_line
			(start 7.196582 -0.84328)
			(end 9.294368 -2.855468)
			(stroke
				(width 0.1)
				(type default)
			)
			(layer "F.SilkS")
		)
		(fp_line
			(start 7.281418 -0.866648)
			(end 9.281922 -2.786126)
			(stroke
				(width 0.1)
				(type default)
			)
			(layer "F.SilkS")
		)
		(fp_line
			(start 7.281418 -0.866648)
			(end 9.281922 -2.786126)
			(stroke
				(width 0.1)
				(type default)
			)
			(layer "F.SilkS")
		)
		(fp_line
			(start 7.366 -0.890016)
			(end 9.269984 -2.716784)
			(stroke
				(width 0.1)
				(type default)
			)
			(layer "F.SilkS")
		)
		(fp_line
			(start 7.366 -0.890016)
			(end 9.269984 -2.716784)
			(stroke
				(width 0.1)
				(type default)
			)
			(layer "F.SilkS")
		)
		(fp_line
			(start 7.464298 -0.926846)
			(end 9.257792 -2.647188)
			(stroke
				(width 0.1)
				(type default)
			)
			(layer "F.SilkS")
		)
		(fp_line
			(start 7.464298 -0.926846)
			(end 9.257792 -2.647188)
			(stroke
				(width 0.1)
				(type default)
			)
			(layer "F.SilkS")
		)
		(fp_line
			(start 7.583678 -0.983488)
			(end 9.2456 -2.577592)
			(stroke
				(width 0.1)
				(type default)
			)
			(layer "F.SilkS")
		)
		(fp_line
			(start 7.583678 -0.983488)
			(end 9.2456 -2.577592)
			(stroke
				(width 0.1)
				(type default)
			)
			(layer "F.SilkS")
		)
		(fp_line
			(start 7.737348 -1.07315)
			(end 9.233408 -2.508504)
			(stroke
				(width 0.1)
				(type default)
			)
			(layer "F.SilkS")
		)
		(fp_line
			(start 7.737348 -1.07315)
			(end 9.233408 -2.508504)
			(stroke
				(width 0.1)
				(type default)
			)
			(layer "F.SilkS")
		)
		(fp_line
			(start 7.82066 -0.882904)
			(end 7.839456 -0.882904)
			(stroke
				(width 0.1)
				(type default)
			)
			(layer "F.SilkS")
		)
		(fp_line
			(start 7.82066 -0.882904)
			(end 7.839456 -0.882904)
			(stroke
				(width 0.1)
				(type default)
			)
			(layer "F.SilkS")
		)
		(fp_line
			(start 7.828788 -0.930148)
			(end 7.82066 -0.882904)
			(stroke
				(width 0.1)
				(type default)
			)
			(layer "F.SilkS")
		)
		(fp_line
			(start 7.828788 -0.930148)
			(end 7.82066 -0.882904)
			(stroke
				(width 0.1)
				(type default)
			)
			(layer "F.SilkS")
		)
		(fp_line
			(start 7.828788 -0.930148)
			(end 9.18464 -2.230882)
			(stroke
				(width 0.1)
				(type default)
			)
			(layer "F.SilkS")
		)
		(fp_line
			(start 7.828788 -0.930148)
			(end 9.18464 -2.230882)
			(stroke
				(width 0.1)
				(type default)
			)
			(layer "F.SilkS")
		)
		(fp_line
			(start 7.839456 -0.882904)
			(end 7.899908 -0.882904)
			(stroke
				(width 0.1)
				(type default)
			)
			(layer "F.SilkS")
		)
		(fp_line
			(start 7.839456 -0.882904)
			(end 7.899908 -0.882904)
			(stroke
				(width 0.1)
				(type default)
			)
			(layer "F.SilkS")
		)
		(fp_line
			(start 7.839456 -0.882904)
			(end 9.172194 -2.161286)
			(stroke
				(width 0.1)
				(type default)
			)
			(layer "F.SilkS")
		)
		(fp_line
			(start 7.839456 -0.882904)
			(end 9.172194 -2.161286)
			(stroke
				(width 0.1)
				(type default)
			)
			(layer "F.SilkS")
		)
		(fp_line
			(start 7.84098 -0.999744)
			(end 7.828788 -0.930148)
			(stroke
				(width 0.1)
				(type default)
			)
			(layer "F.SilkS")
		)
		(fp_line
			(start 7.84098 -0.999744)
			(end 7.828788 -0.930148)
			(stroke
				(width 0.1)
				(type default)
			)
			(layer "F.SilkS")
		)
		(fp_line
			(start 7.84098 -0.999744)
			(end 9.196832 -2.300224)
			(stroke
				(width 0.1)
				(type default)
			)
			(layer "F.SilkS")
		)
		(fp_line
			(start 7.84098 -0.999744)
			(end 9.196832 -2.300224)
			(stroke
				(width 0.1)
				(type default)
			)
			(layer "F.SilkS")
		)
		(fp_line
			(start 7.852918 -1.068832)
			(end 7.84098 -0.999744)
			(stroke
				(width 0.1)
				(type default)
			)
			(layer "F.SilkS")
		)
		(fp_line
			(start 7.852918 -1.068832)
			(end 7.84098 -0.999744)
			(stroke
				(width 0.1)
				(type default)
			)
			(layer "F.SilkS")
		)
		(fp_line
			(start 7.852918 -1.068832)
			(end 9.209024 -2.369566)
			(stroke
				(width 0.1)
				(type default)
			)
			(layer "F.SilkS")
		)
		(fp_line
			(start 7.852918 -1.068832)
			(end 9.209024 -2.369566)
			(stroke
				(width 0.1)
				(type default)
			)
			(layer "F.SilkS")
		)
		(fp_line
			(start 7.865364 -1.138428)
			(end 7.852918 -1.068832)
			(stroke
				(width 0.1)
				(type default)
			)
			(layer "F.SilkS")
		)
		(fp_line
			(start 7.865364 -1.138428)
			(end 7.852918 -1.068832)
			(stroke
				(width 0.1)
				(type default)
			)
			(layer "F.SilkS")
		)
		(fp_line
			(start 7.865364 -1.138428)
			(end 9.220962 -2.438908)
			(stroke
				(width 0.1)
				(type default)
			)
			(layer "F.SilkS")
		)
		(fp_line
			(start 7.865364 -1.138428)
			(end 9.220962 -2.438908)
			(stroke
				(width 0.1)
				(type default)
			)
			(layer "F.SilkS")
		)
		(fp_line
			(start 7.899908 -0.882904)
			(end 7.960106 -0.882904)
			(stroke
				(width 0.1)
				(type default)
			)
			(layer "F.SilkS")
		)
		(fp_line
			(start 7.899908 -0.882904)
			(end 7.960106 -0.882904)
			(stroke
				(width 0.1)
				(type default)
			)
			(layer "F.SilkS")
		)
		(fp_line
			(start 7.899908 -0.882904)
			(end 9.160002 -2.091944)
			(stroke
				(width 0.1)
				(type default)
			)
			(layer "F.SilkS")
		)
		(fp_line
			(start 7.899908 -0.882904)
			(end 9.160002 -2.091944)
			(stroke
				(width 0.1)
				(type default)
			)
			(layer "F.SilkS")
		)
		(fp_line
			(start 7.936484 -2.187702)
			(end 9.42848 -3.618992)
			(stroke
				(width 0.1)
				(type default)
			)
			(layer "F.SilkS")
		)
		(fp_line
			(start 7.936484 -2.187702)
			(end 9.42848 -3.618992)
			(stroke
				(width 0.1)
				(type default)
			)
			(layer "F.SilkS")
		)
		(fp_line
			(start 7.960106 -0.882904)
			(end 8.02005 -0.882904)
			(stroke
				(width 0.1)
				(type default)
			)
			(layer "F.SilkS")
		)
		(fp_line
			(start 7.960106 -0.882904)
			(end 8.02005 -0.882904)
			(stroke
				(width 0.1)
				(type default)
			)
			(layer "F.SilkS")
		)
		(fp_line
			(start 7.960106 -0.882904)
			(end 9.148064 -2.022602)
			(stroke
				(width 0.1)
				(type default)
			)
			(layer "F.SilkS")
		)
		(fp_line
			(start 7.960106 -0.882904)
			(end 9.148064 -2.022602)
			(stroke
				(width 0.1)
				(type default)
			)
			(layer "F.SilkS")
		)
		(fp_line
			(start 8.002778 -2.30886)
			(end 9.440672 -3.688334)
			(stroke
				(width 0.1)
				(type default)
			)
			(layer "F.SilkS")
		)
		(fp_line
			(start 8.002778 -2.30886)
			(end 9.440672 -3.688334)
			(stroke
				(width 0.1)
				(type default)
			)
			(layer "F.SilkS")
		)
		(fp_line
			(start 8.02005 -0.882904)
			(end 8.080248 -0.882904)
			(stroke
				(width 0.1)
				(type default)
			)
			(layer "F.SilkS")
		)
		(fp_line
			(start 8.02005 -0.882904)
			(end 8.080248 -0.882904)
			(stroke
				(width 0.1)
				(type default)
			)
			(layer "F.SilkS")
		)
		(fp_line
			(start 8.02005 -0.882904)
			(end 9.135872 -1.953006)
			(stroke
				(width 0.1)
				(type default)
			)
			(layer "F.SilkS")
		)
		(fp_line
			(start 8.02005 -0.882904)
			(end 9.135872 -1.953006)
			(stroke
				(width 0.1)
				(type default)
			)
			(layer "F.SilkS")
		)
		(fp_line
			(start 8.04799 -2.410206)
			(end 9.452864 -3.75793)
			(stroke
				(width 0.1)
				(type default)
			)
			(layer "F.SilkS")
		)
		(fp_line
			(start 8.04799 -2.410206)
			(end 9.452864 -3.75793)
			(stroke
				(width 0.1)
				(type default)
			)
			(layer "F.SilkS")
		)
		(fp_line
			(start 8.078724 -2.497328)
			(end 9.465056 -3.827526)
			(stroke
				(width 0.1)
				(type default)
			)
			(layer "F.SilkS")
		)
		(fp_line
			(start 8.078724 -2.497328)
			(end 9.465056 -3.827526)
			(stroke
				(width 0.1)
				(type default)
			)
			(layer "F.SilkS")
		)
		(fp_line
			(start 8.080248 -0.882904)
			(end 8.140446 -0.882904)
			(stroke
				(width 0.1)
				(type default)
			)
			(layer "F.SilkS")
		)
		(fp_line
			(start 8.080248 -0.882904)
			(end 8.140446 -0.882904)
			(stroke
				(width 0.1)
				(type default)
			)
			(layer "F.SilkS")
		)
		(fp_line
			(start 8.080248 -0.882904)
			(end 9.12368 -1.883664)
			(stroke
				(width 0.1)
				(type default)
			)
			(layer "F.SilkS")
		)
		(fp_line
			(start 8.080248 -0.882904)
			(end 9.12368 -1.883664)
			(stroke
				(width 0.1)
				(type default)
			)
			(layer "F.SilkS")
		)
		(fp_line
			(start 8.140446 -0.882904)
			(end 8.200644 -0.882904)
			(stroke
				(width 0.1)
				(type default)
			)
			(layer "F.SilkS")
		)
		(fp_line
			(start 8.140446 -0.882904)
			(end 8.200644 -0.882904)
			(stroke
				(width 0.1)
				(type default)
			)
			(layer "F.SilkS")
		)
		(fp_line
			(start 8.140446 -0.882904)
			(end 9.111234 -1.814322)
			(stroke
				(width 0.1)
				(type default)
			)
			(layer "F.SilkS")
		)
		(fp_line
			(start 8.140446 -0.882904)
			(end 9.111234 -1.814322)
			(stroke
				(width 0.1)
				(type default)
			)
			(layer "F.SilkS")
		)
		(fp_line
			(start 8.18261 -2.943352)
			(end 8.170418 -2.87401)
			(stroke
				(width 0.1)
				(type default)
			)
			(layer "F.SilkS")
		)
		(fp_line
			(start 8.18261 -2.943352)
			(end 8.170418 -2.87401)
			(stroke
				(width 0.1)
				(type default)
			)
			(layer "F.SilkS")
		)
		(fp_line
			(start 8.194802 -3.012694)
			(end 8.18261 -2.943352)
			(stroke
				(width 0.1)
				(type default)
			)
			(layer "F.SilkS")
		)
		(fp_line
			(start 8.194802 -3.012694)
			(end 8.18261 -2.943352)
			(stroke
				(width 0.1)
				(type default)
			)
			(layer "F.SilkS")
		)
		(fp_line
			(start 8.200644 -0.882904)
			(end 8.260842 -0.882904)
			(stroke
				(width 0.1)
				(type default)
			)
			(layer "F.SilkS")
		)
		(fp_line
			(start 8.200644 -0.882904)
			(end 8.260842 -0.882904)
			(stroke
				(width 0.1)
				(type default)
			)
			(layer "F.SilkS")
		)
		(fp_line
			(start 8.200644 -0.882904)
			(end 9.099042 -1.744726)
			(stroke
				(width 0.1)
				(type default)
			)
			(layer "F.SilkS")
		)
		(fp_line
			(start 8.200644 -0.882904)
			(end 9.099042 -1.744726)
			(stroke
				(width 0.1)
				(type default)
			)
			(layer "F.SilkS")
		)
		(fp_line
			(start 8.206994 -3.08229)
			(end 8.194802 -3.012694)
			(stroke
				(width 0.1)
				(type default)
			)
			(layer "F.SilkS")
		)
		(fp_line
			(start 8.206994 -3.08229)
			(end 8.194802 -3.012694)
			(stroke
				(width 0.1)
				(type default)
			)
			(layer "F.SilkS")
		)
		(fp_line
			(start 8.219186 -3.151378)
			(end 8.206994 -3.08229)
			(stroke
				(width 0.1)
				(type default)
			)
			(layer "F.SilkS")
		)
		(fp_line
			(start 8.219186 -3.151378)
			(end 8.206994 -3.08229)
			(stroke
				(width 0.1)
				(type default)
			)
			(layer "F.SilkS")
		)
		(fp_line
			(start 8.231378 -3.22072)
			(end 8.219186 -3.151378)
			(stroke
				(width 0.1)
				(type default)
			)
			(layer "F.SilkS")
		)
		(fp_line
			(start 8.231378 -3.22072)
			(end 8.219186 -3.151378)
			(stroke
				(width 0.1)
				(type default)
			)
			(layer "F.SilkS")
		)
		(fp_line
			(start 8.24357 -3.290316)
			(end 8.231378 -3.22072)
			(stroke
				(width 0.1)
				(type default)
			)
			(layer "F.SilkS")
		)
		(fp_line
			(start 8.24357 -3.290316)
			(end 8.231378 -3.22072)
			(stroke
				(width 0.1)
				(type default)
			)
			(layer "F.SilkS")
		)
		(fp_line
			(start 8.255762 -3.359658)
			(end 8.24357 -3.290316)
			(stroke
				(width 0.1)
				(type default)
			)
			(layer "F.SilkS")
		)
		(fp_line
			(start 8.255762 -3.359658)
			(end 8.24357 -3.290316)
			(stroke
				(width 0.1)
				(type default)
			)
			(layer "F.SilkS")
		)
		(fp_line
			(start 8.260842 -0.882904)
			(end 8.320786 -0.882904)
			(stroke
				(width 0.1)
				(type default)
			)
			(layer "F.SilkS")
		)
		(fp_line
			(start 8.260842 -0.882904)
			(end 8.320786 -0.882904)
			(stroke
				(width 0.1)
				(type default)
			)
			(layer "F.SilkS")
		)
		(fp_line
			(start 8.260842 -0.882904)
			(end 9.087104 -1.675384)
			(stroke
				(width 0.1)
				(type default)
			)
			(layer "F.SilkS")
		)
		(fp_line
			(start 8.260842 -0.882904)
			(end 9.087104 -1.675384)
			(stroke
				(width 0.1)
				(type default)
			)
			(layer "F.SilkS")
		)
		(fp_line
			(start 8.2677 -3.429)
			(end 8.255762 -3.359658)
			(stroke
				(width 0.1)
				(type default)
			)
			(layer "F.SilkS")
		)
		(fp_line
			(start 8.2677 -3.429)
			(end 8.255762 -3.359658)
			(stroke
				(width 0.1)
				(type default)
			)
			(layer "F.SilkS")
		)
		(fp_line
			(start 8.279892 -3.498342)
			(end 8.2677 -3.429)
			(stroke
				(width 0.1)
				(type default)
			)
			(layer "F.SilkS")
		)
		(fp_line
			(start 8.279892 -3.498342)
			(end 8.2677 -3.429)
			(stroke
				(width 0.1)
				(type default)
			)
			(layer "F.SilkS")
		)
		(fp_line
			(start 8.292084 -3.567684)
			(end 8.279892 -3.498342)
			(stroke
				(width 0.1)
				(type default)
			)
			(layer "F.SilkS")
		)
		(fp_line
			(start 8.292084 -3.567684)
			(end 8.279892 -3.498342)
			(stroke
				(width 0.1)
				(type default)
			)
			(layer "F.SilkS")
		)
		(fp_line
			(start 8.304276 -3.63728)
			(end 8.292084 -3.567684)
			(stroke
				(width 0.1)
				(type default)
			)
			(layer "F.SilkS")
		)
		(fp_line
			(start 8.304276 -3.63728)
			(end 8.292084 -3.567684)
			(stroke
				(width 0.1)
				(type default)
			)
			(layer "F.SilkS")
		)
		(fp_line
			(start 8.316468 -3.706368)
			(end 8.304276 -3.63728)
			(stroke
				(width 0.1)
				(type default)
			)
			(layer "F.SilkS")
		)
		(fp_line
			(start 8.316468 -3.706368)
			(end 8.304276 -3.63728)
			(stroke
				(width 0.1)
				(type default)
			)
			(layer "F.SilkS")
		)
		(fp_line
			(start 8.320786 -0.882904)
			(end 8.381238 -0.882904)
			(stroke
				(width 0.1)
				(type default)
			)
			(layer "F.SilkS")
		)
		(fp_line
			(start 8.320786 -0.882904)
			(end 8.381238 -0.882904)
			(stroke
				(width 0.1)
				(type default)
			)
			(layer "F.SilkS")
		)
		(fp_line
			(start 8.320786 -0.882904)
			(end 9.074912 -1.606296)
			(stroke
				(width 0.1)
				(type default)
			)
			(layer "F.SilkS")
		)
		(fp_line
			(start 8.320786 -0.882904)
			(end 9.074912 -1.606296)
			(stroke
				(width 0.1)
				(type default)
			)
			(layer "F.SilkS")
		)
		(fp_line
			(start 8.32866 -3.77571)
			(end 8.316468 -3.706368)
			(stroke
				(width 0.1)
				(type default)
			)
			(layer "F.SilkS")
		)
		(fp_line
			(start 8.32866 -3.77571)
			(end 8.316468 -3.706368)
			(stroke
				(width 0.1)
				(type default)
			)
			(layer "F.SilkS")
		)
		(fp_line
			(start 8.340852 -3.845306)
			(end 8.32866 -3.77571)
			(stroke
				(width 0.1)
				(type default)
			)
			(layer "F.SilkS")
		)
		(fp_line
			(start 8.340852 -3.845306)
			(end 8.32866 -3.77571)
			(stroke
				(width 0.1)
				(type default)
			)
			(layer "F.SilkS")
		)
		(fp_line
			(start 8.35279 -3.914648)
			(end 8.340852 -3.845306)
			(stroke
				(width 0.1)
				(type default)
			)
			(layer "F.SilkS")
		)
		(fp_line
			(start 8.35279 -3.914648)
			(end 8.340852 -3.845306)
			(stroke
				(width 0.1)
				(type default)
			)
			(layer "F.SilkS")
		)
		(fp_line
			(start 8.365236 -3.98399)
			(end 8.35279 -3.914648)
			(stroke
				(width 0.1)
				(type default)
			)
			(layer "F.SilkS")
		)
		(fp_line
			(start 8.365236 -3.98399)
			(end 8.35279 -3.914648)
			(stroke
				(width 0.1)
				(type default)
			)
			(layer "F.SilkS")
		)
		(fp_line
			(start 8.377174 -4.053332)
			(end 8.365236 -3.98399)
			(stroke
				(width 0.1)
				(type default)
			)
			(layer "F.SilkS")
		)
		(fp_line
			(start 8.377174 -4.053332)
			(end 8.365236 -3.98399)
			(stroke
				(width 0.1)
				(type default)
			)
			(layer "F.SilkS")
		)
		(fp_line
			(start 8.381238 -0.882904)
			(end 8.441182 -0.882904)
			(stroke
				(width 0.1)
				(type default)
			)
			(layer "F.SilkS")
		)
		(fp_line
			(start 8.381238 -0.882904)
			(end 8.441182 -0.882904)
			(stroke
				(width 0.1)
				(type default)
			)
			(layer "F.SilkS")
		)
		(fp_line
			(start 8.381238 -0.882904)
			(end 9.062466 -1.5367)
			(stroke
				(width 0.1)
				(type default)
			)
			(layer "F.SilkS")
		)
		(fp_line
			(start 8.381238 -0.882904)
			(end 9.062466 -1.5367)
			(stroke
				(width 0.1)
				(type default)
			)
			(layer "F.SilkS")
		)
		(fp_line
			(start 8.389366 -4.122674)
			(end 8.377174 -4.053332)
			(stroke
				(width 0.1)
				(type default)
			)
			(layer "F.SilkS")
		)
		(fp_line
			(start 8.389366 -4.122674)
			(end 8.377174 -4.053332)
			(stroke
				(width 0.1)
				(type default)
			)
			(layer "F.SilkS")
		)
		(fp_line
			(start 8.401558 -4.19227)
			(end 8.389366 -4.122674)
			(stroke
				(width 0.1)
				(type default)
			)
			(layer "F.SilkS")
		)
		(fp_line
			(start 8.401558 -4.19227)
			(end 8.389366 -4.122674)
			(stroke
				(width 0.1)
				(type default)
			)
			(layer "F.SilkS")
		)
		(fp_line
			(start 8.41375 -4.261612)
			(end 8.401558 -4.19227)
			(stroke
				(width 0.1)
				(type default)
			)
			(layer "F.SilkS")
		)
		(fp_line
			(start 8.41375 -4.261612)
			(end 8.401558 -4.19227)
			(stroke
				(width 0.1)
				(type default)
			)
			(layer "F.SilkS")
		)
		(fp_line
			(start 8.425942 -4.3307)
			(end 8.41375 -4.261612)
			(stroke
				(width 0.1)
				(type default)
			)
			(layer "F.SilkS")
		)
		(fp_line
			(start 8.425942 -4.3307)
			(end 8.41375 -4.261612)
			(stroke
				(width 0.1)
				(type default)
			)
			(layer "F.SilkS")
		)
		(fp_line
			(start 8.43788 -4.400296)
			(end 8.425942 -4.3307)
			(stroke
				(width 0.1)
				(type default)
			)
			(layer "F.SilkS")
		)
		(fp_line
			(start 8.43788 -4.400296)
			(end 8.425942 -4.3307)
			(stroke
				(width 0.1)
				(type default)
			)
			(layer "F.SilkS")
		)
		(fp_line
			(start 8.441182 -0.882904)
			(end 8.50138 -0.882904)
			(stroke
				(width 0.1)
				(type default)
			)
			(layer "F.SilkS")
		)
		(fp_line
			(start 8.441182 -0.882904)
			(end 8.50138 -0.882904)
			(stroke
				(width 0.1)
				(type default)
			)
			(layer "F.SilkS")
		)
		(fp_line
			(start 8.441182 -0.882904)
			(end 9.050274 -1.467104)
			(stroke
				(width 0.1)
				(type default)
			)
			(layer "F.SilkS")
		)
		(fp_line
			(start 8.441182 -0.882904)
			(end 9.050274 -1.467104)
			(stroke
				(width 0.1)
				(type default)
			)
			(layer "F.SilkS")
		)
		(fp_line
			(start 8.450326 -4.469638)
			(end 8.43788 -4.400296)
			(stroke
				(width 0.1)
				(type default)
			)
			(layer "F.SilkS")
		)
		(fp_line
			(start 8.450326 -4.469638)
			(end 8.43788 -4.400296)
			(stroke
				(width 0.1)
				(type default)
			)
			(layer "F.SilkS")
		)
		(fp_line
			(start 8.450326 -4.469638)
			(end 8.462264 -4.53898)
			(stroke
				(width 0.1)
				(type default)
			)
			(layer "F.SilkS")
		)
		(fp_line
			(start 8.450326 -4.469638)
			(end 8.462264 -4.53898)
			(stroke
				(width 0.1)
				(type default)
			)
			(layer "F.SilkS")
		)
		(fp_line
			(start 8.462264 -4.53898)
			(end 8.474456 -4.608322)
			(stroke
				(width 0.1)
				(type default)
			)
			(layer "F.SilkS")
		)
		(fp_line
			(start 8.462264 -4.53898)
			(end 8.474456 -4.608322)
			(stroke
				(width 0.1)
				(type default)
			)
			(layer "F.SilkS")
		)
		(fp_line
			(start 8.474456 -4.608322)
			(end 8.486648 -4.677664)
			(stroke
				(width 0.1)
				(type default)
			)
			(layer "F.SilkS")
		)
		(fp_line
			(start 8.474456 -4.608322)
			(end 8.486648 -4.677664)
			(stroke
				(width 0.1)
				(type default)
			)
			(layer "F.SilkS")
		)
		(fp_line
			(start 8.486648 -4.677664)
			(end 8.49884 -4.74726)
			(stroke
				(width 0.1)
				(type default)
			)
			(layer "F.SilkS")
		)
		(fp_line
			(start 8.486648 -4.677664)
			(end 8.49884 -4.74726)
			(stroke
				(width 0.1)
				(type default)
			)
			(layer "F.SilkS")
		)
		(fp_line
			(start 8.49884 -4.74726)
			(end 8.511032 -4.816602)
			(stroke
				(width 0.1)
				(type default)
			)
			(layer "F.SilkS")
		)
		(fp_line
			(start 8.49884 -4.74726)
			(end 8.511032 -4.816602)
			(stroke
				(width 0.1)
				(type default)
			)
			(layer "F.SilkS")
		)
		(fp_line
			(start 8.50138 -0.882904)
			(end 8.561578 -0.882904)
			(stroke
				(width 0.1)
				(type default)
			)
			(layer "F.SilkS")
		)
		(fp_line
			(start 8.50138 -0.882904)
			(end 8.561578 -0.882904)
			(stroke
				(width 0.1)
				(type default)
			)
			(layer "F.SilkS")
		)
		(fp_line
			(start 8.50138 -0.882904)
			(end 9.038082 -1.397762)
			(stroke
				(width 0.1)
				(type default)
			)
			(layer "F.SilkS")
		)
		(fp_line
			(start 8.50138 -0.882904)
			(end 9.038082 -1.397762)
			(stroke
				(width 0.1)
				(type default)
			)
			(layer "F.SilkS")
		)
		(fp_line
			(start 8.511032 -4.816602)
			(end 8.52297 -4.88569)
			(stroke
				(width 0.1)
				(type default)
			)
			(layer "F.SilkS")
		)
		(fp_line
			(start 8.511032 -4.816602)
			(end 8.52297 -4.88569)
			(stroke
				(width 0.1)
				(type default)
			)
			(layer "F.SilkS")
		)
		(fp_line
			(start 8.52297 -4.88569)
			(end 8.535416 -4.955286)
			(stroke
				(width 0.1)
				(type default)
			)
			(layer "F.SilkS")
		)
		(fp_line
			(start 8.52297 -4.88569)
			(end 8.535416 -4.955286)
			(stroke
				(width 0.1)
				(type default)
			)
			(layer "F.SilkS")
		)
		(fp_line
			(start 8.535416 -4.955286)
			(end 8.547608 -5.024628)
			(stroke
				(width 0.1)
				(type default)
			)
			(layer "F.SilkS")
		)
		(fp_line
			(start 8.535416 -4.955286)
			(end 8.547608 -5.024628)
			(stroke
				(width 0.1)
				(type default)
			)
			(layer "F.SilkS")
		)
		(fp_line
			(start 8.547608 -5.024628)
			(end 8.559546 -5.09397)
			(stroke
				(width 0.1)
				(type default)
			)
			(layer "F.SilkS")
		)
		(fp_line
			(start 8.547608 -5.024628)
			(end 8.559546 -5.09397)
			(stroke
				(width 0.1)
				(type default)
			)
			(layer "F.SilkS")
		)
		(fp_line
			(start 8.559546 -5.09397)
			(end 8.571738 -5.163312)
			(stroke
				(width 0.1)
				(type default)
			)
			(layer "F.SilkS")
		)
		(fp_line
			(start 8.559546 -5.09397)
			(end 8.571738 -5.163312)
			(stroke
				(width 0.1)
				(type default)
			)
			(layer "F.SilkS")
		)
		(fp_line
			(start 8.561578 -0.882904)
			(end 8.621522 -0.882904)
			(stroke
				(width 0.1)
				(type default)
			)
			(layer "F.SilkS")
		)
		(fp_line
			(start 8.561578 -0.882904)
			(end 8.621522 -0.882904)
			(stroke
				(width 0.1)
				(type default)
			)
			(layer "F.SilkS")
		)
		(fp_line
			(start 8.561578 -0.882904)
			(end 9.026144 -1.32842)
			(stroke
				(width 0.1)
				(type default)
			)
			(layer "F.SilkS")
		)
		(fp_line
			(start 8.561578 -0.882904)
			(end 9.026144 -1.32842)
			(stroke
				(width 0.1)
				(type default)
			)
			(layer "F.SilkS")
		)
		(fp_line
			(start 8.573262 -5.171694)
			(end 8.571738 -5.163312)
			(stroke
				(width 0.1)
				(type default)
			)
			(layer "F.SilkS")
		)
		(fp_line
			(start 8.573262 -5.171694)
			(end 8.571738 -5.163312)
			(stroke
				(width 0.1)
				(type default)
			)
			(layer "F.SilkS")
		)
		(fp_line
			(start 8.580374 -5.171694)
			(end 8.571738 -5.163312)
			(stroke
				(width 0.1)
				(type default)
			)
			(layer "F.SilkS")
		)
		(fp_line
			(start 8.580374 -5.171694)
			(end 8.571738 -5.163312)
			(stroke
				(width 0.1)
				(type default)
			)
			(layer "F.SilkS")
		)
		(fp_line
			(start 8.580374 -5.171694)
			(end 8.573262 -5.171694)
			(stroke
				(width 0.1)
				(type default)
			)
			(layer "F.SilkS")
		)
		(fp_line
			(start 8.580374 -5.171694)
			(end 8.573262 -5.171694)
			(stroke
				(width 0.1)
				(type default)
			)
			(layer "F.SilkS")
		)
		(fp_line
			(start 8.621522 -0.882904)
			(end 8.681974 -0.882904)
			(stroke
				(width 0.1)
				(type default)
			)
			(layer "F.SilkS")
		)
		(fp_line
			(start 8.621522 -0.882904)
			(end 8.681974 -0.882904)
			(stroke
				(width 0.1)
				(type default)
			)
			(layer "F.SilkS")
		)
		(fp_line
			(start 8.621522 -0.882904)
			(end 9.013952 -1.259078)
			(stroke
				(width 0.1)
				(type default)
			)
			(layer "F.SilkS")
		)
		(fp_line
			(start 8.621522 -0.882904)
			(end 9.013952 -1.259078)
			(stroke
				(width 0.1)
				(type default)
			)
			(layer "F.SilkS")
		)
		(fp_line
			(start 8.640572 -5.171694)
			(end 8.559546 -5.09397)
			(stroke
				(width 0.1)
				(type default)
			)
			(layer "F.SilkS")
		)
		(fp_line
			(start 8.640572 -5.171694)
			(end 8.559546 -5.09397)
			(stroke
				(width 0.1)
				(type default)
			)
			(layer "F.SilkS")
		)
		(fp_line
			(start 8.640572 -5.171694)
			(end 8.580374 -5.171694)
			(stroke
				(width 0.1)
				(type default)
			)
			(layer "F.SilkS")
		)
		(fp_line
			(start 8.640572 -5.171694)
			(end 8.580374 -5.171694)
			(stroke
				(width 0.1)
				(type default)
			)
			(layer "F.SilkS")
		)
		(fp_line
			(start 8.681974 -0.882904)
			(end 8.741918 -0.882904)
			(stroke
				(width 0.1)
				(type default)
			)
			(layer "F.SilkS")
		)
		(fp_line
			(start 8.681974 -0.882904)
			(end 8.741918 -0.882904)
			(stroke
				(width 0.1)
				(type default)
			)
			(layer "F.SilkS")
		)
		(fp_line
			(start 8.681974 -0.882904)
			(end 9.001506 -1.189482)
			(stroke
				(width 0.1)
				(type default)
			)
			(layer "F.SilkS")
		)
		(fp_line
			(start 8.681974 -0.882904)
			(end 9.001506 -1.189482)
			(stroke
				(width 0.1)
				(type default)
			)
			(layer "F.SilkS")
		)
		(fp_line
			(start 8.70077 -5.171694)
			(end 8.547608 -5.024628)
			(stroke
				(width 0.1)
				(type default)
			)
			(layer "F.SilkS")
		)
		(fp_line
			(start 8.70077 -5.171694)
			(end 8.547608 -5.024628)
			(stroke
				(width 0.1)
				(type default)
			)
			(layer "F.SilkS")
		)
		(fp_line
			(start 8.70077 -5.171694)
			(end 8.640572 -5.171694)
			(stroke
				(width 0.1)
				(type default)
			)
			(layer "F.SilkS")
		)
		(fp_line
			(start 8.70077 -5.171694)
			(end 8.640572 -5.171694)
			(stroke
				(width 0.1)
				(type default)
			)
			(layer "F.SilkS")
		)
		(fp_line
			(start 8.741918 -0.882904)
			(end 8.802116 -0.882904)
			(stroke
				(width 0.1)
				(type default)
			)
			(layer "F.SilkS")
		)
		(fp_line
			(start 8.741918 -0.882904)
			(end 8.802116 -0.882904)
			(stroke
				(width 0.1)
				(type default)
			)
			(layer "F.SilkS")
		)
		(fp_line
			(start 8.741918 -0.882904)
			(end 8.989314 -1.12014)
			(stroke
				(width 0.1)
				(type default)
			)
			(layer "F.SilkS")
		)
		(fp_line
			(start 8.741918 -0.882904)
			(end 8.989314 -1.12014)
			(stroke
				(width 0.1)
				(type default)
			)
			(layer "F.SilkS")
		)
		(fp_line
			(start 8.760968 -5.171694)
			(end 8.535416 -4.955286)
			(stroke
				(width 0.1)
				(type default)
			)
			(layer "F.SilkS")
		)
		(fp_line
			(start 8.760968 -5.171694)
			(end 8.535416 -4.955286)
			(stroke
				(width 0.1)
				(type default)
			)
			(layer "F.SilkS")
		)
		(fp_line
			(start 8.760968 -5.171694)
			(end 8.70077 -5.171694)
			(stroke
				(width 0.1)
				(type default)
			)
			(layer "F.SilkS")
		)
		(fp_line
			(start 8.760968 -5.171694)
			(end 8.70077 -5.171694)
			(stroke
				(width 0.1)
				(type default)
			)
			(layer "F.SilkS")
		)
		(fp_line
			(start 8.802116 -0.882904)
			(end 8.862314 -0.882904)
			(stroke
				(width 0.1)
				(type default)
			)
			(layer "F.SilkS")
		)
		(fp_line
			(start 8.802116 -0.882904)
			(end 8.862314 -0.882904)
			(stroke
				(width 0.1)
				(type default)
			)
			(layer "F.SilkS")
		)
		(fp_line
			(start 8.802116 -0.882904)
			(end 8.977122 -1.050798)
			(stroke
				(width 0.1)
				(type default)
			)
			(layer "F.SilkS")
		)
		(fp_line
			(start 8.802116 -0.882904)
			(end 8.977122 -1.050798)
			(stroke
				(width 0.1)
				(type default)
			)
			(layer "F.SilkS")
		)
		(fp_line
			(start 8.821166 -5.171694)
			(end 8.52297 -4.88569)
			(stroke
				(width 0.1)
				(type default)
			)
			(layer "F.SilkS")
		)
		(fp_line
			(start 8.821166 -5.171694)
			(end 8.52297 -4.88569)
			(stroke
				(width 0.1)
				(type default)
			)
			(layer "F.SilkS")
		)
		(fp_line
			(start 8.821166 -5.171694)
			(end 8.760968 -5.171694)
			(stroke
				(width 0.1)
				(type default)
			)
			(layer "F.SilkS")
		)
		(fp_line
			(start 8.821166 -5.171694)
			(end 8.760968 -5.171694)
			(stroke
				(width 0.1)
				(type default)
			)
			(layer "F.SilkS")
		)
		(fp_line
			(start 8.862314 -0.882904)
			(end 8.922512 -0.882904)
			(stroke
				(width 0.1)
				(type default)
			)
			(layer "F.SilkS")
		)
		(fp_line
			(start 8.862314 -0.882904)
			(end 8.922512 -0.882904)
			(stroke
				(width 0.1)
				(type default)
			)
			(layer "F.SilkS")
		)
		(fp_line
			(start 8.862314 -0.882904)
			(end 8.965184 -0.981456)
			(stroke
				(width 0.1)
				(type default)
			)
			(layer "F.SilkS")
		)
		(fp_line
			(start 8.862314 -0.882904)
			(end 8.965184 -0.981456)
			(stroke
				(width 0.1)
				(type default)
			)
			(layer "F.SilkS")
		)
		(fp_line
			(start 8.88111 -5.171694)
			(end 8.511032 -4.816602)
			(stroke
				(width 0.1)
				(type default)
			)
			(layer "F.SilkS")
		)
		(fp_line
			(start 8.88111 -5.171694)
			(end 8.511032 -4.816602)
			(stroke
				(width 0.1)
				(type default)
			)
			(layer "F.SilkS")
		)
		(fp_line
			(start 8.88111 -5.171694)
			(end 8.821166 -5.171694)
			(stroke
				(width 0.1)
				(type default)
			)
			(layer "F.SilkS")
		)
		(fp_line
			(start 8.88111 -5.171694)
			(end 8.821166 -5.171694)
			(stroke
				(width 0.1)
				(type default)
			)
			(layer "F.SilkS")
		)
		(fp_line
			(start 8.922512 -0.882904)
			(end 8.947658 -0.882904)
			(stroke
				(width 0.1)
				(type default)
			)
			(layer "F.SilkS")
		)
		(fp_line
			(start 8.922512 -0.882904)
			(end 8.947658 -0.882904)
			(stroke
				(width 0.1)
				(type default)
			)
			(layer "F.SilkS")
		)
		(fp_line
			(start 8.922512 -0.882904)
			(end 8.952738 -0.91186)
			(stroke
				(width 0.1)
				(type default)
			)
			(layer "F.SilkS")
		)
		(fp_line
			(start 8.922512 -0.882904)
			(end 8.952738 -0.91186)
			(stroke
				(width 0.1)
				(type default)
			)
			(layer "F.SilkS")
		)
		(fp_line
			(start 8.941308 -5.171694)
			(end 8.49884 -4.74726)
			(stroke
				(width 0.1)
				(type default)
			)
			(layer "F.SilkS")
		)
		(fp_line
			(start 8.941308 -5.171694)
			(end 8.49884 -4.74726)
			(stroke
				(width 0.1)
				(type default)
			)
			(layer "F.SilkS")
		)
		(fp_line
			(start 8.941308 -5.171694)
			(end 8.88111 -5.171694)
			(stroke
				(width 0.1)
				(type default)
			)
			(layer "F.SilkS")
		)
		(fp_line
			(start 8.941308 -5.171694)
			(end 8.88111 -5.171694)
			(stroke
				(width 0.1)
				(type default)
			)
			(layer "F.SilkS")
		)
		(fp_line
			(start 8.947658 -0.882904)
			(end 8.952738 -0.91186)
			(stroke
				(width 0.1)
				(type default)
			)
			(layer "F.SilkS")
		)
		(fp_line
			(start 8.947658 -0.882904)
			(end 8.952738 -0.91186)
			(stroke
				(width 0.1)
				(type default)
			)
			(layer "F.SilkS")
		)
		(fp_line
			(start 8.965184 -0.981456)
			(end 8.952738 -0.91186)
			(stroke
				(width 0.1)
				(type default)
			)
			(layer "F.SilkS")
		)
		(fp_line
			(start 8.965184 -0.981456)
			(end 8.952738 -0.91186)
			(stroke
				(width 0.1)
				(type default)
			)
			(layer "F.SilkS")
		)
		(fp_line
			(start 8.977122 -1.050798)
			(end 8.965184 -0.981456)
			(stroke
				(width 0.1)
				(type default)
			)
			(layer "F.SilkS")
		)
		(fp_line
			(start 8.977122 -1.050798)
			(end 8.965184 -0.981456)
			(stroke
				(width 0.1)
				(type default)
			)
			(layer "F.SilkS")
		)
		(fp_line
			(start 8.989314 -1.12014)
			(end 8.977122 -1.050798)
			(stroke
				(width 0.1)
				(type default)
			)
			(layer "F.SilkS")
		)
		(fp_line
			(start 8.989314 -1.12014)
			(end 8.977122 -1.050798)
			(stroke
				(width 0.1)
				(type default)
			)
			(layer "F.SilkS")
		)
		(fp_line
			(start 9.001506 -5.171694)
			(end 8.486648 -4.677664)
			(stroke
				(width 0.1)
				(type default)
			)
			(layer "F.SilkS")
		)
		(fp_line
			(start 9.001506 -5.171694)
			(end 8.486648 -4.677664)
			(stroke
				(width 0.1)
				(type default)
			)
			(layer "F.SilkS")
		)
		(fp_line
			(start 9.001506 -5.171694)
			(end 8.941308 -5.171694)
			(stroke
				(width 0.1)
				(type default)
			)
			(layer "F.SilkS")
		)
		(fp_line
			(start 9.001506 -5.171694)
			(end 8.941308 -5.171694)
			(stroke
				(width 0.1)
				(type default)
			)
			(layer "F.SilkS")
		)
		(fp_line
			(start 9.001506 -1.189482)
			(end 8.989314 -1.12014)
			(stroke
				(width 0.1)
				(type default)
			)
			(layer "F.SilkS")
		)
		(fp_line
			(start 9.001506 -1.189482)
			(end 8.989314 -1.12014)
			(stroke
				(width 0.1)
				(type default)
			)
			(layer "F.SilkS")
		)
		(fp_line
			(start 9.013952 -1.259078)
			(end 9.001506 -1.189482)
			(stroke
				(width 0.1)
				(type default)
			)
			(layer "F.SilkS")
		)
		(fp_line
			(start 9.013952 -1.259078)
			(end 9.001506 -1.189482)
			(stroke
				(width 0.1)
				(type default)
			)
			(layer "F.SilkS")
		)
		(fp_line
			(start 9.026144 -1.32842)
			(end 9.013952 -1.259078)
			(stroke
				(width 0.1)
				(type default)
			)
			(layer "F.SilkS")
		)
		(fp_line
			(start 9.026144 -1.32842)
			(end 9.013952 -1.259078)
			(stroke
				(width 0.1)
				(type default)
			)
			(layer "F.SilkS")
		)
		(fp_line
			(start 9.038082 -1.397762)
			(end 9.026144 -1.32842)
			(stroke
				(width 0.1)
				(type default)
			)
			(layer "F.SilkS")
		)
		(fp_line
			(start 9.038082 -1.397762)
			(end 9.026144 -1.32842)
			(stroke
				(width 0.1)
				(type default)
			)
			(layer "F.SilkS")
		)
		(fp_line
			(start 9.050274 -1.467104)
			(end 9.038082 -1.397762)
			(stroke
				(width 0.1)
				(type default)
			)
			(layer "F.SilkS")
		)
		(fp_line
			(start 9.050274 -1.467104)
			(end 9.038082 -1.397762)
			(stroke
				(width 0.1)
				(type default)
			)
			(layer "F.SilkS")
		)
		(fp_line
			(start 9.061704 -5.171694)
			(end 8.474456 -4.608322)
			(stroke
				(width 0.1)
				(type default)
			)
			(layer "F.SilkS")
		)
		(fp_line
			(start 9.061704 -5.171694)
			(end 8.474456 -4.608322)
			(stroke
				(width 0.1)
				(type default)
			)
			(layer "F.SilkS")
		)
		(fp_line
			(start 9.061704 -5.171694)
			(end 9.001506 -5.171694)
			(stroke
				(width 0.1)
				(type default)
			)
			(layer "F.SilkS")
		)
		(fp_line
			(start 9.061704 -5.171694)
			(end 9.001506 -5.171694)
			(stroke
				(width 0.1)
				(type default)
			)
			(layer "F.SilkS")
		)
		(fp_line
			(start 9.062466 -1.5367)
			(end 9.050274 -1.467104)
			(stroke
				(width 0.1)
				(type default)
			)
			(layer "F.SilkS")
		)
		(fp_line
			(start 9.062466 -1.5367)
			(end 9.050274 -1.467104)
			(stroke
				(width 0.1)
				(type default)
			)
			(layer "F.SilkS")
		)
		(fp_line
			(start 9.074912 -1.606296)
			(end 9.062466 -1.5367)
			(stroke
				(width 0.1)
				(type default)
			)
			(layer "F.SilkS")
		)
		(fp_line
			(start 9.074912 -1.606296)
			(end 9.062466 -1.5367)
			(stroke
				(width 0.1)
				(type default)
			)
			(layer "F.SilkS")
		)
		(fp_line
			(start 9.087104 -1.675384)
			(end 9.074912 -1.606296)
			(stroke
				(width 0.1)
				(type default)
			)
			(layer "F.SilkS")
		)
		(fp_line
			(start 9.087104 -1.675384)
			(end 9.074912 -1.606296)
			(stroke
				(width 0.1)
				(type default)
			)
			(layer "F.SilkS")
		)
		(fp_line
			(start 9.099042 -1.744726)
			(end 9.087104 -1.675384)
			(stroke
				(width 0.1)
				(type default)
			)
			(layer "F.SilkS")
		)
		(fp_line
			(start 9.099042 -1.744726)
			(end 9.087104 -1.675384)
			(stroke
				(width 0.1)
				(type default)
			)
			(layer "F.SilkS")
		)
		(fp_line
			(start 9.111234 -1.814322)
			(end 9.099042 -1.744726)
			(stroke
				(width 0.1)
				(type default)
			)
			(layer "F.SilkS")
		)
		(fp_line
			(start 9.111234 -1.814322)
			(end 9.099042 -1.744726)
			(stroke
				(width 0.1)
				(type default)
			)
			(layer "F.SilkS")
		)
		(fp_line
			(start 9.121902 -5.171694)
			(end 8.462264 -4.53898)
			(stroke
				(width 0.1)
				(type default)
			)
			(layer "F.SilkS")
		)
		(fp_line
			(start 9.121902 -5.171694)
			(end 8.462264 -4.53898)
			(stroke
				(width 0.1)
				(type default)
			)
			(layer "F.SilkS")
		)
		(fp_line
			(start 9.121902 -5.171694)
			(end 9.061704 -5.171694)
			(stroke
				(width 0.1)
				(type default)
			)
			(layer "F.SilkS")
		)
		(fp_line
			(start 9.121902 -5.171694)
			(end 9.061704 -5.171694)
			(stroke
				(width 0.1)
				(type default)
			)
			(layer "F.SilkS")
		)
		(fp_line
			(start 9.12368 -1.883664)
			(end 9.111234 -1.814322)
			(stroke
				(width 0.1)
				(type default)
			)
			(layer "F.SilkS")
		)
		(fp_line
			(start 9.12368 -1.883664)
			(end 9.111234 -1.814322)
			(stroke
				(width 0.1)
				(type default)
			)
			(layer "F.SilkS")
		)
		(fp_line
			(start 9.135872 -1.953006)
			(end 9.12368 -1.883664)
			(stroke
				(width 0.1)
				(type default)
			)
			(layer "F.SilkS")
		)
		(fp_line
			(start 9.135872 -1.953006)
			(end 9.12368 -1.883664)
			(stroke
				(width 0.1)
				(type default)
			)
			(layer "F.SilkS")
		)
		(fp_line
			(start 9.148064 -2.022602)
			(end 9.135872 -1.953006)
			(stroke
				(width 0.1)
				(type default)
			)
			(layer "F.SilkS")
		)
		(fp_line
			(start 9.148064 -2.022602)
			(end 9.135872 -1.953006)
			(stroke
				(width 0.1)
				(type default)
			)
			(layer "F.SilkS")
		)
		(fp_line
			(start 9.160002 -2.091944)
			(end 9.148064 -2.022602)
			(stroke
				(width 0.1)
				(type default)
			)
			(layer "F.SilkS")
		)
		(fp_line
			(start 9.160002 -2.091944)
			(end 9.148064 -2.022602)
			(stroke
				(width 0.1)
				(type default)
			)
			(layer "F.SilkS")
		)
		(fp_line
			(start 9.172194 -2.161286)
			(end 9.160002 -2.091944)
			(stroke
				(width 0.1)
				(type default)
			)
			(layer "F.SilkS")
		)
		(fp_line
			(start 9.172194 -2.161286)
			(end 9.160002 -2.091944)
			(stroke
				(width 0.1)
				(type default)
			)
			(layer "F.SilkS")
		)
		(fp_line
			(start 9.172194 -2.161286)
			(end 9.18464 -2.230882)
			(stroke
				(width 0.1)
				(type default)
			)
			(layer "F.SilkS")
		)
		(fp_line
			(start 9.172194 -2.161286)
			(end 9.18464 -2.230882)
			(stroke
				(width 0.1)
				(type default)
			)
			(layer "F.SilkS")
		)
		(fp_line
			(start 9.181846 -5.171694)
			(end 8.450326 -4.469638)
			(stroke
				(width 0.1)
				(type default)
			)
			(layer "F.SilkS")
		)
		(fp_line
			(start 9.181846 -5.171694)
			(end 8.450326 -4.469638)
			(stroke
				(width 0.1)
				(type default)
			)
			(layer "F.SilkS")
		)
		(fp_line
			(start 9.181846 -5.171694)
			(end 9.121902 -5.171694)
			(stroke
				(width 0.1)
				(type default)
			)
			(layer "F.SilkS")
		)
		(fp_line
			(start 9.181846 -5.171694)
			(end 9.121902 -5.171694)
			(stroke
				(width 0.1)
				(type default)
			)
			(layer "F.SilkS")
		)
		(fp_line
			(start 9.18464 -2.230882)
			(end 9.196832 -2.300224)
			(stroke
				(width 0.1)
				(type default)
			)
			(layer "F.SilkS")
		)
		(fp_line
			(start 9.18464 -2.230882)
			(end 9.196832 -2.300224)
			(stroke
				(width 0.1)
				(type default)
			)
			(layer "F.SilkS")
		)
		(fp_line
			(start 9.196832 -2.300224)
			(end 9.209024 -2.369566)
			(stroke
				(width 0.1)
				(type default)
			)
			(layer "F.SilkS")
		)
		(fp_line
			(start 9.196832 -2.300224)
			(end 9.209024 -2.369566)
			(stroke
				(width 0.1)
				(type default)
			)
			(layer "F.SilkS")
		)
		(fp_line
			(start 9.209024 -2.369566)
			(end 9.220962 -2.438908)
			(stroke
				(width 0.1)
				(type default)
			)
			(layer "F.SilkS")
		)
		(fp_line
			(start 9.209024 -2.369566)
			(end 9.220962 -2.438908)
			(stroke
				(width 0.1)
				(type default)
			)
			(layer "F.SilkS")
		)
		(fp_line
			(start 9.220962 -2.438908)
			(end 9.233408 -2.508504)
			(stroke
				(width 0.1)
				(type default)
			)
			(layer "F.SilkS")
		)
		(fp_line
			(start 9.220962 -2.438908)
			(end 9.233408 -2.508504)
			(stroke
				(width 0.1)
				(type default)
			)
			(layer "F.SilkS")
		)
		(fp_line
			(start 9.233408 -2.508504)
			(end 9.2456 -2.577592)
			(stroke
				(width 0.1)
				(type default)
			)
			(layer "F.SilkS")
		)
		(fp_line
			(start 9.233408 -2.508504)
			(end 9.2456 -2.577592)
			(stroke
				(width 0.1)
				(type default)
			)
			(layer "F.SilkS")
		)
		(fp_line
			(start 9.242298 -5.171694)
			(end 8.43788 -4.400296)
			(stroke
				(width 0.1)
				(type default)
			)
			(layer "F.SilkS")
		)
		(fp_line
			(start 9.242298 -5.171694)
			(end 8.43788 -4.400296)
			(stroke
				(width 0.1)
				(type default)
			)
			(layer "F.SilkS")
		)
		(fp_line
			(start 9.242298 -5.171694)
			(end 9.181846 -5.171694)
			(stroke
				(width 0.1)
				(type default)
			)
			(layer "F.SilkS")
		)
		(fp_line
			(start 9.242298 -5.171694)
			(end 9.181846 -5.171694)
			(stroke
				(width 0.1)
				(type default)
			)
			(layer "F.SilkS")
		)
		(fp_line
			(start 9.2456 -2.577592)
			(end 9.257792 -2.647188)
			(stroke
				(width 0.1)
				(type default)
			)
			(layer "F.SilkS")
		)
		(fp_line
			(start 9.2456 -2.577592)
			(end 9.257792 -2.647188)
			(stroke
				(width 0.1)
				(type default)
			)
			(layer "F.SilkS")
		)
		(fp_line
			(start 9.257792 -2.647188)
			(end 9.269984 -2.716784)
			(stroke
				(width 0.1)
				(type default)
			)
			(layer "F.SilkS")
		)
		(fp_line
			(start 9.257792 -2.647188)
			(end 9.269984 -2.716784)
			(stroke
				(width 0.1)
				(type default)
			)
			(layer "F.SilkS")
		)
		(fp_line
			(start 9.269984 -2.716784)
			(end 9.281922 -2.786126)
			(stroke
				(width 0.1)
				(type default)
			)
			(layer "F.SilkS")
		)
		(fp_line
			(start 9.269984 -2.716784)
			(end 9.281922 -2.786126)
			(stroke
				(width 0.1)
				(type default)
			)
			(layer "F.SilkS")
		)
		(fp_line
			(start 9.281922 -2.786126)
			(end 9.294368 -2.855468)
			(stroke
				(width 0.1)
				(type default)
			)
			(layer "F.SilkS")
		)
		(fp_line
			(start 9.281922 -2.786126)
			(end 9.294368 -2.855468)
			(stroke
				(width 0.1)
				(type default)
			)
			(layer "F.SilkS")
		)
		(fp_line
			(start 9.294368 -2.855468)
			(end 9.30656 -2.925064)
			(stroke
				(width 0.1)
				(type default)
			)
			(layer "F.SilkS")
		)
		(fp_line
			(start 9.294368 -2.855468)
			(end 9.30656 -2.925064)
			(stroke
				(width 0.1)
				(type default)
			)
			(layer "F.SilkS")
		)
		(fp_line
			(start 9.302242 -5.171694)
			(end 8.425942 -4.3307)
			(stroke
				(width 0.1)
				(type default)
			)
			(layer "F.SilkS")
		)
		(fp_line
			(start 9.302242 -5.171694)
			(end 8.425942 -4.3307)
			(stroke
				(width 0.1)
				(type default)
			)
			(layer "F.SilkS")
		)
		(fp_line
			(start 9.302242 -5.171694)
			(end 9.242298 -5.171694)
			(stroke
				(width 0.1)
				(type default)
			)
			(layer "F.SilkS")
		)
		(fp_line
			(start 9.302242 -5.171694)
			(end 9.242298 -5.171694)
			(stroke
				(width 0.1)
				(type default)
			)
			(layer "F.SilkS")
		)
		(fp_line
			(start 9.30656 -2.925064)
			(end 9.318752 -2.994406)
			(stroke
				(width 0.1)
				(type default)
			)
			(layer "F.SilkS")
		)
		(fp_line
			(start 9.30656 -2.925064)
			(end 9.318752 -2.994406)
			(stroke
				(width 0.1)
				(type default)
			)
			(layer "F.SilkS")
		)
		(fp_line
			(start 9.318752 -2.994406)
			(end 9.330944 -3.063748)
			(stroke
				(width 0.1)
				(type default)
			)
			(layer "F.SilkS")
		)
		(fp_line
			(start 9.318752 -2.994406)
			(end 9.330944 -3.063748)
			(stroke
				(width 0.1)
				(type default)
			)
			(layer "F.SilkS")
		)
		(fp_line
			(start 9.330944 -3.063748)
			(end 9.343136 -3.13309)
			(stroke
				(width 0.1)
				(type default)
			)
			(layer "F.SilkS")
		)
		(fp_line
			(start 9.330944 -3.063748)
			(end 9.343136 -3.13309)
			(stroke
				(width 0.1)
				(type default)
			)
			(layer "F.SilkS")
		)
		(fp_line
			(start 9.343136 -3.13309)
			(end 9.355328 -3.202432)
			(stroke
				(width 0.1)
				(type default)
			)
			(layer "F.SilkS")
		)
		(fp_line
			(start 9.343136 -3.13309)
			(end 9.355328 -3.202432)
			(stroke
				(width 0.1)
				(type default)
			)
			(layer "F.SilkS")
		)
		(fp_line
			(start 9.355328 -3.202432)
			(end 9.36752 -3.272028)
			(stroke
				(width 0.1)
				(type default)
			)
			(layer "F.SilkS")
		)
		(fp_line
			(start 9.355328 -3.202432)
			(end 9.36752 -3.272028)
			(stroke
				(width 0.1)
				(type default)
			)
			(layer "F.SilkS")
		)
		(fp_line
			(start 9.36244 -5.171694)
			(end 8.41375 -4.261612)
			(stroke
				(width 0.1)
				(type default)
			)
			(layer "F.SilkS")
		)
		(fp_line
			(start 9.36244 -5.171694)
			(end 8.41375 -4.261612)
			(stroke
				(width 0.1)
				(type default)
			)
			(layer "F.SilkS")
		)
		(fp_line
			(start 9.36244 -5.171694)
			(end 9.302242 -5.171694)
			(stroke
				(width 0.1)
				(type default)
			)
			(layer "F.SilkS")
		)
		(fp_line
			(start 9.36244 -5.171694)
			(end 9.302242 -5.171694)
			(stroke
				(width 0.1)
				(type default)
			)
			(layer "F.SilkS")
		)
		(fp_line
			(start 9.36752 -3.272028)
			(end 9.379712 -3.34137)
			(stroke
				(width 0.1)
				(type default)
			)
			(layer "F.SilkS")
		)
		(fp_line
			(start 9.36752 -3.272028)
			(end 9.379712 -3.34137)
			(stroke
				(width 0.1)
				(type default)
			)
			(layer "F.SilkS")
		)
		(fp_line
			(start 9.379712 -3.34137)
			(end 9.391904 -3.410712)
			(stroke
				(width 0.1)
				(type default)
			)
			(layer "F.SilkS")
		)
		(fp_line
			(start 9.379712 -3.34137)
			(end 9.391904 -3.410712)
			(stroke
				(width 0.1)
				(type default)
			)
			(layer "F.SilkS")
		)
		(fp_line
			(start 9.404096 -3.480054)
			(end 9.391904 -3.410712)
			(stroke
				(width 0.1)
				(type default)
			)
			(layer "F.SilkS")
		)
		(fp_line
			(start 9.404096 -3.480054)
			(end 9.391904 -3.410712)
			(stroke
				(width 0.1)
				(type default)
			)
			(layer "F.SilkS")
		)
		(fp_line
			(start 9.416288 -3.54965)
			(end 6.565392 -0.815086)
			(stroke
				(width 0.1)
				(type default)
			)
			(layer "F.SilkS")
		)
		(fp_line
			(start 9.416288 -3.54965)
			(end 6.565392 -0.815086)
			(stroke
				(width 0.1)
				(type default)
			)
			(layer "F.SilkS")
		)
		(fp_line
			(start 9.416288 -3.54965)
			(end 9.404096 -3.480054)
			(stroke
				(width 0.1)
				(type default)
			)
			(layer "F.SilkS")
		)
		(fp_line
			(start 9.416288 -3.54965)
			(end 9.404096 -3.480054)
			(stroke
				(width 0.1)
				(type default)
			)
			(layer "F.SilkS")
		)
		(fp_line
			(start 9.416288 -3.54965)
			(end 9.42848 -3.618992)
			(stroke
				(width 0.1)
				(type default)
			)
			(layer "F.SilkS")
		)
		(fp_line
			(start 9.416288 -3.54965)
			(end 9.42848 -3.618992)
			(stroke
				(width 0.1)
				(type default)
			)
			(layer "F.SilkS")
		)
		(fp_line
			(start 9.422638 -5.171694)
			(end 8.401558 -4.19227)
			(stroke
				(width 0.1)
				(type default)
			)
			(layer "F.SilkS")
		)
		(fp_line
			(start 9.422638 -5.171694)
			(end 8.401558 -4.19227)
			(stroke
				(width 0.1)
				(type default)
			)
			(layer "F.SilkS")
		)
		(fp_line
			(start 9.422638 -5.171694)
			(end 9.36244 -5.171694)
			(stroke
				(width 0.1)
				(type default)
			)
			(layer "F.SilkS")
		)
		(fp_line
			(start 9.422638 -5.171694)
			(end 9.36244 -5.171694)
			(stroke
				(width 0.1)
				(type default)
			)
			(layer "F.SilkS")
		)
		(fp_line
			(start 9.42848 -3.618992)
			(end 9.440672 -3.688334)
			(stroke
				(width 0.1)
				(type default)
			)
			(layer "F.SilkS")
		)
		(fp_line
			(start 9.42848 -3.618992)
			(end 9.440672 -3.688334)
			(stroke
				(width 0.1)
				(type default)
			)
			(layer "F.SilkS")
		)
		(fp_line
			(start 9.440672 -3.688334)
			(end 9.452864 -3.75793)
			(stroke
				(width 0.1)
				(type default)
			)
			(layer "F.SilkS")
		)
		(fp_line
			(start 9.440672 -3.688334)
			(end 9.452864 -3.75793)
			(stroke
				(width 0.1)
				(type default)
			)
			(layer "F.SilkS")
		)
		(fp_line
			(start 9.465056 -3.827526)
			(end 9.452864 -3.75793)
			(stroke
				(width 0.1)
				(type default)
			)
			(layer "F.SilkS")
		)
		(fp_line
			(start 9.465056 -3.827526)
			(end 9.452864 -3.75793)
			(stroke
				(width 0.1)
				(type default)
			)
			(layer "F.SilkS")
		)
		(fp_line
			(start 9.465056 -3.827526)
			(end 9.477248 -3.896614)
			(stroke
				(width 0.1)
				(type default)
			)
			(layer "F.SilkS")
		)
		(fp_line
			(start 9.465056 -3.827526)
			(end 9.477248 -3.896614)
			(stroke
				(width 0.1)
				(type default)
			)
			(layer "F.SilkS")
		)
		(fp_line
			(start 9.477248 -3.896614)
			(end 8.107172 -2.582418)
			(stroke
				(width 0.1)
				(type default)
			)
			(layer "F.SilkS")
		)
		(fp_line
			(start 9.477248 -3.896614)
			(end 8.107172 -2.582418)
			(stroke
				(width 0.1)
				(type default)
			)
			(layer "F.SilkS")
		)
		(fp_line
			(start 9.477248 -3.896614)
			(end 9.48944 -3.965956)
			(stroke
				(width 0.1)
				(type default)
			)
			(layer "F.SilkS")
		)
		(fp_line
			(start 9.477248 -3.896614)
			(end 9.48944 -3.965956)
			(stroke
				(width 0.1)
				(type default)
			)
			(layer "F.SilkS")
		)
		(fp_line
			(start 9.482836 -5.171694)
			(end 8.389366 -4.122674)
			(stroke
				(width 0.1)
				(type default)
			)
			(layer "F.SilkS")
		)
		(fp_line
			(start 9.482836 -5.171694)
			(end 8.389366 -4.122674)
			(stroke
				(width 0.1)
				(type default)
			)
			(layer "F.SilkS")
		)
		(fp_line
			(start 9.482836 -5.171694)
			(end 9.422638 -5.171694)
			(stroke
				(width 0.1)
				(type default)
			)
			(layer "F.SilkS")
		)
		(fp_line
			(start 9.482836 -5.171694)
			(end 9.422638 -5.171694)
			(stroke
				(width 0.1)
				(type default)
			)
			(layer "F.SilkS")
		)
		(fp_line
			(start 9.48944 -3.965956)
			(end 8.123682 -2.655824)
			(stroke
				(width 0.1)
				(type default)
			)
			(layer "F.SilkS")
		)
		(fp_line
			(start 9.48944 -3.965956)
			(end 8.123682 -2.655824)
			(stroke
				(width 0.1)
				(type default)
			)
			(layer "F.SilkS")
		)
		(fp_line
			(start 9.48944 -3.965956)
			(end 9.501632 -4.035552)
			(stroke
				(width 0.1)
				(type default)
			)
			(layer "F.SilkS")
		)
		(fp_line
			(start 9.48944 -3.965956)
			(end 9.501632 -4.035552)
			(stroke
				(width 0.1)
				(type default)
			)
			(layer "F.SilkS")
		)
		(fp_line
			(start 9.501632 -4.035552)
			(end 8.140446 -2.729738)
			(stroke
				(width 0.1)
				(type default)
			)
			(layer "F.SilkS")
		)
		(fp_line
			(start 9.501632 -4.035552)
			(end 8.140446 -2.729738)
			(stroke
				(width 0.1)
				(type default)
			)
			(layer "F.SilkS")
		)
		(fp_line
			(start 9.501632 -4.035552)
			(end 9.513824 -4.104894)
			(stroke
				(width 0.1)
				(type default)
			)
			(layer "F.SilkS")
		)
		(fp_line
			(start 9.501632 -4.035552)
			(end 9.513824 -4.104894)
			(stroke
				(width 0.1)
				(type default)
			)
			(layer "F.SilkS")
		)
		(fp_line
			(start 9.513824 -4.104894)
			(end 8.156956 -2.803398)
			(stroke
				(width 0.1)
				(type default)
			)
			(layer "F.SilkS")
		)
		(fp_line
			(start 9.513824 -4.104894)
			(end 8.156956 -2.803398)
			(stroke
				(width 0.1)
				(type default)
			)
			(layer "F.SilkS")
		)
		(fp_line
			(start 9.513824 -4.104894)
			(end 9.526016 -4.174236)
			(stroke
				(width 0.1)
				(type default)
			)
			(layer "F.SilkS")
		)
		(fp_line
			(start 9.513824 -4.104894)
			(end 9.526016 -4.174236)
			(stroke
				(width 0.1)
				(type default)
			)
			(layer "F.SilkS")
		)
		(fp_line
			(start 9.526016 -4.174236)
			(end 8.170418 -2.87401)
			(stroke
				(width 0.1)
				(type default)
			)
			(layer "F.SilkS")
		)
		(fp_line
			(start 9.526016 -4.174236)
			(end 8.170418 -2.87401)
			(stroke
				(width 0.1)
				(type default)
			)
			(layer "F.SilkS")
		)
		(fp_line
			(start 9.526016 -4.174236)
			(end 9.538208 -4.243578)
			(stroke
				(width 0.1)
				(type default)
			)
			(layer "F.SilkS")
		)
		(fp_line
			(start 9.526016 -4.174236)
			(end 9.538208 -4.243578)
			(stroke
				(width 0.1)
				(type default)
			)
			(layer "F.SilkS")
		)
		(fp_line
			(start 9.538208 -4.243578)
			(end 8.18261 -2.943352)
			(stroke
				(width 0.1)
				(type default)
			)
			(layer "F.SilkS")
		)
		(fp_line
			(start 9.538208 -4.243578)
			(end 8.18261 -2.943352)
			(stroke
				(width 0.1)
				(type default)
			)
			(layer "F.SilkS")
		)
		(fp_line
			(start 9.538208 -4.243578)
			(end 9.5504 -4.313174)
			(stroke
				(width 0.1)
				(type default)
			)
			(layer "F.SilkS")
		)
		(fp_line
			(start 9.538208 -4.243578)
			(end 9.5504 -4.313174)
			(stroke
				(width 0.1)
				(type default)
			)
			(layer "F.SilkS")
		)
		(fp_line
			(start 9.543034 -5.171694)
			(end 8.377174 -4.053332)
			(stroke
				(width 0.1)
				(type default)
			)
			(layer "F.SilkS")
		)
		(fp_line
			(start 9.543034 -5.171694)
			(end 8.377174 -4.053332)
			(stroke
				(width 0.1)
				(type default)
			)
			(layer "F.SilkS")
		)
		(fp_line
			(start 9.543034 -5.171694)
			(end 9.482836 -5.171694)
			(stroke
				(width 0.1)
				(type default)
			)
			(layer "F.SilkS")
		)
		(fp_line
			(start 9.543034 -5.171694)
			(end 9.482836 -5.171694)
			(stroke
				(width 0.1)
				(type default)
			)
			(layer "F.SilkS")
		)
		(fp_line
			(start 9.5504 -4.313174)
			(end 8.194802 -3.012694)
			(stroke
				(width 0.1)
				(type default)
			)
			(layer "F.SilkS")
		)
		(fp_line
			(start 9.5504 -4.313174)
			(end 8.194802 -3.012694)
			(stroke
				(width 0.1)
				(type default)
			)
			(layer "F.SilkS")
		)
		(fp_line
			(start 9.5504 -4.313174)
			(end 9.562592 -4.382516)
			(stroke
				(width 0.1)
				(type default)
			)
			(layer "F.SilkS")
		)
		(fp_line
			(start 9.5504 -4.313174)
			(end 9.562592 -4.382516)
			(stroke
				(width 0.1)
				(type default)
			)
			(layer "F.SilkS")
		)
		(fp_line
			(start 9.562592 -4.382516)
			(end 8.206994 -3.08229)
			(stroke
				(width 0.1)
				(type default)
			)
			(layer "F.SilkS")
		)
		(fp_line
			(start 9.562592 -4.382516)
			(end 8.206994 -3.08229)
			(stroke
				(width 0.1)
				(type default)
			)
			(layer "F.SilkS")
		)
		(fp_line
			(start 9.562592 -4.382516)
			(end 9.574784 -4.452112)
			(stroke
				(width 0.1)
				(type default)
			)
			(layer "F.SilkS")
		)
		(fp_line
			(start 9.562592 -4.382516)
			(end 9.574784 -4.452112)
			(stroke
				(width 0.1)
				(type default)
			)
			(layer "F.SilkS")
		)
		(fp_line
			(start 9.574784 -4.452112)
			(end 8.219186 -3.151378)
			(stroke
				(width 0.1)
				(type default)
			)
			(layer "F.SilkS")
		)
		(fp_line
			(start 9.574784 -4.452112)
			(end 8.219186 -3.151378)
			(stroke
				(width 0.1)
				(type default)
			)
			(layer "F.SilkS")
		)
		(fp_line
			(start 9.574784 -4.452112)
			(end 9.586976 -4.5212)
			(stroke
				(width 0.1)
				(type default)
			)
			(layer "F.SilkS")
		)
		(fp_line
			(start 9.574784 -4.452112)
			(end 9.586976 -4.5212)
			(stroke
				(width 0.1)
				(type default)
			)
			(layer "F.SilkS")
		)
		(fp_line
			(start 9.586976 -4.5212)
			(end 8.231378 -3.22072)
			(stroke
				(width 0.1)
				(type default)
			)
			(layer "F.SilkS")
		)
		(fp_line
			(start 9.586976 -4.5212)
			(end 8.231378 -3.22072)
			(stroke
				(width 0.1)
				(type default)
			)
			(layer "F.SilkS")
		)
		(fp_line
			(start 9.586976 -4.5212)
			(end 9.599168 -4.590796)
			(stroke
				(width 0.1)
				(type default)
			)
			(layer "F.SilkS")
		)
		(fp_line
			(start 9.586976 -4.5212)
			(end 9.599168 -4.590796)
			(stroke
				(width 0.1)
				(type default)
			)
			(layer "F.SilkS")
		)
		(fp_line
			(start 9.599168 -4.590796)
			(end 8.24357 -3.290316)
			(stroke
				(width 0.1)
				(type default)
			)
			(layer "F.SilkS")
		)
		(fp_line
			(start 9.599168 -4.590796)
			(end 8.24357 -3.290316)
			(stroke
				(width 0.1)
				(type default)
			)
			(layer "F.SilkS")
		)
		(fp_line
			(start 9.599168 -4.590796)
			(end 9.61136 -4.660138)
			(stroke
				(width 0.1)
				(type default)
			)
			(layer "F.SilkS")
		)
		(fp_line
			(start 9.599168 -4.590796)
			(end 9.61136 -4.660138)
			(stroke
				(width 0.1)
				(type default)
			)
			(layer "F.SilkS")
		)
		(fp_line
			(start 9.603232 -5.171694)
			(end 8.365236 -3.98399)
			(stroke
				(width 0.1)
				(type default)
			)
			(layer "F.SilkS")
		)
		(fp_line
			(start 9.603232 -5.171694)
			(end 8.365236 -3.98399)
			(stroke
				(width 0.1)
				(type default)
			)
			(layer "F.SilkS")
		)
		(fp_line
			(start 9.603232 -5.171694)
			(end 9.543034 -5.171694)
			(stroke
				(width 0.1)
				(type default)
			)
			(layer "F.SilkS")
		)
		(fp_line
			(start 9.603232 -5.171694)
			(end 9.543034 -5.171694)
			(stroke
				(width 0.1)
				(type default)
			)
			(layer "F.SilkS")
		)
		(fp_line
			(start 9.61136 -4.660138)
			(end 8.255762 -3.359658)
			(stroke
				(width 0.1)
				(type default)
			)
			(layer "F.SilkS")
		)
		(fp_line
			(start 9.61136 -4.660138)
			(end 8.255762 -3.359658)
			(stroke
				(width 0.1)
				(type default)
			)
			(layer "F.SilkS")
		)
		(fp_line
			(start 9.61136 -4.660138)
			(end 9.623552 -4.729734)
			(stroke
				(width 0.1)
				(type default)
			)
			(layer "F.SilkS")
		)
		(fp_line
			(start 9.61136 -4.660138)
			(end 9.623552 -4.729734)
			(stroke
				(width 0.1)
				(type default)
			)
			(layer "F.SilkS")
		)
		(fp_line
			(start 9.623552 -4.729734)
			(end 8.2677 -3.429)
			(stroke
				(width 0.1)
				(type default)
			)
			(layer "F.SilkS")
		)
		(fp_line
			(start 9.623552 -4.729734)
			(end 8.2677 -3.429)
			(stroke
				(width 0.1)
				(type default)
			)
			(layer "F.SilkS")
		)
		(fp_line
			(start 9.623552 -4.729734)
			(end 9.635744 -4.798822)
			(stroke
				(width 0.1)
				(type default)
			)
			(layer "F.SilkS")
		)
		(fp_line
			(start 9.623552 -4.729734)
			(end 9.635744 -4.798822)
			(stroke
				(width 0.1)
				(type default)
			)
			(layer "F.SilkS")
		)
		(fp_line
			(start 9.635744 -4.798822)
			(end 8.279892 -3.498342)
			(stroke
				(width 0.1)
				(type default)
			)
			(layer "F.SilkS")
		)
		(fp_line
			(start 9.635744 -4.798822)
			(end 8.279892 -3.498342)
			(stroke
				(width 0.1)
				(type default)
			)
			(layer "F.SilkS")
		)
		(fp_line
			(start 9.635744 -4.798822)
			(end 9.64819 -4.868418)
			(stroke
				(width 0.1)
				(type default)
			)
			(layer "F.SilkS")
		)
		(fp_line
			(start 9.635744 -4.798822)
			(end 9.64819 -4.868418)
			(stroke
				(width 0.1)
				(type default)
			)
			(layer "F.SilkS")
		)
		(fp_line
			(start 9.64819 -4.868418)
			(end 8.292084 -3.567684)
			(stroke
				(width 0.1)
				(type default)
			)
			(layer "F.SilkS")
		)
		(fp_line
			(start 9.64819 -4.868418)
			(end 8.292084 -3.567684)
			(stroke
				(width 0.1)
				(type default)
			)
			(layer "F.SilkS")
		)
		(fp_line
			(start 9.64819 -4.868418)
			(end 9.660382 -4.938014)
			(stroke
				(width 0.1)
				(type default)
			)
			(layer "F.SilkS")
		)
		(fp_line
			(start 9.64819 -4.868418)
			(end 9.660382 -4.938014)
			(stroke
				(width 0.1)
				(type default)
			)
			(layer "F.SilkS")
		)
		(fp_line
			(start 9.660382 -4.938014)
			(end 8.304276 -3.63728)
			(stroke
				(width 0.1)
				(type default)
			)
			(layer "F.SilkS")
		)
		(fp_line
			(start 9.660382 -4.938014)
			(end 8.304276 -3.63728)
			(stroke
				(width 0.1)
				(type default)
			)
			(layer "F.SilkS")
		)
		(fp_line
			(start 9.660382 -4.938014)
			(end 9.67232 -5.007356)
			(stroke
				(width 0.1)
				(type default)
			)
			(layer "F.SilkS")
		)
		(fp_line
			(start 9.660382 -4.938014)
			(end 9.67232 -5.007356)
			(stroke
				(width 0.1)
				(type default)
			)
			(layer "F.SilkS")
		)
		(fp_line
			(start 9.663176 -5.171694)
			(end 8.35279 -3.914648)
			(stroke
				(width 0.1)
				(type default)
			)
			(layer "F.SilkS")
		)
		(fp_line
			(start 9.663176 -5.171694)
			(end 8.35279 -3.914648)
			(stroke
				(width 0.1)
				(type default)
			)
			(layer "F.SilkS")
		)
		(fp_line
			(start 9.663176 -5.171694)
			(end 9.603232 -5.171694)
			(stroke
				(width 0.1)
				(type default)
			)
			(layer "F.SilkS")
		)
		(fp_line
			(start 9.663176 -5.171694)
			(end 9.603232 -5.171694)
			(stroke
				(width 0.1)
				(type default)
			)
			(layer "F.SilkS")
		)
		(fp_line
			(start 9.67232 -5.007356)
			(end 8.316468 -3.706368)
			(stroke
				(width 0.1)
				(type default)
			)
			(layer "F.SilkS")
		)
		(fp_line
			(start 9.67232 -5.007356)
			(end 8.316468 -3.706368)
			(stroke
				(width 0.1)
				(type default)
			)
			(layer "F.SilkS")
		)
		(fp_line
			(start 9.67232 -5.007356)
			(end 9.684512 -5.076698)
			(stroke
				(width 0.1)
				(type default)
			)
			(layer "F.SilkS")
		)
		(fp_line
			(start 9.67232 -5.007356)
			(end 9.684512 -5.076698)
			(stroke
				(width 0.1)
				(type default)
			)
			(layer "F.SilkS")
		)
		(fp_line
			(start 9.684512 -5.076698)
			(end 8.32866 -3.77571)
			(stroke
				(width 0.1)
				(type default)
			)
			(layer "F.SilkS")
		)
		(fp_line
			(start 9.684512 -5.076698)
			(end 8.32866 -3.77571)
			(stroke
				(width 0.1)
				(type default)
			)
			(layer "F.SilkS")
		)
		(fp_line
			(start 9.684512 -5.076698)
			(end 9.696704 -5.14604)
			(stroke
				(width 0.1)
				(type default)
			)
			(layer "F.SilkS")
		)
		(fp_line
			(start 9.684512 -5.076698)
			(end 9.696704 -5.14604)
			(stroke
				(width 0.1)
				(type default)
			)
			(layer "F.SilkS")
		)
		(fp_line
			(start 9.696704 -5.14604)
			(end 8.340852 -3.845306)
			(stroke
				(width 0.1)
				(type default)
			)
			(layer "F.SilkS")
		)
		(fp_line
			(start 9.696704 -5.14604)
			(end 8.340852 -3.845306)
			(stroke
				(width 0.1)
				(type default)
			)
			(layer "F.SilkS")
		)
		(fp_line
			(start 9.696704 -5.14604)
			(end 9.701276 -5.171694)
			(stroke
				(width 0.1)
				(type default)
			)
			(layer "F.SilkS")
		)
		(fp_line
			(start 9.696704 -5.14604)
			(end 9.701276 -5.171694)
			(stroke
				(width 0.1)
				(type default)
			)
			(layer "F.SilkS")
		)
		(fp_line
			(start 9.701276 -5.171694)
			(end 9.663176 -5.171694)
			(stroke
				(width 0.1)
				(type default)
			)
			(layer "F.SilkS")
		)
		(fp_line
			(start 9.701276 -5.171694)
			(end 9.663176 -5.171694)
			(stroke
				(width 0.1)
				(type default)
			)
			(layer "F.SilkS")
		)
		(fp_line
			(start 9.754616 -1.96977)
			(end 11.590528 -3.730752)
			(stroke
				(width 0.1)
				(type default)
			)
			(layer "F.SilkS")
		)
		(fp_line
			(start 9.754616 -1.96977)
			(end 11.590528 -3.730752)
			(stroke
				(width 0.1)
				(type default)
			)
			(layer "F.SilkS")
		)
		(fp_line
			(start 9.75614 -2.028698)
			(end 11.526012 -3.726688)
			(stroke
				(width 0.1)
				(type default)
			)
			(layer "F.SilkS")
		)
		(fp_line
			(start 9.75614 -2.028698)
			(end 11.526012 -3.726688)
			(stroke
				(width 0.1)
				(type default)
			)
			(layer "F.SilkS")
		)
		(fp_line
			(start 9.75741 -2.08788)
			(end 11.46175 -3.722878)
			(stroke
				(width 0.1)
				(type default)
			)
			(layer "F.SilkS")
		)
		(fp_line
			(start 9.75741 -2.08788)
			(end 11.46175 -3.722878)
			(stroke
				(width 0.1)
				(type default)
			)
			(layer "F.SilkS")
		)
		(fp_line
			(start 9.758172 -1.915414)
			(end 11.65479 -3.734816)
			(stroke
				(width 0.1)
				(type default)
			)
			(layer "F.SilkS")
		)
		(fp_line
			(start 9.758172 -1.915414)
			(end 11.65479 -3.734816)
			(stroke
				(width 0.1)
				(type default)
			)
			(layer "F.SilkS")
		)
		(fp_line
			(start 9.760458 -2.148332)
			(end 11.394694 -3.71602)
			(stroke
				(width 0.1)
				(type default)
			)
			(layer "F.SilkS")
		)
		(fp_line
			(start 9.760458 -2.148332)
			(end 11.394694 -3.71602)
			(stroke
				(width 0.1)
				(type default)
			)
			(layer "F.SilkS")
		)
		(fp_line
			(start 9.762998 -1.862074)
			(end 11.719052 -3.738626)
			(stroke
				(width 0.1)
				(type default)
			)
			(layer "F.SilkS")
		)
		(fp_line
			(start 9.762998 -1.862074)
			(end 11.719052 -3.738626)
			(stroke
				(width 0.1)
				(type default)
			)
			(layer "F.SilkS")
		)
		(fp_line
			(start 9.76757 -1.808988)
			(end 11.782044 -3.74142)
			(stroke
				(width 0.1)
				(type default)
			)
			(layer "F.SilkS")
		)
		(fp_line
			(start 9.76757 -1.808988)
			(end 11.782044 -3.74142)
			(stroke
				(width 0.1)
				(type default)
			)
			(layer "F.SilkS")
		)
		(fp_line
			(start 9.768586 -2.214118)
			(end 11.319002 -3.701288)
			(stroke
				(width 0.1)
				(type default)
			)
			(layer "F.SilkS")
		)
		(fp_line
			(start 9.768586 -2.214118)
			(end 11.319002 -3.701288)
			(stroke
				(width 0.1)
				(type default)
			)
			(layer "F.SilkS")
		)
		(fp_line
			(start 9.77646 -1.759712)
			(end 11.83894 -3.738372)
			(stroke
				(width 0.1)
				(type default)
			)
			(layer "F.SilkS")
		)
		(fp_line
			(start 9.77646 -1.759712)
			(end 11.83894 -3.738372)
			(stroke
				(width 0.1)
				(type default)
			)
			(layer "F.SilkS")
		)
		(fp_line
			(start 9.777222 -2.279904)
			(end 11.24331 -3.686556)
			(stroke
				(width 0.1)
				(type default)
			)
			(layer "F.SilkS")
		)
		(fp_line
			(start 9.777222 -2.279904)
			(end 11.24331 -3.686556)
			(stroke
				(width 0.1)
				(type default)
			)
			(layer "F.SilkS")
		)
		(fp_line
			(start 9.78662 -1.711706)
			(end 11.89609 -3.735324)
			(stroke
				(width 0.1)
				(type default)
			)
			(layer "F.SilkS")
		)
		(fp_line
			(start 9.78662 -1.711706)
			(end 11.89609 -3.735324)
			(stroke
				(width 0.1)
				(type default)
			)
			(layer "F.SilkS")
		)
		(fp_line
			(start 9.79043 -2.350262)
			(end 11.167872 -3.67157)
			(stroke
				(width 0.1)
				(type default)
			)
			(layer "F.SilkS")
		)
		(fp_line
			(start 9.79043 -2.350262)
			(end 11.167872 -3.67157)
			(stroke
				(width 0.1)
				(type default)
			)
			(layer "F.SilkS")
		)
		(fp_line
			(start 9.797034 -1.663954)
			(end 11.952986 -3.732276)
			(stroke
				(width 0.1)
				(type default)
			)
			(layer "F.SilkS")
		)
		(fp_line
			(start 9.797034 -1.663954)
			(end 11.952986 -3.732276)
			(stroke
				(width 0.1)
				(type default)
			)
			(layer "F.SilkS")
		)
		(fp_line
			(start 9.809988 -1.618742)
			(end 12.010136 -3.729482)
			(stroke
				(width 0.1)
				(type default)
			)
			(layer "F.SilkS")
		)
		(fp_line
			(start 9.809988 -1.618742)
			(end 12.010136 -3.729482)
			(stroke
				(width 0.1)
				(type default)
			)
			(layer "F.SilkS")
		)
		(fp_line
			(start 9.812528 -2.429256)
			(end 11.09218 -3.656838)
			(stroke
				(width 0.1)
				(type default)
			)
			(layer "F.SilkS")
		)
		(fp_line
			(start 9.812528 -2.429256)
			(end 11.09218 -3.656838)
			(stroke
				(width 0.1)
				(type default)
			)
			(layer "F.SilkS")
		)
		(fp_line
			(start 9.825228 -1.575562)
			(end 12.063984 -3.723132)
			(stroke
				(width 0.1)
				(type default)
			)
			(layer "F.SilkS")
		)
		(fp_line
			(start 9.825228 -1.575562)
			(end 12.063984 -3.723132)
			(stroke
				(width 0.1)
				(type default)
			)
			(layer "F.SilkS")
		)
		(fp_line
			(start 9.834626 -2.507996)
			(end 11.00201 -3.627882)
			(stroke
				(width 0.1)
				(type default)
			)
			(layer "F.SilkS")
		)
		(fp_line
			(start 9.834626 -2.507996)
			(end 11.00201 -3.627882)
			(stroke
				(width 0.1)
				(type default)
			)
			(layer "F.SilkS")
		)
		(fp_line
			(start 9.840214 -1.532382)
			(end 12.115038 -3.714496)
			(stroke
				(width 0.1)
				(type default)
			)
			(layer "F.SilkS")
		)
		(fp_line
			(start 9.840214 -1.532382)
			(end 12.115038 -3.714496)
			(stroke
				(width 0.1)
				(type default)
			)
			(layer "F.SilkS")
		)
		(fp_line
			(start 9.856978 -2.587244)
			(end 10.90676 -3.594354)
			(stroke
				(width 0.1)
				(type default)
			)
			(layer "F.SilkS")
		)
		(fp_line
			(start 9.856978 -2.587244)
			(end 10.90676 -3.594354)
			(stroke
				(width 0.1)
				(type default)
			)
			(layer "F.SilkS")
		)
		(fp_line
			(start 9.857232 -1.49098)
			(end 12.165838 -3.705352)
			(stroke
				(width 0.1)
				(type default)
			)
			(layer "F.SilkS")
		)
		(fp_line
			(start 9.857232 -1.49098)
			(end 12.165838 -3.705352)
			(stroke
				(width 0.1)
				(type default)
			)
			(layer "F.SilkS")
		)
		(fp_line
			(start 9.87679 -1.452118)
			(end 10.97661 -2.50698)
			(stroke
				(width 0.1)
				(type default)
			)
			(layer "F.SilkS")
		)
		(fp_line
			(start 9.87679 -1.452118)
			(end 10.97661 -2.50698)
			(stroke
				(width 0.1)
				(type default)
			)
			(layer "F.SilkS")
		)
		(fp_line
			(start 9.884664 -2.671572)
			(end 10.811764 -3.560826)
			(stroke
				(width 0.1)
				(type default)
			)
			(layer "F.SilkS")
		)
		(fp_line
			(start 9.884664 -2.671572)
			(end 10.811764 -3.560826)
			(stroke
				(width 0.1)
				(type default)
			)
			(layer "F.SilkS")
		)
		(fp_line
			(start 9.896602 -1.413256)
			(end 10.944606 -2.418588)
			(stroke
				(width 0.1)
				(type default)
			)
			(layer "F.SilkS")
		)
		(fp_line
			(start 9.896602 -1.413256)
			(end 10.944606 -2.418588)
			(stroke
				(width 0.1)
				(type default)
			)
			(layer "F.SilkS")
		)
		(fp_line
			(start 9.916922 -1.375156)
			(end 10.912856 -2.33045)
			(stroke
				(width 0.1)
				(type default)
			)
			(layer "F.SilkS")
		)
		(fp_line
			(start 9.916922 -1.375156)
			(end 10.912856 -2.33045)
			(stroke
				(width 0.1)
				(type default)
			)
			(layer "F.SilkS")
		)
		(fp_line
			(start 9.940798 -1.340358)
			(end 10.903712 -2.263902)
			(stroke
				(width 0.1)
				(type default)
			)
			(layer "F.SilkS")
		)
		(fp_line
			(start 9.940798 -1.340358)
			(end 10.903712 -2.263902)
			(stroke
				(width 0.1)
				(type default)
			)
			(layer "F.SilkS")
		)
		(fp_line
			(start 9.945116 -2.787142)
			(end 10.69721 -3.508502)
			(stroke
				(width 0.1)
				(type default)
			)
			(layer "F.SilkS")
		)
		(fp_line
			(start 9.945116 -2.787142)
			(end 10.69721 -3.508502)
			(stroke
				(width 0.1)
				(type default)
			)
			(layer "F.SilkS")
		)
		(fp_line
			(start 9.964674 -1.30556)
			(end 10.898632 -2.201418)
			(stroke
				(width 0.1)
				(type default)
			)
			(layer "F.SilkS")
		)
		(fp_line
			(start 9.964674 -1.30556)
			(end 10.898632 -2.201418)
			(stroke
				(width 0.1)
				(type default)
			)
			(layer "F.SilkS")
		)
		(fp_line
			(start 9.98855 -1.270508)
			(end 10.902442 -2.147316)
			(stroke
				(width 0.1)
				(type default)
			)
			(layer "F.SilkS")
		)
		(fp_line
			(start 9.98855 -1.270508)
			(end 10.902442 -2.147316)
			(stroke
				(width 0.1)
				(type default)
			)
			(layer "F.SilkS")
		)
		(fp_line
			(start 10.005568 -2.902966)
			(end 10.557002 -3.431794)
			(stroke
				(width 0.1)
				(type default)
			)
			(layer "F.SilkS")
		)
		(fp_line
			(start 10.005568 -2.902966)
			(end 10.557002 -3.431794)
			(stroke
				(width 0.1)
				(type default)
			)
			(layer "F.SilkS")
		)
		(fp_line
			(start 10.015982 -1.239266)
			(end 10.90803 -2.094992)
			(stroke
				(width 0.1)
				(type default)
			)
			(layer "F.SilkS")
		)
		(fp_line
			(start 10.015982 -1.239266)
			(end 10.90803 -2.094992)
			(stroke
				(width 0.1)
				(type default)
			)
			(layer "F.SilkS")
		)
		(fp_line
			(start 10.043668 -1.208278)
			(end 10.921238 -2.04978)
			(stroke
				(width 0.1)
				(type default)
			)
			(layer "F.SilkS")
		)
		(fp_line
			(start 10.043668 -1.208278)
			(end 10.921238 -2.04978)
			(stroke
				(width 0.1)
				(type default)
			)
			(layer "F.SilkS")
		)
		(fp_line
			(start 10.071608 -1.17729)
			(end 10.9347 -2.00533)
			(stroke
				(width 0.1)
				(type default)
			)
			(layer "F.SilkS")
		)
		(fp_line
			(start 10.071608 -1.17729)
			(end 10.9347 -2.00533)
			(stroke
				(width 0.1)
				(type default)
			)
			(layer "F.SilkS")
		)
		(fp_line
			(start 10.102088 -1.148588)
			(end 10.956798 -1.9685)
			(stroke
				(width 0.1)
				(type default)
			)
			(layer "F.SilkS")
		)
		(fp_line
			(start 10.102088 -1.148588)
			(end 10.956798 -1.9685)
			(stroke
				(width 0.1)
				(type default)
			)
			(layer "F.SilkS")
		)
		(fp_line
			(start 10.133584 -1.121156)
			(end 10.978642 -1.931924)
			(stroke
				(width 0.1)
				(type default)
			)
			(layer "F.SilkS")
		)
		(fp_line
			(start 10.133584 -1.121156)
			(end 10.978642 -1.931924)
			(stroke
				(width 0.1)
				(type default)
			)
			(layer "F.SilkS")
		)
		(fp_line
			(start 10.16508 -1.093724)
			(end 11.006582 -1.90119)
			(stroke
				(width 0.1)
				(type default)
			)
			(layer "F.SilkS")
		)
		(fp_line
			(start 10.16508 -1.093724)
			(end 11.006582 -1.90119)
			(stroke
				(width 0.1)
				(type default)
			)
			(layer "F.SilkS")
		)
		(fp_line
			(start 10.198354 -1.067816)
			(end 11.037062 -1.872742)
			(stroke
				(width 0.1)
				(type default)
			)
			(layer "F.SilkS")
		)
		(fp_line
			(start 10.198354 -1.067816)
			(end 11.037062 -1.872742)
			(stroke
				(width 0.1)
				(type default)
			)
			(layer "F.SilkS")
		)
		(fp_line
			(start 10.233406 -1.043686)
			(end 11.06932 -1.845818)
			(stroke
				(width 0.1)
				(type default)
			)
			(layer "F.SilkS")
		)
		(fp_line
			(start 10.233406 -1.043686)
			(end 11.06932 -1.845818)
			(stroke
				(width 0.1)
				(type default)
			)
			(layer "F.SilkS")
		)
		(fp_line
			(start 10.268458 -1.01981)
			(end 11.108182 -1.825244)
			(stroke
				(width 0.1)
				(type default)
			)
			(layer "F.SilkS")
		)
		(fp_line
			(start 10.268458 -1.01981)
			(end 11.108182 -1.825244)
			(stroke
				(width 0.1)
				(type default)
			)
			(layer "F.SilkS")
		)
		(fp_line
			(start 10.30478 -0.99695)
			(end 11.147044 -1.804924)
			(stroke
				(width 0.1)
				(type default)
			)
			(layer "F.SilkS")
		)
		(fp_line
			(start 10.30478 -0.99695)
			(end 11.147044 -1.804924)
			(stroke
				(width 0.1)
				(type default)
			)
			(layer "F.SilkS")
		)
		(fp_line
			(start 10.343388 -0.976122)
			(end 11.190478 -1.788922)
			(stroke
				(width 0.1)
				(type default)
			)
			(layer "F.SilkS")
		)
		(fp_line
			(start 10.343388 -0.976122)
			(end 11.190478 -1.788922)
			(stroke
				(width 0.1)
				(type default)
			)
			(layer "F.SilkS")
		)
		(fp_line
			(start 10.381996 -0.955548)
			(end 11.237722 -1.776476)
			(stroke
				(width 0.1)
				(type default)
			)
			(layer "F.SilkS")
		)
		(fp_line
			(start 10.381996 -0.955548)
			(end 11.237722 -1.776476)
			(stroke
				(width 0.1)
				(type default)
			)
			(layer "F.SilkS")
		)
		(fp_line
			(start 10.421366 -0.935482)
			(end 11.28522 -1.76403)
			(stroke
				(width 0.1)
				(type default)
			)
			(layer "F.SilkS")
		)
		(fp_line
			(start 10.421366 -0.935482)
			(end 11.28522 -1.76403)
			(stroke
				(width 0.1)
				(type default)
			)
			(layer "F.SilkS")
		)
		(fp_line
			(start 10.46353 -0.918464)
			(end 11.33856 -1.75768)
			(stroke
				(width 0.1)
				(type default)
			)
			(layer "F.SilkS")
		)
		(fp_line
			(start 10.46353 -0.918464)
			(end 11.33856 -1.75768)
			(stroke
				(width 0.1)
				(type default)
			)
			(layer "F.SilkS")
		)
		(fp_line
			(start 10.505694 -0.901192)
			(end 11.39444 -1.753616)
			(stroke
				(width 0.1)
				(type default)
			)
			(layer "F.SilkS")
		)
		(fp_line
			(start 10.505694 -0.901192)
			(end 11.39444 -1.753616)
			(stroke
				(width 0.1)
				(type default)
			)
			(layer "F.SilkS")
		)
		(fp_line
			(start 10.548366 -0.884682)
			(end 11.45032 -1.749552)
			(stroke
				(width 0.1)
				(type default)
			)
			(layer "F.SilkS")
		)
		(fp_line
			(start 10.548366 -0.884682)
			(end 11.45032 -1.749552)
			(stroke
				(width 0.1)
				(type default)
			)
			(layer "F.SilkS")
		)
		(fp_line
			(start 10.572496 -4.831842)
			(end 10.566146 -4.825746)
			(stroke
				(width 0.1)
				(type default)
			)
			(layer "F.SilkS")
		)
		(fp_line
			(start 10.572496 -4.831842)
			(end 10.566146 -4.825746)
			(stroke
				(width 0.1)
				(type default)
			)
			(layer "F.SilkS")
		)
		(fp_line
			(start 10.582148 -4.783328)
			(end 10.566146 -4.825746)
			(stroke
				(width 0.1)
				(type default)
			)
			(layer "F.SilkS")
		)
		(fp_line
			(start 10.582148 -4.783328)
			(end 10.566146 -4.825746)
			(stroke
				(width 0.1)
				(type default)
			)
			(layer "F.SilkS")
		)
		(fp_line
			(start 10.59434 -0.870712)
			(end 11.516614 -1.75514)
			(stroke
				(width 0.1)
				(type default)
			)
			(layer "F.SilkS")
		)
		(fp_line
			(start 10.59434 -0.870712)
			(end 11.516614 -1.75514)
			(stroke
				(width 0.1)
				(type default)
			)
			(layer "F.SilkS")
		)
		(fp_line
			(start 10.59815 -4.74091)
			(end 10.582148 -4.783328)
			(stroke
				(width 0.1)
				(type default)
			)
			(layer "F.SilkS")
		)
		(fp_line
			(start 10.59815 -4.74091)
			(end 10.582148 -4.783328)
			(stroke
				(width 0.1)
				(type default)
			)
			(layer "F.SilkS")
		)
		(fp_line
			(start 10.613898 -4.698746)
			(end 10.59815 -4.74091)
			(stroke
				(width 0.1)
				(type default)
			)
			(layer "F.SilkS")
		)
		(fp_line
			(start 10.613898 -4.698746)
			(end 10.59815 -4.74091)
			(stroke
				(width 0.1)
				(type default)
			)
			(layer "F.SilkS")
		)
		(fp_line
			(start 10.613898 -4.698746)
			(end 10.6299 -4.656074)
			(stroke
				(width 0.1)
				(type default)
			)
			(layer "F.SilkS")
		)
		(fp_line
			(start 10.613898 -4.698746)
			(end 10.6299 -4.656074)
			(stroke
				(width 0.1)
				(type default)
			)
			(layer "F.SilkS")
		)
		(fp_line
			(start 10.6299 -4.656074)
			(end 10.645902 -4.613656)
			(stroke
				(width 0.1)
				(type default)
			)
			(layer "F.SilkS")
		)
		(fp_line
			(start 10.6299 -4.656074)
			(end 10.645902 -4.613656)
			(stroke
				(width 0.1)
				(type default)
			)
			(layer "F.SilkS")
		)
		(fp_line
			(start 10.64006 -0.856996)
			(end 11.585448 -1.763522)
			(stroke
				(width 0.1)
				(type default)
			)
			(layer "F.SilkS")
		)
		(fp_line
			(start 10.64006 -0.856996)
			(end 11.585448 -1.763522)
			(stroke
				(width 0.1)
				(type default)
			)
			(layer "F.SilkS")
		)
		(fp_line
			(start 10.645902 -4.613656)
			(end 10.661904 -4.571492)
			(stroke
				(width 0.1)
				(type default)
			)
			(layer "F.SilkS")
		)
		(fp_line
			(start 10.645902 -4.613656)
			(end 10.661904 -4.571492)
			(stroke
				(width 0.1)
				(type default)
			)
			(layer "F.SilkS")
		)
		(fp_line
			(start 10.661904 -4.571492)
			(end 10.677906 -4.529074)
			(stroke
				(width 0.1)
				(type default)
			)
			(layer "F.SilkS")
		)
		(fp_line
			(start 10.661904 -4.571492)
			(end 10.677906 -4.529074)
			(stroke
				(width 0.1)
				(type default)
			)
			(layer "F.SilkS")
		)
		(fp_line
			(start 10.677906 -4.529074)
			(end 10.693908 -4.486402)
			(stroke
				(width 0.1)
				(type default)
			)
			(layer "F.SilkS")
		)
		(fp_line
			(start 10.677906 -4.529074)
			(end 10.693908 -4.486402)
			(stroke
				(width 0.1)
				(type default)
			)
			(layer "F.SilkS")
		)
		(fp_line
			(start 10.686542 -0.843534)
			(end 11.654282 -1.772158)
			(stroke
				(width 0.1)
				(type default)
			)
			(layer "F.SilkS")
		)
		(fp_line
			(start 10.686542 -0.843534)
			(end 11.654282 -1.772158)
			(stroke
				(width 0.1)
				(type default)
			)
			(layer "F.SilkS")
		)
		(fp_line
			(start 10.693908 -4.486402)
			(end 10.709656 -4.443984)
			(stroke
				(width 0.1)
				(type default)
			)
			(layer "F.SilkS")
		)
		(fp_line
			(start 10.693908 -4.486402)
			(end 10.709656 -4.443984)
			(stroke
				(width 0.1)
				(type default)
			)
			(layer "F.SilkS")
		)
		(fp_line
			(start 10.698734 -4.895088)
			(end 10.582148 -4.783328)
			(stroke
				(width 0.1)
				(type default)
			)
			(layer "F.SilkS")
		)
		(fp_line
			(start 10.698734 -4.895088)
			(end 10.582148 -4.783328)
			(stroke
				(width 0.1)
				(type default)
			)
			(layer "F.SilkS")
		)
		(fp_line
			(start 10.709656 -4.443984)
			(end 10.725658 -4.40182)
			(stroke
				(width 0.1)
				(type default)
			)
			(layer "F.SilkS")
		)
		(fp_line
			(start 10.709656 -4.443984)
			(end 10.725658 -4.40182)
			(stroke
				(width 0.1)
				(type default)
			)
			(layer "F.SilkS")
		)
		(fp_line
			(start 10.725658 -4.40182)
			(end 10.74166 -4.359402)
			(stroke
				(width 0.1)
				(type default)
			)
			(layer "F.SilkS")
		)
		(fp_line
			(start 10.725658 -4.40182)
			(end 10.74166 -4.359402)
			(stroke
				(width 0.1)
				(type default)
			)
			(layer "F.SilkS")
		)
		(fp_line
			(start 10.736072 -0.833628)
			(end 11.723116 -1.78054)
			(stroke
				(width 0.1)
				(type default)
			)
			(layer "F.SilkS")
		)
		(fp_line
			(start 10.736072 -0.833628)
			(end 11.723116 -1.78054)
			(stroke
				(width 0.1)
				(type default)
			)
			(layer "F.SilkS")
		)
		(fp_line
			(start 10.74166 -4.359402)
			(end 10.757662 -4.316984)
			(stroke
				(width 0.1)
				(type default)
			)
			(layer "F.SilkS")
		)
		(fp_line
			(start 10.74166 -4.359402)
			(end 10.757662 -4.316984)
			(stroke
				(width 0.1)
				(type default)
			)
			(layer "F.SilkS")
		)
		(fp_line
			(start 10.757662 -4.316984)
			(end 10.773664 -4.274566)
			(stroke
				(width 0.1)
				(type default)
			)
			(layer "F.SilkS")
		)
		(fp_line
			(start 10.757662 -4.316984)
			(end 10.773664 -4.274566)
			(stroke
				(width 0.1)
				(type default)
			)
			(layer "F.SilkS")
		)
		(fp_line
			(start 10.773664 -4.274566)
			(end 10.789666 -4.232148)
			(stroke
				(width 0.1)
				(type default)
			)
			(layer "F.SilkS")
		)
		(fp_line
			(start 10.773664 -4.274566)
			(end 10.789666 -4.232148)
			(stroke
				(width 0.1)
				(type default)
			)
			(layer "F.SilkS")
		)
		(fp_line
			(start 10.785602 -0.823214)
			(end 11.818112 -1.813814)
			(stroke
				(width 0.1)
				(type default)
			)
			(layer "F.SilkS")
		)
		(fp_line
			(start 10.785602 -0.823214)
			(end 11.818112 -1.813814)
			(stroke
				(width 0.1)
				(type default)
			)
			(layer "F.SilkS")
		)
		(fp_line
			(start 10.789666 -4.232148)
			(end 10.805414 -4.18973)
			(stroke
				(width 0.1)
				(type default)
			)
			(layer "F.SilkS")
		)
		(fp_line
			(start 10.789666 -4.232148)
			(end 10.805414 -4.18973)
			(stroke
				(width 0.1)
				(type default)
			)
			(layer "F.SilkS")
		)
		(fp_line
			(start 10.805414 -4.18973)
			(end 10.821416 -4.147312)
			(stroke
				(width 0.1)
				(type default)
			)
			(layer "F.SilkS")
		)
		(fp_line
			(start 10.805414 -4.18973)
			(end 10.821416 -4.147312)
			(stroke
				(width 0.1)
				(type default)
			)
			(layer "F.SilkS")
		)
		(fp_line
			(start 10.818368 -4.952492)
			(end 10.59815 -4.74091)
			(stroke
				(width 0.1)
				(type default)
			)
			(layer "F.SilkS")
		)
		(fp_line
			(start 10.818368 -4.952492)
			(end 10.59815 -4.74091)
			(stroke
				(width 0.1)
				(type default)
			)
			(layer "F.SilkS")
		)
		(fp_line
			(start 10.821416 -4.147312)
			(end 10.837418 -4.104894)
			(stroke
				(width 0.1)
				(type default)
			)
			(layer "F.SilkS")
		)
		(fp_line
			(start 10.821416 -4.147312)
			(end 10.837418 -4.104894)
			(stroke
				(width 0.1)
				(type default)
			)
			(layer "F.SilkS")
		)
		(fp_line
			(start 10.836402 -0.814324)
			(end 11.91514 -1.84912)
			(stroke
				(width 0.1)
				(type default)
			)
			(layer "F.SilkS")
		)
		(fp_line
			(start 10.836402 -0.814324)
			(end 11.91514 -1.84912)
			(stroke
				(width 0.1)
				(type default)
			)
			(layer "F.SilkS")
		)
		(fp_line
			(start 10.837418 -4.104894)
			(end 10.85342 -4.062476)
			(stroke
				(width 0.1)
				(type default)
			)
			(layer "F.SilkS")
		)
		(fp_line
			(start 10.837418 -4.104894)
			(end 10.85342 -4.062476)
			(stroke
				(width 0.1)
				(type default)
			)
			(layer "F.SilkS")
		)
		(fp_line
			(start 10.889742 -0.808228)
			(end 12.047474 -1.918462)
			(stroke
				(width 0.1)
				(type default)
			)
			(layer "F.SilkS")
		)
		(fp_line
			(start 10.889742 -0.808228)
			(end 12.047474 -1.918462)
			(stroke
				(width 0.1)
				(type default)
			)
			(layer "F.SilkS")
		)
		(fp_line
			(start 10.931144 -5.002784)
			(end 10.613898 -4.698746)
			(stroke
				(width 0.1)
				(type default)
			)
			(layer "F.SilkS")
		)
		(fp_line
			(start 10.931144 -5.002784)
			(end 10.613898 -4.698746)
			(stroke
				(width 0.1)
				(type default)
			)
			(layer "F.SilkS")
		)
		(fp_line
			(start 10.99947 -0.797814)
			(end 13.653516 -3.343402)
			(stroke
				(width 0.1)
				(type default)
			)
			(layer "F.SilkS")
		)
		(fp_line
			(start 10.99947 -0.797814)
			(end 13.653516 -3.343402)
			(stroke
				(width 0.1)
				(type default)
			)
			(layer "F.SilkS")
		)
		(fp_line
			(start 11.03503 -5.044694)
			(end 10.6299 -4.656074)
			(stroke
				(width 0.1)
				(type default)
			)
			(layer "F.SilkS")
		)
		(fp_line
			(start 11.03503 -5.044694)
			(end 10.6299 -4.656074)
			(stroke
				(width 0.1)
				(type default)
			)
			(layer "F.SilkS")
		)
		(fp_line
			(start 11.057382 -0.795274)
			(end 13.64107 -3.27406)
			(stroke
				(width 0.1)
				(type default)
			)
			(layer "F.SilkS")
		)
		(fp_line
			(start 11.057382 -0.795274)
			(end 13.64107 -3.27406)
			(stroke
				(width 0.1)
				(type default)
			)
			(layer "F.SilkS")
		)
		(fp_line
			(start 11.11504 -0.792988)
			(end 13.629132 -3.204972)
			(stroke
				(width 0.1)
				(type default)
			)
			(layer "F.SilkS")
		)
		(fp_line
			(start 11.11504 -0.792988)
			(end 13.629132 -3.204972)
			(stroke
				(width 0.1)
				(type default)
			)
			(layer "F.SilkS")
		)
		(fp_line
			(start 11.13536 -5.083048)
			(end 10.645902 -4.613656)
			(stroke
				(width 0.1)
				(type default)
			)
			(layer "F.SilkS")
		)
		(fp_line
			(start 11.13536 -5.083048)
			(end 10.645902 -4.613656)
			(stroke
				(width 0.1)
				(type default)
			)
			(layer "F.SilkS")
		)
		(fp_line
			(start 11.182096 -0.799846)
			(end 13.61694 -3.135376)
			(stroke
				(width 0.1)
				(type default)
			)
			(layer "F.SilkS")
		)
		(fp_line
			(start 11.182096 -0.799846)
			(end 13.61694 -3.135376)
			(stroke
				(width 0.1)
				(type default)
			)
			(layer "F.SilkS")
		)
		(fp_line
			(start 11.226546 -5.11302)
			(end 10.661904 -4.571492)
			(stroke
				(width 0.1)
				(type default)
			)
			(layer "F.SilkS")
		)
		(fp_line
			(start 11.226546 -5.11302)
			(end 10.661904 -4.571492)
			(stroke
				(width 0.1)
				(type default)
			)
			(layer "F.SilkS")
		)
		(fp_line
			(start 11.246612 -2.76606)
			(end 12.216638 -3.696716)
			(stroke
				(width 0.1)
				(type default)
			)
			(layer "F.SilkS")
		)
		(fp_line
			(start 11.246612 -2.76606)
			(end 12.216638 -3.696716)
			(stroke
				(width 0.1)
				(type default)
			)
			(layer "F.SilkS")
		)
		(fp_line
			(start 11.248898 -0.805942)
			(end 13.604494 -3.06578)
			(stroke
				(width 0.1)
				(type default)
			)
			(layer "F.SilkS")
		)
		(fp_line
			(start 11.248898 -0.805942)
			(end 13.604494 -3.06578)
			(stroke
				(width 0.1)
				(type default)
			)
			(layer "F.SilkS")
		)
		(fp_line
			(start 11.315446 -5.140706)
			(end 10.677906 -4.529074)
			(stroke
				(width 0.1)
				(type default)
			)
			(layer "F.SilkS")
		)
		(fp_line
			(start 11.315446 -5.140706)
			(end 10.677906 -4.529074)
			(stroke
				(width 0.1)
				(type default)
			)
			(layer "F.SilkS")
		)
		(fp_line
			(start 11.315954 -0.813054)
			(end 13.592556 -2.996692)
			(stroke
				(width 0.1)
				(type default)
			)
			(layer "F.SilkS")
		)
		(fp_line
			(start 11.315954 -0.813054)
			(end 13.592556 -2.996692)
			(stroke
				(width 0.1)
				(type default)
			)
			(layer "F.SilkS")
		)
		(fp_line
			(start 11.364722 -2.821686)
			(end 12.265914 -3.686302)
			(stroke
				(width 0.1)
				(type default)
			)
			(layer "F.SilkS")
		)
		(fp_line
			(start 11.364722 -2.821686)
			(end 12.265914 -3.686302)
			(stroke
				(width 0.1)
				(type default)
			)
			(layer "F.SilkS")
		)
		(fp_line
			(start 11.382756 -0.81915)
			(end 13.580364 -2.927096)
			(stroke
				(width 0.1)
				(type default)
			)
			(layer "F.SilkS")
		)
		(fp_line
			(start 11.382756 -0.81915)
			(end 13.580364 -2.927096)
			(stroke
				(width 0.1)
				(type default)
			)
			(layer "F.SilkS")
		)
		(fp_line
			(start 11.398758 -5.163058)
			(end 10.693908 -4.486402)
			(stroke
				(width 0.1)
				(type default)
			)
			(layer "F.SilkS")
		)
		(fp_line
			(start 11.398758 -5.163058)
			(end 10.693908 -4.486402)
			(stroke
				(width 0.1)
				(type default)
			)
			(layer "F.SilkS")
		)
		(fp_line
			(start 11.436096 -2.832354)
			(end 12.31138 -3.672078)
			(stroke
				(width 0.1)
				(type default)
			)
			(layer "F.SilkS")
		)
		(fp_line
			(start 11.436096 -2.832354)
			(end 12.31138 -3.672078)
			(stroke
				(width 0.1)
				(type default)
			)
			(layer "F.SilkS")
		)
		(fp_line
			(start 11.460734 -0.836422)
			(end 13.568172 -2.857754)
			(stroke
				(width 0.1)
				(type default)
			)
			(layer "F.SilkS")
		)
		(fp_line
			(start 11.460734 -0.836422)
			(end 13.568172 -2.857754)
			(stroke
				(width 0.1)
				(type default)
			)
			(layer "F.SilkS")
		)
		(fp_line
			(start 11.478514 -5.1816)
			(end 10.709656 -4.443984)
			(stroke
				(width 0.1)
				(type default)
			)
			(layer "F.SilkS")
		)
		(fp_line
			(start 11.478514 -5.1816)
			(end 10.709656 -4.443984)
			(stroke
				(width 0.1)
				(type default)
			)
			(layer "F.SilkS")
		)
		(fp_line
			(start 11.505184 -2.84099)
			(end 12.356592 -3.657854)
			(stroke
				(width 0.1)
				(type default)
			)
			(layer "F.SilkS")
		)
		(fp_line
			(start 11.505184 -2.84099)
			(end 12.356592 -3.657854)
			(stroke
				(width 0.1)
				(type default)
			)
			(layer "F.SilkS")
		)
		(fp_line
			(start 11.546332 -0.860552)
			(end 13.55598 -2.788412)
			(stroke
				(width 0.1)
				(type default)
			)
			(layer "F.SilkS")
		)
		(fp_line
			(start 11.546332 -0.860552)
			(end 13.55598 -2.788412)
			(stroke
				(width 0.1)
				(type default)
			)
			(layer "F.SilkS")
		)
		(fp_line
			(start 11.557762 -5.199888)
			(end 10.725658 -4.40182)
			(stroke
				(width 0.1)
				(type default)
			)
			(layer "F.SilkS")
		)
		(fp_line
			(start 11.557762 -5.199888)
			(end 10.725658 -4.40182)
			(stroke
				(width 0.1)
				(type default)
			)
			(layer "F.SilkS")
		)
		(fp_line
			(start 11.629898 -5.211572)
			(end 10.74166 -4.359402)
			(stroke
				(width 0.1)
				(type default)
			)
			(layer "F.SilkS")
		)
		(fp_line
			(start 11.629898 -5.211572)
			(end 10.74166 -4.359402)
			(stroke
				(width 0.1)
				(type default)
			)
			(layer "F.SilkS")
		)
		(fp_line
			(start 11.63193 -0.884936)
			(end 13.544042 -2.71907)
			(stroke
				(width 0.1)
				(type default)
			)
			(layer "F.SilkS")
		)
		(fp_line
			(start 11.63193 -0.884936)
			(end 13.544042 -2.71907)
			(stroke
				(width 0.1)
				(type default)
			)
			(layer "F.SilkS")
		)
		(fp_line
			(start 11.702034 -5.223002)
			(end 10.757662 -4.316984)
			(stroke
				(width 0.1)
				(type default)
			)
			(layer "F.SilkS")
		)
		(fp_line
			(start 11.702034 -5.223002)
			(end 10.757662 -4.316984)
			(stroke
				(width 0.1)
				(type default)
			)
			(layer "F.SilkS")
		)
		(fp_line
			(start 11.728704 -0.919988)
			(end 13.531596 -2.649728)
			(stroke
				(width 0.1)
				(type default)
			)
			(layer "F.SilkS")
		)
		(fp_line
			(start 11.728704 -0.919988)
			(end 13.531596 -2.649728)
			(stroke
				(width 0.1)
				(type default)
			)
			(layer "F.SilkS")
		)
		(fp_line
			(start 11.77417 -5.234178)
			(end 10.773664 -4.274566)
			(stroke
				(width 0.1)
				(type default)
			)
			(layer "F.SilkS")
		)
		(fp_line
			(start 11.77417 -5.234178)
			(end 10.773664 -4.274566)
			(stroke
				(width 0.1)
				(type default)
			)
			(layer "F.SilkS")
		)
		(fp_line
			(start 11.84021 -5.24002)
			(end 10.789666 -4.232148)
			(stroke
				(width 0.1)
				(type default)
			)
			(layer "F.SilkS")
		)
		(fp_line
			(start 11.84021 -5.24002)
			(end 10.789666 -4.232148)
			(stroke
				(width 0.1)
				(type default)
			)
			(layer "F.SilkS")
		)
		(fp_line
			(start 11.8491 -0.9779)
			(end 13.519404 -2.580386)
			(stroke
				(width 0.1)
				(type default)
			)
			(layer "F.SilkS")
		)
		(fp_line
			(start 11.8491 -0.9779)
			(end 13.519404 -2.580386)
			(stroke
				(width 0.1)
				(type default)
			)
			(layer "F.SilkS")
		)
		(fp_line
			(start 11.906504 -5.245862)
			(end 10.805414 -4.18973)
			(stroke
				(width 0.1)
				(type default)
			)
			(layer "F.SilkS")
		)
		(fp_line
			(start 11.906504 -5.245862)
			(end 10.805414 -4.18973)
			(stroke
				(width 0.1)
				(type default)
			)
			(layer "F.SilkS")
		)
		(fp_line
			(start 11.972798 -5.251958)
			(end 10.821416 -4.147312)
			(stroke
				(width 0.1)
				(type default)
			)
			(layer "F.SilkS")
		)
		(fp_line
			(start 11.972798 -5.251958)
			(end 10.821416 -4.147312)
			(stroke
				(width 0.1)
				(type default)
			)
			(layer "F.SilkS")
		)
		(fp_line
			(start 12.000738 -1.06553)
			(end 13.507466 -2.51079)
			(stroke
				(width 0.1)
				(type default)
			)
			(layer "F.SilkS")
		)
		(fp_line
			(start 12.000738 -1.06553)
			(end 13.507466 -2.51079)
			(stroke
				(width 0.1)
				(type default)
			)
			(layer "F.SilkS")
		)
		(fp_line
			(start 12.036806 -5.255514)
			(end 10.837418 -4.104894)
			(stroke
				(width 0.1)
				(type default)
			)
			(layer "F.SilkS")
		)
		(fp_line
			(start 12.036806 -5.255514)
			(end 10.837418 -4.104894)
			(stroke
				(width 0.1)
				(type default)
			)
			(layer "F.SilkS")
		)
		(fp_line
			(start 12.093956 -0.882904)
			(end 12.111228 -0.882904)
			(stroke
				(width 0.1)
				(type default)
			)
			(layer "F.SilkS")
		)
		(fp_line
			(start 12.093956 -0.882904)
			(end 12.111228 -0.882904)
			(stroke
				(width 0.1)
				(type default)
			)
			(layer "F.SilkS")
		)
		(fp_line
			(start 12.098528 -5.257038)
			(end 10.85342 -4.062476)
			(stroke
				(width 0.1)
				(type default)
			)
			(layer "F.SilkS")
		)
		(fp_line
			(start 12.098528 -5.257038)
			(end 10.85342 -4.062476)
			(stroke
				(width 0.1)
				(type default)
			)
			(layer "F.SilkS")
		)
		(fp_line
			(start 12.102592 -0.932434)
			(end 12.093956 -0.882904)
			(stroke
				(width 0.1)
				(type default)
			)
			(layer "F.SilkS")
		)
		(fp_line
			(start 12.102592 -0.932434)
			(end 12.093956 -0.882904)
			(stroke
				(width 0.1)
				(type default)
			)
			(layer "F.SilkS")
		)
		(fp_line
			(start 12.102592 -0.932434)
			(end 13.458444 -2.233422)
			(stroke
				(width 0.1)
				(type default)
			)
			(layer "F.SilkS")
		)
		(fp_line
			(start 12.102592 -0.932434)
			(end 13.458444 -2.233422)
			(stroke
				(width 0.1)
				(type default)
			)
			(layer "F.SilkS")
		)
		(fp_line
			(start 12.111228 -0.882904)
			(end 12.171172 -0.882904)
			(stroke
				(width 0.1)
				(type default)
			)
			(layer "F.SilkS")
		)
		(fp_line
			(start 12.111228 -0.882904)
			(end 12.171172 -0.882904)
			(stroke
				(width 0.1)
				(type default)
			)
			(layer "F.SilkS")
		)
		(fp_line
			(start 12.111228 -0.882904)
			(end 13.446506 -2.163826)
			(stroke
				(width 0.1)
				(type default)
			)
			(layer "F.SilkS")
		)
		(fp_line
			(start 12.111228 -0.882904)
			(end 13.446506 -2.163826)
			(stroke
				(width 0.1)
				(type default)
			)
			(layer "F.SilkS")
		)
		(fp_line
			(start 12.115038 -1.00203)
			(end 12.102592 -0.932434)
			(stroke
				(width 0.1)
				(type default)
			)
			(layer "F.SilkS")
		)
		(fp_line
			(start 12.115038 -1.00203)
			(end 12.102592 -0.932434)
			(stroke
				(width 0.1)
				(type default)
			)
			(layer "F.SilkS")
		)
		(fp_line
			(start 12.115038 -1.00203)
			(end 13.47089 -2.302764)
			(stroke
				(width 0.1)
				(type default)
			)
			(layer "F.SilkS")
		)
		(fp_line
			(start 12.115038 -1.00203)
			(end 13.47089 -2.302764)
			(stroke
				(width 0.1)
				(type default)
			)
			(layer "F.SilkS")
		)
		(fp_line
			(start 12.12723 -1.071626)
			(end 12.115038 -1.00203)
			(stroke
				(width 0.1)
				(type default)
			)
			(layer "F.SilkS")
		)
		(fp_line
			(start 12.12723 -1.071626)
			(end 12.115038 -1.00203)
			(stroke
				(width 0.1)
				(type default)
			)
			(layer "F.SilkS")
		)
		(fp_line
			(start 12.12723 -1.071626)
			(end 13.483082 -2.372106)
			(stroke
				(width 0.1)
				(type default)
			)
			(layer "F.SilkS")
		)
		(fp_line
			(start 12.12723 -1.071626)
			(end 13.483082 -2.372106)
			(stroke
				(width 0.1)
				(type default)
			)
			(layer "F.SilkS")
		)
		(fp_line
			(start 12.139676 -1.140968)
			(end 12.12723 -1.071626)
			(stroke
				(width 0.1)
				(type default)
			)
			(layer "F.SilkS")
		)
		(fp_line
			(start 12.139676 -1.140968)
			(end 12.12723 -1.071626)
			(stroke
				(width 0.1)
				(type default)
			)
			(layer "F.SilkS")
		)
		(fp_line
			(start 12.139676 -1.140968)
			(end 13.49502 -2.441448)
			(stroke
				(width 0.1)
				(type default)
			)
			(layer "F.SilkS")
		)
		(fp_line
			(start 12.139676 -1.140968)
			(end 13.49502 -2.441448)
			(stroke
				(width 0.1)
				(type default)
			)
			(layer "F.SilkS")
		)
		(fp_line
			(start 12.160504 -5.258816)
			(end 10.92708 -4.07543)
			(stroke
				(width 0.1)
				(type default)
			)
			(layer "F.SilkS")
		)
		(fp_line
			(start 12.160504 -5.258816)
			(end 10.92708 -4.07543)
			(stroke
				(width 0.1)
				(type default)
			)
			(layer "F.SilkS")
		)
		(fp_line
			(start 12.171172 -0.882904)
			(end 12.23137 -0.882904)
			(stroke
				(width 0.1)
				(type default)
			)
			(layer "F.SilkS")
		)
		(fp_line
			(start 12.171172 -0.882904)
			(end 12.23137 -0.882904)
			(stroke
				(width 0.1)
				(type default)
			)
			(layer "F.SilkS")
		)
		(fp_line
			(start 12.171172 -0.882904)
			(end 13.434314 -2.094738)
			(stroke
				(width 0.1)
				(type default)
			)
			(layer "F.SilkS")
		)
		(fp_line
			(start 12.171172 -0.882904)
			(end 13.434314 -2.094738)
			(stroke
				(width 0.1)
				(type default)
			)
			(layer "F.SilkS")
		)
		(fp_line
			(start 12.22248 -5.260594)
			(end 11.042904 -4.12877)
			(stroke
				(width 0.1)
				(type default)
			)
			(layer "F.SilkS")
		)
		(fp_line
			(start 12.22248 -5.260594)
			(end 11.042904 -4.12877)
			(stroke
				(width 0.1)
				(type default)
			)
			(layer "F.SilkS")
		)
		(fp_line
			(start 12.23137 -0.882904)
			(end 12.291568 -0.882904)
			(stroke
				(width 0.1)
				(type default)
			)
			(layer "F.SilkS")
		)
		(fp_line
			(start 12.23137 -0.882904)
			(end 12.291568 -0.882904)
			(stroke
				(width 0.1)
				(type default)
			)
			(layer "F.SilkS")
		)
		(fp_line
			(start 12.23137 -0.882904)
			(end 13.422122 -2.025396)
			(stroke
				(width 0.1)
				(type default)
			)
			(layer "F.SilkS")
		)
		(fp_line
			(start 12.23137 -0.882904)
			(end 13.422122 -2.025396)
			(stroke
				(width 0.1)
				(type default)
			)
			(layer "F.SilkS")
		)
		(fp_line
			(start 12.281408 -5.25907)
			(end 11.150092 -4.173728)
			(stroke
				(width 0.1)
				(type default)
			)
			(layer "F.SilkS")
		)
		(fp_line
			(start 12.281408 -5.25907)
			(end 11.150092 -4.173728)
			(stroke
				(width 0.1)
				(type default)
			)
			(layer "F.SilkS")
		)
		(fp_line
			(start 12.291568 -0.882904)
			(end 12.351512 -0.882904)
			(stroke
				(width 0.1)
				(type default)
			)
			(layer "F.SilkS")
		)
		(fp_line
			(start 12.291568 -0.882904)
			(end 12.351512 -0.882904)
			(stroke
				(width 0.1)
				(type default)
			)
			(layer "F.SilkS")
		)
		(fp_line
			(start 12.291568 -0.882904)
			(end 13.40993 -1.9558)
			(stroke
				(width 0.1)
				(type default)
			)
			(layer "F.SilkS")
		)
		(fp_line
			(start 12.291568 -0.882904)
			(end 13.40993 -1.9558)
			(stroke
				(width 0.1)
				(type default)
			)
			(layer "F.SilkS")
		)
		(fp_line
			(start 12.335002 -2.251964)
			(end 12.323064 -2.182622)
			(stroke
				(width 0.1)
				(type default)
			)
			(layer "F.SilkS")
		)
		(fp_line
			(start 12.335002 -2.251964)
			(end 12.323064 -2.182622)
			(stroke
				(width 0.1)
				(type default)
			)
			(layer "F.SilkS")
		)
		(fp_line
			(start 12.337542 -5.255514)
			(end 11.246358 -4.208526)
			(stroke
				(width 0.1)
				(type default)
			)
			(layer "F.SilkS")
		)
		(fp_line
			(start 12.337542 -5.255514)
			(end 11.246358 -4.208526)
			(stroke
				(width 0.1)
				(type default)
			)
			(layer "F.SilkS")
		)
		(fp_line
			(start 12.347194 -2.321306)
			(end 12.335002 -2.251964)
			(stroke
				(width 0.1)
				(type default)
			)
			(layer "F.SilkS")
		)
		(fp_line
			(start 12.347194 -2.321306)
			(end 12.335002 -2.251964)
			(stroke
				(width 0.1)
				(type default)
			)
			(layer "F.SilkS")
		)
		(fp_line
			(start 12.351512 -0.882904)
			(end 12.41171 -0.882904)
			(stroke
				(width 0.1)
				(type default)
			)
			(layer "F.SilkS")
		)
		(fp_line
			(start 12.351512 -0.882904)
			(end 12.41171 -0.882904)
			(stroke
				(width 0.1)
				(type default)
			)
			(layer "F.SilkS")
		)
		(fp_line
			(start 12.351512 -0.882904)
			(end 13.397992 -1.886458)
			(stroke
				(width 0.1)
				(type default)
			)
			(layer "F.SilkS")
		)
		(fp_line
			(start 12.351512 -0.882904)
			(end 13.397992 -1.886458)
			(stroke
				(width 0.1)
				(type default)
			)
			(layer "F.SilkS")
		)
		(fp_line
			(start 12.359386 -2.390902)
			(end 12.347194 -2.321306)
			(stroke
				(width 0.1)
				(type default)
			)
			(layer "F.SilkS")
		)
		(fp_line
			(start 12.359386 -2.390902)
			(end 12.347194 -2.321306)
			(stroke
				(width 0.1)
				(type default)
			)
			(layer "F.SilkS")
		)
		(fp_line
			(start 12.371578 -2.460244)
			(end 12.359386 -2.390902)
			(stroke
				(width 0.1)
				(type default)
			)
			(layer "F.SilkS")
		)
		(fp_line
			(start 12.371578 -2.460244)
			(end 12.359386 -2.390902)
			(stroke
				(width 0.1)
				(type default)
			)
			(layer "F.SilkS")
		)
		(fp_line
			(start 12.38377 -2.529586)
			(end 12.371578 -2.460244)
			(stroke
				(width 0.1)
				(type default)
			)
			(layer "F.SilkS")
		)
		(fp_line
			(start 12.38377 -2.529586)
			(end 12.371578 -2.460244)
			(stroke
				(width 0.1)
				(type default)
			)
			(layer "F.SilkS")
		)
		(fp_line
			(start 12.393676 -5.251704)
			(end 11.336782 -4.237736)
			(stroke
				(width 0.1)
				(type default)
			)
			(layer "F.SilkS")
		)
		(fp_line
			(start 12.393676 -5.251704)
			(end 11.336782 -4.237736)
			(stroke
				(width 0.1)
				(type default)
			)
			(layer "F.SilkS")
		)
		(fp_line
			(start 12.395962 -2.598928)
			(end 12.38377 -2.529586)
			(stroke
				(width 0.1)
				(type default)
			)
			(layer "F.SilkS")
		)
		(fp_line
			(start 12.395962 -2.598928)
			(end 12.38377 -2.529586)
			(stroke
				(width 0.1)
				(type default)
			)
			(layer "F.SilkS")
		)
		(fp_line
			(start 12.401804 -3.64363)
			(end 11.574526 -2.849626)
			(stroke
				(width 0.1)
				(type default)
			)
			(layer "F.SilkS")
		)
		(fp_line
			(start 12.401804 -3.64363)
			(end 11.574526 -2.849626)
			(stroke
				(width 0.1)
				(type default)
			)
			(layer "F.SilkS")
		)
		(fp_line
			(start 12.408154 -2.668524)
			(end 12.395962 -2.598928)
			(stroke
				(width 0.1)
				(type default)
			)
			(layer "F.SilkS")
		)
		(fp_line
			(start 12.408154 -2.668524)
			(end 12.395962 -2.598928)
			(stroke
				(width 0.1)
				(type default)
			)
			(layer "F.SilkS")
		)
		(fp_line
			(start 12.41171 -0.882904)
			(end 12.471908 -0.882904)
			(stroke
				(width 0.1)
				(type default)
			)
			(layer "F.SilkS")
		)
		(fp_line
			(start 12.41171 -0.882904)
			(end 12.471908 -0.882904)
			(stroke
				(width 0.1)
				(type default)
			)
			(layer "F.SilkS")
		)
		(fp_line
			(start 12.41171 -0.882904)
			(end 13.385546 -1.817116)
			(stroke
				(width 0.1)
				(type default)
			)
			(layer "F.SilkS")
		)
		(fp_line
			(start 12.41171 -0.882904)
			(end 13.385546 -1.817116)
			(stroke
				(width 0.1)
				(type default)
			)
			(layer "F.SilkS")
		)
		(fp_line
			(start 12.445238 -3.62712)
			(end 11.643614 -2.858262)
			(stroke
				(width 0.1)
				(type default)
			)
			(layer "F.SilkS")
		)
		(fp_line
			(start 12.445238 -3.62712)
			(end 11.643614 -2.858262)
			(stroke
				(width 0.1)
				(type default)
			)
			(layer "F.SilkS")
		)
		(fp_line
			(start 12.44981 -5.24764)
			(end 11.421364 -4.261104)
			(stroke
				(width 0.1)
				(type default)
			)
			(layer "F.SilkS")
		)
		(fp_line
			(start 12.44981 -5.24764)
			(end 11.421364 -4.261104)
			(stroke
				(width 0.1)
				(type default)
			)
			(layer "F.SilkS")
		)
		(fp_line
			(start 12.471908 -0.882904)
			(end 12.53236 -0.882904)
			(stroke
				(width 0.1)
				(type default)
			)
			(layer "F.SilkS")
		)
		(fp_line
			(start 12.471908 -0.882904)
			(end 12.53236 -0.882904)
			(stroke
				(width 0.1)
				(type default)
			)
			(layer "F.SilkS")
		)
		(fp_line
			(start 12.471908 -0.882904)
			(end 13.373354 -1.74752)
			(stroke
				(width 0.1)
				(type default)
			)
			(layer "F.SilkS")
		)
		(fp_line
			(start 12.471908 -0.882904)
			(end 13.373354 -1.74752)
			(stroke
				(width 0.1)
				(type default)
			)
			(layer "F.SilkS")
		)
		(fp_line
			(start 12.485624 -3.608324)
			(end 11.704574 -2.859278)
			(stroke
				(width 0.1)
				(type default)
			)
			(layer "F.SilkS")
		)
		(fp_line
			(start 12.485624 -3.608324)
			(end 11.704574 -2.859278)
			(stroke
				(width 0.1)
				(type default)
			)
			(layer "F.SilkS")
		)
		(fp_line
			(start 12.506198 -5.24383)
			(end 11.499596 -4.278376)
			(stroke
				(width 0.1)
				(type default)
			)
			(layer "F.SilkS")
		)
		(fp_line
			(start 12.506198 -5.24383)
			(end 11.499596 -4.278376)
			(stroke
				(width 0.1)
				(type default)
			)
			(layer "F.SilkS")
		)
		(fp_line
			(start 12.52601 -3.589274)
			(end 11.763502 -2.858008)
			(stroke
				(width 0.1)
				(type default)
			)
			(layer "F.SilkS")
		)
		(fp_line
			(start 12.52601 -3.589274)
			(end 11.763502 -2.858008)
			(stroke
				(width 0.1)
				(type default)
			)
			(layer "F.SilkS")
		)
		(fp_line
			(start 12.53236 -0.882904)
			(end 12.592558 -0.882904)
			(stroke
				(width 0.1)
				(type default)
			)
			(layer "F.SilkS")
		)
		(fp_line
			(start 12.53236 -0.882904)
			(end 12.592558 -0.882904)
			(stroke
				(width 0.1)
				(type default)
			)
			(layer "F.SilkS")
		)
		(fp_line
			(start 12.53236 -0.882904)
			(end 13.361416 -1.678178)
			(stroke
				(width 0.1)
				(type default)
			)
			(layer "F.SilkS")
		)
		(fp_line
			(start 12.53236 -0.882904)
			(end 13.361416 -1.678178)
			(stroke
				(width 0.1)
				(type default)
			)
			(layer "F.SilkS")
		)
		(fp_line
			(start 12.562078 -5.24002)
			(end 11.575542 -4.293616)
			(stroke
				(width 0.1)
				(type default)
			)
			(layer "F.SilkS")
		)
		(fp_line
			(start 12.562078 -5.24002)
			(end 11.575542 -4.293616)
			(stroke
				(width 0.1)
				(type default)
			)
			(layer "F.SilkS")
		)
		(fp_line
			(start 12.590018 -3.708654)
			(end 12.57808 -3.639312)
			(stroke
				(width 0.1)
				(type default)
			)
			(layer "F.SilkS")
		)
		(fp_line
			(start 12.590018 -3.708654)
			(end 12.57808 -3.639312)
			(stroke
				(width 0.1)
				(type default)
			)
			(layer "F.SilkS")
		)
		(fp_line
			(start 12.592558 -0.882904)
			(end 12.652502 -0.882904)
			(stroke
				(width 0.1)
				(type default)
			)
			(layer "F.SilkS")
		)
		(fp_line
			(start 12.592558 -0.882904)
			(end 12.652502 -0.882904)
			(stroke
				(width 0.1)
				(type default)
			)
			(layer "F.SilkS")
		)
		(fp_line
			(start 12.592558 -0.882904)
			(end 13.34897 -1.608836)
			(stroke
				(width 0.1)
				(type default)
			)
			(layer "F.SilkS")
		)
		(fp_line
			(start 12.592558 -0.882904)
			(end 13.34897 -1.608836)
			(stroke
				(width 0.1)
				(type default)
			)
			(layer "F.SilkS")
		)
		(fp_line
			(start 12.601956 -3.777996)
			(end 12.590018 -3.708654)
			(stroke
				(width 0.1)
				(type default)
			)
			(layer "F.SilkS")
		)
		(fp_line
			(start 12.601956 -3.777996)
			(end 12.590018 -3.708654)
			(stroke
				(width 0.1)
				(type default)
			)
			(layer "F.SilkS")
		)
		(fp_line
			(start 12.618212 -5.23621)
			(end 11.6459 -4.303268)
			(stroke
				(width 0.1)
				(type default)
			)
			(layer "F.SilkS")
		)
		(fp_line
			(start 12.618212 -5.23621)
			(end 11.6459 -4.303268)
			(stroke
				(width 0.1)
				(type default)
			)
			(layer "F.SilkS")
		)
		(fp_line
			(start 12.652502 -0.882904)
			(end 12.7127 -0.882904)
			(stroke
				(width 0.1)
				(type default)
			)
			(layer "F.SilkS")
		)
		(fp_line
			(start 12.652502 -0.882904)
			(end 12.7127 -0.882904)
			(stroke
				(width 0.1)
				(type default)
			)
			(layer "F.SilkS")
		)
		(fp_line
			(start 12.652502 -0.882904)
			(end 13.337286 -1.539494)
			(stroke
				(width 0.1)
				(type default)
			)
			(layer "F.SilkS")
		)
		(fp_line
			(start 12.652502 -0.882904)
			(end 13.337286 -1.539494)
			(stroke
				(width 0.1)
				(type default)
			)
			(layer "F.SilkS")
		)
		(fp_line
			(start 12.666726 -5.225034)
			(end 11.715242 -4.312412)
			(stroke
				(width 0.1)
				(type default)
			)
			(layer "F.SilkS")
		)
		(fp_line
			(start 12.666726 -5.225034)
			(end 11.715242 -4.312412)
			(stroke
				(width 0.1)
				(type default)
			)
			(layer "F.SilkS")
		)
		(fp_line
			(start 12.7127 -0.882904)
			(end 12.772898 -0.882904)
			(stroke
				(width 0.1)
				(type default)
			)
			(layer "F.SilkS")
		)
		(fp_line
			(start 12.7127 -0.882904)
			(end 12.772898 -0.882904)
			(stroke
				(width 0.1)
				(type default)
			)
			(layer "F.SilkS")
		)
		(fp_line
			(start 12.7127 -0.882904)
			(end 13.32484 -1.470152)
			(stroke
				(width 0.1)
				(type default)
			)
			(layer "F.SilkS")
		)
		(fp_line
			(start 12.7127 -0.882904)
			(end 13.32484 -1.470152)
			(stroke
				(width 0.1)
				(type default)
			)
			(layer "F.SilkS")
		)
		(fp_line
			(start 12.715494 -5.214112)
			(end 11.78179 -4.318254)
			(stroke
				(width 0.1)
				(type default)
			)
			(layer "F.SilkS")
		)
		(fp_line
			(start 12.715494 -5.214112)
			(end 11.78179 -4.318254)
			(stroke
				(width 0.1)
				(type default)
			)
			(layer "F.SilkS")
		)
		(fp_line
			(start 12.764008 -5.202936)
			(end 11.846306 -4.322572)
			(stroke
				(width 0.1)
				(type default)
			)
			(layer "F.SilkS")
		)
		(fp_line
			(start 12.764008 -5.202936)
			(end 11.846306 -4.322572)
			(stroke
				(width 0.1)
				(type default)
			)
			(layer "F.SilkS")
		)
		(fp_line
			(start 12.772898 -0.882904)
			(end 12.832842 -0.882904)
			(stroke
				(width 0.1)
				(type default)
			)
			(layer "F.SilkS")
		)
		(fp_line
			(start 12.772898 -0.882904)
			(end 12.832842 -0.882904)
			(stroke
				(width 0.1)
				(type default)
			)
			(layer "F.SilkS")
		)
		(fp_line
			(start 12.772898 -0.882904)
			(end 13.312394 -1.400556)
			(stroke
				(width 0.1)
				(type default)
			)
			(layer "F.SilkS")
		)
		(fp_line
			(start 12.772898 -0.882904)
			(end 13.312394 -1.400556)
			(stroke
				(width 0.1)
				(type default)
			)
			(layer "F.SilkS")
		)
		(fp_line
			(start 12.812522 -5.19176)
			(end 11.910568 -4.326636)
			(stroke
				(width 0.1)
				(type default)
			)
			(layer "F.SilkS")
		)
		(fp_line
			(start 12.812522 -5.19176)
			(end 11.910568 -4.326636)
			(stroke
				(width 0.1)
				(type default)
			)
			(layer "F.SilkS")
		)
		(fp_line
			(start 12.832842 -0.882904)
			(end 12.89304 -0.882904)
			(stroke
				(width 0.1)
				(type default)
			)
			(layer "F.SilkS")
		)
		(fp_line
			(start 12.832842 -0.882904)
			(end 12.89304 -0.882904)
			(stroke
				(width 0.1)
				(type default)
			)
			(layer "F.SilkS")
		)
		(fp_line
			(start 12.832842 -0.882904)
			(end 13.30071 -1.331468)
			(stroke
				(width 0.1)
				(type default)
			)
			(layer "F.SilkS")
		)
		(fp_line
			(start 12.832842 -0.882904)
			(end 13.30071 -1.331468)
			(stroke
				(width 0.1)
				(type default)
			)
			(layer "F.SilkS")
		)
		(fp_line
			(start 12.861036 -5.180584)
			(end 11.972036 -4.327906)
			(stroke
				(width 0.1)
				(type default)
			)
			(layer "F.SilkS")
		)
		(fp_line
			(start 12.861036 -5.180584)
			(end 11.972036 -4.327906)
			(stroke
				(width 0.1)
				(type default)
			)
			(layer "F.SilkS")
		)
		(fp_line
			(start 12.89304 -0.882904)
			(end 12.953238 -0.882904)
			(stroke
				(width 0.1)
				(type default)
			)
			(layer "F.SilkS")
		)
		(fp_line
			(start 12.89304 -0.882904)
			(end 12.953238 -0.882904)
			(stroke
				(width 0.1)
				(type default)
			)
			(layer "F.SilkS")
		)
		(fp_line
			(start 12.89304 -0.882904)
			(end 13.288264 -1.262126)
			(stroke
				(width 0.1)
				(type default)
			)
			(layer "F.SilkS")
		)
		(fp_line
			(start 12.89304 -0.882904)
			(end 13.288264 -1.262126)
			(stroke
				(width 0.1)
				(type default)
			)
			(layer "F.SilkS")
		)
		(fp_line
			(start 12.909804 -5.169408)
			(end 12.033758 -4.328922)
			(stroke
				(width 0.1)
				(type default)
			)
			(layer "F.SilkS")
		)
		(fp_line
			(start 12.909804 -5.169408)
			(end 12.033758 -4.328922)
			(stroke
				(width 0.1)
				(type default)
			)
			(layer "F.SilkS")
		)
		(fp_line
			(start 12.953238 -0.882904)
			(end 13.01369 -0.882904)
			(stroke
				(width 0.1)
				(type default)
			)
			(layer "F.SilkS")
		)
		(fp_line
			(start 12.953238 -0.882904)
			(end 13.01369 -0.882904)
			(stroke
				(width 0.1)
				(type default)
			)
			(layer "F.SilkS")
		)
		(fp_line
			(start 12.953238 -0.882904)
			(end 13.275818 -1.19253)
			(stroke
				(width 0.1)
				(type default)
			)
			(layer "F.SilkS")
		)
		(fp_line
			(start 12.953238 -0.882904)
			(end 13.275818 -1.19253)
			(stroke
				(width 0.1)
				(type default)
			)
			(layer "F.SilkS")
		)
		(fp_line
			(start 12.955778 -5.155946)
			(end 12.09421 -4.32943)
			(stroke
				(width 0.1)
				(type default)
			)
			(layer "F.SilkS")
		)
		(fp_line
			(start 12.955778 -5.155946)
			(end 12.09421 -4.32943)
			(stroke
				(width 0.1)
				(type default)
			)
			(layer "F.SilkS")
		)
		(fp_line
			(start 12.996926 -5.137658)
			(end 12.149836 -4.325112)
			(stroke
				(width 0.1)
				(type default)
			)
			(layer "F.SilkS")
		)
		(fp_line
			(start 12.996926 -5.137658)
			(end 12.149836 -4.325112)
			(stroke
				(width 0.1)
				(type default)
			)
			(layer "F.SilkS")
		)
		(fp_line
			(start 13.01369 -0.882904)
			(end 13.073634 -0.882904)
			(stroke
				(width 0.1)
				(type default)
			)
			(layer "F.SilkS")
		)
		(fp_line
			(start 13.01369 -0.882904)
			(end 13.073634 -0.882904)
			(stroke
				(width 0.1)
				(type default)
			)
			(layer "F.SilkS")
		)
		(fp_line
			(start 13.01369 -0.882904)
			(end 13.264134 -1.123188)
			(stroke
				(width 0.1)
				(type default)
			)
			(layer "F.SilkS")
		)
		(fp_line
			(start 13.01369 -0.882904)
			(end 13.264134 -1.123188)
			(stroke
				(width 0.1)
				(type default)
			)
			(layer "F.SilkS")
		)
		(fp_line
			(start 13.038074 -5.11937)
			(end 12.205462 -4.320794)
			(stroke
				(width 0.1)
				(type default)
			)
			(layer "F.SilkS")
		)
		(fp_line
			(start 13.038074 -5.11937)
			(end 12.205462 -4.320794)
			(stroke
				(width 0.1)
				(type default)
			)
			(layer "F.SilkS")
		)
		(fp_line
			(start 13.073634 -0.882904)
			(end 13.133578 -0.882904)
			(stroke
				(width 0.1)
				(type default)
			)
			(layer "F.SilkS")
		)
		(fp_line
			(start 13.073634 -0.882904)
			(end 13.133578 -0.882904)
			(stroke
				(width 0.1)
				(type default)
			)
			(layer "F.SilkS")
		)
		(fp_line
			(start 13.073634 -0.882904)
			(end 13.251942 -1.053846)
			(stroke
				(width 0.1)
				(type default)
			)
			(layer "F.SilkS")
		)
		(fp_line
			(start 13.073634 -0.882904)
			(end 13.251942 -1.053846)
			(stroke
				(width 0.1)
				(type default)
			)
			(layer "F.SilkS")
		)
		(fp_line
			(start 13.079222 -5.101336)
			(end 12.256008 -4.311396)
			(stroke
				(width 0.1)
				(type default)
			)
			(layer "F.SilkS")
		)
		(fp_line
			(start 13.079222 -5.101336)
			(end 12.256008 -4.311396)
			(stroke
				(width 0.1)
				(type default)
			)
			(layer "F.SilkS")
		)
		(fp_line
			(start 13.120116 -5.083048)
			(end 12.302998 -4.29895)
			(stroke
				(width 0.1)
				(type default)
			)
			(layer "F.SilkS")
		)
		(fp_line
			(start 13.120116 -5.083048)
			(end 12.302998 -4.29895)
			(stroke
				(width 0.1)
				(type default)
			)
			(layer "F.SilkS")
		)
		(fp_line
			(start 13.133578 -0.882904)
			(end 13.19403 -0.882904)
			(stroke
				(width 0.1)
				(type default)
			)
			(layer "F.SilkS")
		)
		(fp_line
			(start 13.133578 -0.882904)
			(end 13.19403 -0.882904)
			(stroke
				(width 0.1)
				(type default)
			)
			(layer "F.SilkS")
		)
		(fp_line
			(start 13.133578 -0.882904)
			(end 13.23975 -0.984504)
			(stroke
				(width 0.1)
				(type default)
			)
			(layer "F.SilkS")
		)
		(fp_line
			(start 13.133578 -0.882904)
			(end 13.23975 -0.984504)
			(stroke
				(width 0.1)
				(type default)
			)
			(layer "F.SilkS")
		)
		(fp_line
			(start 13.161518 -5.06476)
			(end 12.34948 -4.285742)
			(stroke
				(width 0.1)
				(type default)
			)
			(layer "F.SilkS")
		)
		(fp_line
			(start 13.161518 -5.06476)
			(end 12.34948 -4.285742)
			(stroke
				(width 0.1)
				(type default)
			)
			(layer "F.SilkS")
		)
		(fp_line
			(start 13.19403 -0.882904)
			(end 13.22197 -0.882904)
			(stroke
				(width 0.1)
				(type default)
			)
			(layer "F.SilkS")
		)
		(fp_line
			(start 13.19403 -0.882904)
			(end 13.22197 -0.882904)
			(stroke
				(width 0.1)
				(type default)
			)
			(layer "F.SilkS")
		)
		(fp_line
			(start 13.19403 -0.882904)
			(end 13.227812 -0.914908)
			(stroke
				(width 0.1)
				(type default)
			)
			(layer "F.SilkS")
		)
		(fp_line
			(start 13.19403 -0.882904)
			(end 13.227812 -0.914908)
			(stroke
				(width 0.1)
				(type default)
			)
			(layer "F.SilkS")
		)
		(fp_line
			(start 13.20292 -5.046472)
			(end 12.388596 -4.265422)
			(stroke
				(width 0.1)
				(type default)
			)
			(layer "F.SilkS")
		)
		(fp_line
			(start 13.20292 -5.046472)
			(end 12.388596 -4.265422)
			(stroke
				(width 0.1)
				(type default)
			)
			(layer "F.SilkS")
		)
		(fp_line
			(start 13.22197 -0.882904)
			(end 13.227812 -0.914908)
			(stroke
				(width 0.1)
				(type default)
			)
			(layer "F.SilkS")
		)
		(fp_line
			(start 13.22197 -0.882904)
			(end 13.227812 -0.914908)
			(stroke
				(width 0.1)
				(type default)
			)
			(layer "F.SilkS")
		)
		(fp_line
			(start 13.227812 -0.914908)
			(end 13.23975 -0.984504)
			(stroke
				(width 0.1)
				(type default)
			)
			(layer "F.SilkS")
		)
		(fp_line
			(start 13.227812 -0.914908)
			(end 13.23975 -0.984504)
			(stroke
				(width 0.1)
				(type default)
			)
			(layer "F.SilkS")
		)
		(fp_line
			(start 13.238988 -5.023612)
			(end 12.427458 -4.245102)
			(stroke
				(width 0.1)
				(type default)
			)
			(layer "F.SilkS")
		)
		(fp_line
			(start 13.238988 -5.023612)
			(end 12.427458 -4.245102)
			(stroke
				(width 0.1)
				(type default)
			)
			(layer "F.SilkS")
		)
		(fp_line
			(start 13.23975 -0.984504)
			(end 13.251942 -1.053846)
			(stroke
				(width 0.1)
				(type default)
			)
			(layer "F.SilkS")
		)
		(fp_line
			(start 13.23975 -0.984504)
			(end 13.251942 -1.053846)
			(stroke
				(width 0.1)
				(type default)
			)
			(layer "F.SilkS")
		)
		(fp_line
			(start 13.251942 -1.053846)
			(end 13.264134 -1.123188)
			(stroke
				(width 0.1)
				(type default)
			)
			(layer "F.SilkS")
		)
		(fp_line
			(start 13.251942 -1.053846)
			(end 13.264134 -1.123188)
			(stroke
				(width 0.1)
				(type default)
			)
			(layer "F.SilkS")
		)
		(fp_line
			(start 13.264134 -1.123188)
			(end 13.275818 -1.19253)
			(stroke
				(width 0.1)
				(type default)
			)
			(layer "F.SilkS")
		)
		(fp_line
			(start 13.264134 -1.123188)
			(end 13.275818 -1.19253)
			(stroke
				(width 0.1)
				(type default)
			)
			(layer "F.SilkS")
		)
		(fp_line
			(start 13.272516 -4.998212)
			(end 12.461748 -4.22021)
			(stroke
				(width 0.1)
				(type default)
			)
			(layer "F.SilkS")
		)
		(fp_line
			(start 13.272516 -4.998212)
			(end 12.461748 -4.22021)
			(stroke
				(width 0.1)
				(type default)
			)
			(layer "F.SilkS")
		)
		(fp_line
			(start 13.275818 -1.19253)
			(end 13.288264 -1.262126)
			(stroke
				(width 0.1)
				(type default)
			)
			(layer "F.SilkS")
		)
		(fp_line
			(start 13.275818 -1.19253)
			(end 13.288264 -1.262126)
			(stroke
				(width 0.1)
				(type default)
			)
			(layer "F.SilkS")
		)
		(fp_line
			(start 13.288264 -1.262126)
			(end 13.30071 -1.331468)
			(stroke
				(width 0.1)
				(type default)
			)
			(layer "F.SilkS")
		)
		(fp_line
			(start 13.288264 -1.262126)
			(end 13.30071 -1.331468)
			(stroke
				(width 0.1)
				(type default)
			)
			(layer "F.SilkS")
		)
		(fp_line
			(start 13.30071 -1.331468)
			(end 13.312394 -1.400556)
			(stroke
				(width 0.1)
				(type default)
			)
			(layer "F.SilkS")
		)
		(fp_line
			(start 13.30071 -1.331468)
			(end 13.312394 -1.400556)
			(stroke
				(width 0.1)
				(type default)
			)
			(layer "F.SilkS")
		)
		(fp_line
			(start 13.306298 -4.972812)
			(end 12.49299 -4.192524)
			(stroke
				(width 0.1)
				(type default)
			)
			(layer "F.SilkS")
		)
		(fp_line
			(start 13.306298 -4.972812)
			(end 12.49299 -4.192524)
			(stroke
				(width 0.1)
				(type default)
			)
			(layer "F.SilkS")
		)
		(fp_line
			(start 13.312394 -1.400556)
			(end 13.32484 -1.470152)
			(stroke
				(width 0.1)
				(type default)
			)
			(layer "F.SilkS")
		)
		(fp_line
			(start 13.312394 -1.400556)
			(end 13.32484 -1.470152)
			(stroke
				(width 0.1)
				(type default)
			)
			(layer "F.SilkS")
		)
		(fp_line
			(start 13.32484 -1.470152)
			(end 13.337286 -1.539494)
			(stroke
				(width 0.1)
				(type default)
			)
			(layer "F.SilkS")
		)
		(fp_line
			(start 13.32484 -1.470152)
			(end 13.337286 -1.539494)
			(stroke
				(width 0.1)
				(type default)
			)
			(layer "F.SilkS")
		)
		(fp_line
			(start 13.337286 -1.539494)
			(end 13.34897 -1.608836)
			(stroke
				(width 0.1)
				(type default)
			)
			(layer "F.SilkS")
		)
		(fp_line
			(start 13.337286 -1.539494)
			(end 13.34897 -1.608836)
			(stroke
				(width 0.1)
				(type default)
			)
			(layer "F.SilkS")
		)
		(fp_line
			(start 13.34008 -4.947412)
			(end 12.522454 -4.16306)
			(stroke
				(width 0.1)
				(type default)
			)
			(layer "F.SilkS")
		)
		(fp_line
			(start 13.34008 -4.947412)
			(end 12.522454 -4.16306)
			(stroke
				(width 0.1)
				(type default)
			)
			(layer "F.SilkS")
		)
		(fp_line
			(start 13.34897 -1.608836)
			(end 13.361416 -1.678178)
			(stroke
				(width 0.1)
				(type default)
			)
			(layer "F.SilkS")
		)
		(fp_line
			(start 13.34897 -1.608836)
			(end 13.361416 -1.678178)
			(stroke
				(width 0.1)
				(type default)
			)
			(layer "F.SilkS")
		)
		(fp_line
			(start 13.361416 -1.678178)
			(end 13.373354 -1.74752)
			(stroke
				(width 0.1)
				(type default)
			)
			(layer "F.SilkS")
		)
		(fp_line
			(start 13.361416 -1.678178)
			(end 13.373354 -1.74752)
			(stroke
				(width 0.1)
				(type default)
			)
			(layer "F.SilkS")
		)
		(fp_line
			(start 13.373354 -1.74752)
			(end 13.385546 -1.817116)
			(stroke
				(width 0.1)
				(type default)
			)
			(layer "F.SilkS")
		)
		(fp_line
			(start 13.373354 -1.74752)
			(end 13.385546 -1.817116)
			(stroke
				(width 0.1)
				(type default)
			)
			(layer "F.SilkS")
		)
		(fp_line
			(start 13.373862 -4.922012)
			(end 12.545822 -4.127754)
			(stroke
				(width 0.1)
				(type default)
			)
			(layer "F.SilkS")
		)
		(fp_line
			(start 13.373862 -4.922012)
			(end 12.545822 -4.127754)
			(stroke
				(width 0.1)
				(type default)
			)
			(layer "F.SilkS")
		)
		(fp_line
			(start 13.385546 -1.817116)
			(end 13.397992 -1.886458)
			(stroke
				(width 0.1)
				(type default)
			)
			(layer "F.SilkS")
		)
		(fp_line
			(start 13.385546 -1.817116)
			(end 13.397992 -1.886458)
			(stroke
				(width 0.1)
				(type default)
			)
			(layer "F.SilkS")
		)
		(fp_line
			(start 13.397992 -1.886458)
			(end 13.40993 -1.9558)
			(stroke
				(width 0.1)
				(type default)
			)
			(layer "F.SilkS")
		)
		(fp_line
			(start 13.397992 -1.886458)
			(end 13.40993 -1.9558)
			(stroke
				(width 0.1)
				(type default)
			)
			(layer "F.SilkS")
		)
		(fp_line
			(start 13.407136 -4.896358)
			(end 12.568936 -4.092194)
			(stroke
				(width 0.1)
				(type default)
			)
			(layer "F.SilkS")
		)
		(fp_line
			(start 13.407136 -4.896358)
			(end 12.568936 -4.092194)
			(stroke
				(width 0.1)
				(type default)
			)
			(layer "F.SilkS")
		)
		(fp_line
			(start 13.40993 -1.9558)
			(end 13.422122 -2.025396)
			(stroke
				(width 0.1)
				(type default)
			)
			(layer "F.SilkS")
		)
		(fp_line
			(start 13.40993 -1.9558)
			(end 13.422122 -2.025396)
			(stroke
				(width 0.1)
				(type default)
			)
			(layer "F.SilkS")
		)
		(fp_line
			(start 13.422122 -2.025396)
			(end 13.434314 -2.094738)
			(stroke
				(width 0.1)
				(type default)
			)
			(layer "F.SilkS")
		)
		(fp_line
			(start 13.422122 -2.025396)
			(end 13.434314 -2.094738)
			(stroke
				(width 0.1)
				(type default)
			)
			(layer "F.SilkS")
		)
		(fp_line
			(start 13.434314 -2.094738)
			(end 13.446506 -2.163826)
			(stroke
				(width 0.1)
				(type default)
			)
			(layer "F.SilkS")
		)
		(fp_line
			(start 13.434314 -2.094738)
			(end 13.446506 -2.163826)
			(stroke
				(width 0.1)
				(type default)
			)
			(layer "F.SilkS")
		)
		(fp_line
			(start 13.440664 -4.871212)
			(end 12.58443 -4.049522)
			(stroke
				(width 0.1)
				(type default)
			)
			(layer "F.SilkS")
		)
		(fp_line
			(start 13.440664 -4.871212)
			(end 12.58443 -4.049522)
			(stroke
				(width 0.1)
				(type default)
			)
			(layer "F.SilkS")
		)
		(fp_line
			(start 13.446506 -2.163826)
			(end 13.458444 -2.233422)
			(stroke
				(width 0.1)
				(type default)
			)
			(layer "F.SilkS")
		)
		(fp_line
			(start 13.446506 -2.163826)
			(end 13.458444 -2.233422)
			(stroke
				(width 0.1)
				(type default)
			)
			(layer "F.SilkS")
		)
		(fp_line
			(start 13.458444 -2.233422)
			(end 13.47089 -2.302764)
			(stroke
				(width 0.1)
				(type default)
			)
			(layer "F.SilkS")
		)
		(fp_line
			(start 13.458444 -2.233422)
			(end 13.47089 -2.302764)
			(stroke
				(width 0.1)
				(type default)
			)
			(layer "F.SilkS")
		)
		(fp_line
			(start 13.466826 -4.837938)
			(end 12.599162 -4.005834)
			(stroke
				(width 0.1)
				(type default)
			)
			(layer "F.SilkS")
		)
		(fp_line
			(start 13.466826 -4.837938)
			(end 12.599162 -4.005834)
			(stroke
				(width 0.1)
				(type default)
			)
			(layer "F.SilkS")
		)
		(fp_line
			(start 13.47089 -2.302764)
			(end 13.483082 -2.372106)
			(stroke
				(width 0.1)
				(type default)
			)
			(layer "F.SilkS")
		)
		(fp_line
			(start 13.47089 -2.302764)
			(end 13.483082 -2.372106)
			(stroke
				(width 0.1)
				(type default)
			)
			(layer "F.SilkS")
		)
		(fp_line
			(start 13.483082 -2.372106)
			(end 13.49502 -2.441448)
			(stroke
				(width 0.1)
				(type default)
			)
			(layer "F.SilkS")
		)
		(fp_line
			(start 13.483082 -2.372106)
			(end 13.49502 -2.441448)
			(stroke
				(width 0.1)
				(type default)
			)
			(layer "F.SilkS")
		)
		(fp_line
			(start 13.492226 -4.804918)
			(end 12.606782 -3.955288)
			(stroke
				(width 0.1)
				(type default)
			)
			(layer "F.SilkS")
		)
		(fp_line
			(start 13.492226 -4.804918)
			(end 12.606782 -3.955288)
			(stroke
				(width 0.1)
				(type default)
			)
			(layer "F.SilkS")
		)
		(fp_line
			(start 13.49502 -2.441448)
			(end 13.507466 -2.51079)
			(stroke
				(width 0.1)
				(type default)
			)
			(layer "F.SilkS")
		)
		(fp_line
			(start 13.49502 -2.441448)
			(end 13.507466 -2.51079)
			(stroke
				(width 0.1)
				(type default)
			)
			(layer "F.SilkS")
		)
		(fp_line
			(start 13.507466 -2.51079)
			(end 13.519404 -2.580386)
			(stroke
				(width 0.1)
				(type default)
			)
			(layer "F.SilkS")
		)
		(fp_line
			(start 13.507466 -2.51079)
			(end 13.519404 -2.580386)
			(stroke
				(width 0.1)
				(type default)
			)
			(layer "F.SilkS")
		)
		(fp_line
			(start 13.518134 -4.771898)
			(end 12.612116 -3.902964)
			(stroke
				(width 0.1)
				(type default)
			)
			(layer "F.SilkS")
		)
		(fp_line
			(start 13.518134 -4.771898)
			(end 12.612116 -3.902964)
			(stroke
				(width 0.1)
				(type default)
			)
			(layer "F.SilkS")
		)
		(fp_line
			(start 13.519404 -2.580386)
			(end 13.531596 -2.649728)
			(stroke
				(width 0.1)
				(type default)
			)
			(layer "F.SilkS")
		)
		(fp_line
			(start 13.519404 -2.580386)
			(end 13.531596 -2.649728)
			(stroke
				(width 0.1)
				(type default)
			)
			(layer "F.SilkS")
		)
		(fp_line
			(start 13.531596 -2.649728)
			(end 13.544042 -2.71907)
			(stroke
				(width 0.1)
				(type default)
			)
			(layer "F.SilkS")
		)
		(fp_line
			(start 13.531596 -2.649728)
			(end 13.544042 -2.71907)
			(stroke
				(width 0.1)
				(type default)
			)
			(layer "F.SilkS")
		)
		(fp_line
			(start 13.544042 -4.738878)
			(end 12.60856 -3.84175)
			(stroke
				(width 0.1)
				(type default)
			)
			(layer "F.SilkS")
		)
		(fp_line
			(start 13.544042 -4.738878)
			(end 12.60856 -3.84175)
			(stroke
				(width 0.1)
				(type default)
			)
			(layer "F.SilkS")
		)
		(fp_line
			(start 13.544042 -2.71907)
			(end 13.55598 -2.788412)
			(stroke
				(width 0.1)
				(type default)
			)
			(layer "F.SilkS")
		)
		(fp_line
			(start 13.544042 -2.71907)
			(end 13.55598 -2.788412)
			(stroke
				(width 0.1)
				(type default)
			)
			(layer "F.SilkS")
		)
		(fp_line
			(start 13.55598 -2.788412)
			(end 13.568172 -2.857754)
			(stroke
				(width 0.1)
				(type default)
			)
			(layer "F.SilkS")
		)
		(fp_line
			(start 13.55598 -2.788412)
			(end 13.568172 -2.857754)
			(stroke
				(width 0.1)
				(type default)
			)
			(layer "F.SilkS")
		)
		(fp_line
			(start 13.568172 -2.857754)
			(end 13.580364 -2.927096)
			(stroke
				(width 0.1)
				(type default)
			)
			(layer "F.SilkS")
		)
		(fp_line
			(start 13.568172 -2.857754)
			(end 13.580364 -2.927096)
			(stroke
				(width 0.1)
				(type default)
			)
			(layer "F.SilkS")
		)
		(fp_line
			(start 13.569442 -4.705858)
			(end 12.601956 -3.777996)
			(stroke
				(width 0.1)
				(type default)
			)
			(layer "F.SilkS")
		)
		(fp_line
			(start 13.569442 -4.705858)
			(end 12.601956 -3.777996)
			(stroke
				(width 0.1)
				(type default)
			)
			(layer "F.SilkS")
		)
		(fp_line
			(start 13.580364 -2.927096)
			(end 13.592556 -2.996692)
			(stroke
				(width 0.1)
				(type default)
			)
			(layer "F.SilkS")
		)
		(fp_line
			(start 13.580364 -2.927096)
			(end 13.592556 -2.996692)
			(stroke
				(width 0.1)
				(type default)
			)
			(layer "F.SilkS")
		)
		(fp_line
			(start 13.592556 -2.996692)
			(end 13.604494 -3.06578)
			(stroke
				(width 0.1)
				(type default)
			)
			(layer "F.SilkS")
		)
		(fp_line
			(start 13.592556 -2.996692)
			(end 13.604494 -3.06578)
			(stroke
				(width 0.1)
				(type default)
			)
			(layer "F.SilkS")
		)
		(fp_line
			(start 13.59535 -4.672838)
			(end 12.590018 -3.708654)
			(stroke
				(width 0.1)
				(type default)
			)
			(layer "F.SilkS")
		)
		(fp_line
			(start 13.59535 -4.672838)
			(end 12.590018 -3.708654)
			(stroke
				(width 0.1)
				(type default)
			)
			(layer "F.SilkS")
		)
		(fp_line
			(start 13.604494 -3.06578)
			(end 13.61694 -3.135376)
			(stroke
				(width 0.1)
				(type default)
			)
			(layer "F.SilkS")
		)
		(fp_line
			(start 13.604494 -3.06578)
			(end 13.61694 -3.135376)
			(stroke
				(width 0.1)
				(type default)
			)
			(layer "F.SilkS")
		)
		(fp_line
			(start 13.616432 -4.635246)
			(end 12.57808 -3.639312)
			(stroke
				(width 0.1)
				(type default)
			)
			(layer "F.SilkS")
		)
		(fp_line
			(start 13.616432 -4.635246)
			(end 12.57808 -3.639312)
			(stroke
				(width 0.1)
				(type default)
			)
			(layer "F.SilkS")
		)
		(fp_line
			(start 13.61694 -3.135376)
			(end 13.629132 -3.204972)
			(stroke
				(width 0.1)
				(type default)
			)
			(layer "F.SilkS")
		)
		(fp_line
			(start 13.61694 -3.135376)
			(end 13.629132 -3.204972)
			(stroke
				(width 0.1)
				(type default)
			)
			(layer "F.SilkS")
		)
		(fp_line
			(start 13.629132 -3.204972)
			(end 13.64107 -3.27406)
			(stroke
				(width 0.1)
				(type default)
			)
			(layer "F.SilkS")
		)
		(fp_line
			(start 13.629132 -3.204972)
			(end 13.64107 -3.27406)
			(stroke
				(width 0.1)
				(type default)
			)
			(layer "F.SilkS")
		)
		(fp_line
			(start 13.633196 -4.593844)
			(end 11.82116 -2.855722)
			(stroke
				(width 0.1)
				(type default)
			)
			(layer "F.SilkS")
		)
		(fp_line
			(start 13.633196 -4.593844)
			(end 11.82116 -2.855722)
			(stroke
				(width 0.1)
				(type default)
			)
			(layer "F.SilkS")
		)
		(fp_line
			(start 13.64996 -4.552442)
			(end 11.877548 -2.851912)
			(stroke
				(width 0.1)
				(type default)
			)
			(layer "F.SilkS")
		)
		(fp_line
			(start 13.64996 -4.552442)
			(end 11.877548 -2.851912)
			(stroke
				(width 0.1)
				(type default)
			)
			(layer "F.SilkS")
		)
		(fp_line
			(start 13.653516 -3.343402)
			(end 13.64107 -3.27406)
			(stroke
				(width 0.1)
				(type default)
			)
			(layer "F.SilkS")
		)
		(fp_line
			(start 13.653516 -3.343402)
			(end 13.64107 -3.27406)
			(stroke
				(width 0.1)
				(type default)
			)
			(layer "F.SilkS")
		)
		(fp_line
			(start 13.665708 -3.412998)
			(end 10.943336 -0.801624)
			(stroke
				(width 0.1)
				(type default)
			)
			(layer "F.SilkS")
		)
		(fp_line
			(start 13.665708 -3.412998)
			(end 10.943336 -0.801624)
			(stroke
				(width 0.1)
				(type default)
			)
			(layer "F.SilkS")
		)
		(fp_line
			(start 13.665708 -3.412998)
			(end 13.653516 -3.343402)
			(stroke
				(width 0.1)
				(type default)
			)
			(layer "F.SilkS")
		)
		(fp_line
			(start 13.665708 -3.412998)
			(end 13.653516 -3.343402)
			(stroke
				(width 0.1)
				(type default)
			)
			(layer "F.SilkS")
		)
		(fp_line
			(start 13.667232 -4.51104)
			(end 11.93292 -2.84734)
			(stroke
				(width 0.1)
				(type default)
			)
			(layer "F.SilkS")
		)
		(fp_line
			(start 13.667232 -4.51104)
			(end 11.93292 -2.84734)
			(stroke
				(width 0.1)
				(type default)
			)
			(layer "F.SilkS")
		)
		(fp_line
			(start 13.677646 -3.48234)
			(end 12.323064 -2.182622)
			(stroke
				(width 0.1)
				(type default)
			)
			(layer "F.SilkS")
		)
		(fp_line
			(start 13.677646 -3.48234)
			(end 12.323064 -2.182622)
			(stroke
				(width 0.1)
				(type default)
			)
			(layer "F.SilkS")
		)
		(fp_line
			(start 13.677646 -3.48234)
			(end 13.665708 -3.412998)
			(stroke
				(width 0.1)
				(type default)
			)
			(layer "F.SilkS")
		)
		(fp_line
			(start 13.677646 -3.48234)
			(end 13.665708 -3.412998)
			(stroke
				(width 0.1)
				(type default)
			)
			(layer "F.SilkS")
		)
		(fp_line
			(start 13.684504 -4.469638)
			(end 11.986006 -2.840482)
			(stroke
				(width 0.1)
				(type default)
			)
			(layer "F.SilkS")
		)
		(fp_line
			(start 13.684504 -4.469638)
			(end 11.986006 -2.840482)
			(stroke
				(width 0.1)
				(type default)
			)
			(layer "F.SilkS")
		)
		(fp_line
			(start 13.690092 -3.551682)
			(end 12.335002 -2.251964)
			(stroke
				(width 0.1)
				(type default)
			)
			(layer "F.SilkS")
		)
		(fp_line
			(start 13.690092 -3.551682)
			(end 12.335002 -2.251964)
			(stroke
				(width 0.1)
				(type default)
			)
			(layer "F.SilkS")
		)
		(fp_line
			(start 13.690092 -3.551682)
			(end 13.677646 -3.48234)
			(stroke
				(width 0.1)
				(type default)
			)
			(layer "F.SilkS")
		)
		(fp_line
			(start 13.690092 -3.551682)
			(end 13.677646 -3.48234)
			(stroke
				(width 0.1)
				(type default)
			)
			(layer "F.SilkS")
		)
		(fp_line
			(start 13.701014 -4.42849)
			(end 12.037822 -2.832862)
			(stroke
				(width 0.1)
				(type default)
			)
			(layer "F.SilkS")
		)
		(fp_line
			(start 13.701014 -4.42849)
			(end 12.037822 -2.832862)
			(stroke
				(width 0.1)
				(type default)
			)
			(layer "F.SilkS")
		)
		(fp_line
			(start 13.70203 -3.621024)
			(end 12.347194 -2.321306)
			(stroke
				(width 0.1)
				(type default)
			)
			(layer "F.SilkS")
		)
		(fp_line
			(start 13.70203 -3.621024)
			(end 12.347194 -2.321306)
			(stroke
				(width 0.1)
				(type default)
			)
			(layer "F.SilkS")
		)
		(fp_line
			(start 13.70203 -3.621024)
			(end 13.690092 -3.551682)
			(stroke
				(width 0.1)
				(type default)
			)
			(layer "F.SilkS")
		)
		(fp_line
			(start 13.70203 -3.621024)
			(end 13.690092 -3.551682)
			(stroke
				(width 0.1)
				(type default)
			)
			(layer "F.SilkS")
		)
		(fp_line
			(start 13.714222 -3.690366)
			(end 12.359386 -2.390902)
			(stroke
				(width 0.1)
				(type default)
			)
			(layer "F.SilkS")
		)
		(fp_line
			(start 13.714222 -3.690366)
			(end 12.359386 -2.390902)
			(stroke
				(width 0.1)
				(type default)
			)
			(layer "F.SilkS")
		)
		(fp_line
			(start 13.714222 -3.690366)
			(end 13.70203 -3.621024)
			(stroke
				(width 0.1)
				(type default)
			)
			(layer "F.SilkS")
		)
		(fp_line
			(start 13.714222 -3.690366)
			(end 13.70203 -3.621024)
			(stroke
				(width 0.1)
				(type default)
			)
			(layer "F.SilkS")
		)
		(fp_line
			(start 13.715238 -4.383786)
			(end 12.087352 -2.822448)
			(stroke
				(width 0.1)
				(type default)
			)
			(layer "F.SilkS")
		)
		(fp_line
			(start 13.715238 -4.383786)
			(end 12.087352 -2.822448)
			(stroke
				(width 0.1)
				(type default)
			)
			(layer "F.SilkS")
		)
		(fp_line
			(start 13.722096 -4.332732)
			(end 12.135612 -2.810764)
			(stroke
				(width 0.1)
				(type default)
			)
			(layer "F.SilkS")
		)
		(fp_line
			(start 13.722096 -4.332732)
			(end 12.135612 -2.810764)
			(stroke
				(width 0.1)
				(type default)
			)
			(layer "F.SilkS")
		)
		(fp_line
			(start 13.72616 -3.759962)
			(end 12.371578 -2.460244)
			(stroke
				(width 0.1)
				(type default)
			)
			(layer "F.SilkS")
		)
		(fp_line
			(start 13.72616 -3.759962)
			(end 12.371578 -2.460244)
			(stroke
				(width 0.1)
				(type default)
			)
			(layer "F.SilkS")
		)
		(fp_line
			(start 13.729208 -4.281932)
			(end 12.181078 -2.796794)
			(stroke
				(width 0.1)
				(type default)
			)
			(layer "F.SilkS")
		)
		(fp_line
			(start 13.729208 -4.281932)
			(end 12.181078 -2.796794)
			(stroke
				(width 0.1)
				(type default)
			)
			(layer "F.SilkS")
		)
		(fp_line
			(start 13.731494 -3.822446)
			(end 12.38377 -2.529586)
			(stroke
				(width 0.1)
				(type default)
			)
			(layer "F.SilkS")
		)
		(fp_line
			(start 13.731494 -3.822446)
			(end 12.38377 -2.529586)
			(stroke
				(width 0.1)
				(type default)
			)
			(layer "F.SilkS")
		)
		(fp_line
			(start 13.73632 -4.230878)
			(end 12.224766 -2.781046)
			(stroke
				(width 0.1)
				(type default)
			)
			(layer "F.SilkS")
		)
		(fp_line
			(start 13.73632 -4.230878)
			(end 12.224766 -2.781046)
			(stroke
				(width 0.1)
				(type default)
			)
			(layer "F.SilkS")
		)
		(fp_line
			(start 13.736574 -3.88493)
			(end 12.395962 -2.598928)
			(stroke
				(width 0.1)
				(type default)
			)
			(layer "F.SilkS")
		)
		(fp_line
			(start 13.736574 -3.88493)
			(end 12.395962 -2.598928)
			(stroke
				(width 0.1)
				(type default)
			)
			(layer "F.SilkS")
		)
		(fp_line
			(start 13.741654 -3.947668)
			(end 12.408154 -2.668524)
			(stroke
				(width 0.1)
				(type default)
			)
			(layer "F.SilkS")
		)
		(fp_line
			(start 13.741654 -3.947668)
			(end 12.408154 -2.668524)
			(stroke
				(width 0.1)
				(type default)
			)
			(layer "F.SilkS")
		)
		(fp_line
			(start 13.743178 -4.179824)
			(end 12.266422 -2.76352)
			(stroke
				(width 0.1)
				(type default)
			)
			(layer "F.SilkS")
		)
		(fp_line
			(start 13.743178 -4.179824)
			(end 12.266422 -2.76352)
			(stroke
				(width 0.1)
				(type default)
			)
			(layer "F.SilkS")
		)
		(fp_line
			(start 13.74648 -4.010152)
			(end 12.380214 -2.699512)
			(stroke
				(width 0.1)
				(type default)
			)
			(layer "F.SilkS")
		)
		(fp_line
			(start 13.74648 -4.010152)
			(end 12.380214 -2.699512)
			(stroke
				(width 0.1)
				(type default)
			)
			(layer "F.SilkS")
		)
		(fp_line
			(start 13.750036 -4.12877)
			(end 12.306046 -2.743454)
			(stroke
				(width 0.1)
				(type default)
			)
			(layer "F.SilkS")
		)
		(fp_line
			(start 13.750036 -4.12877)
			(end 12.306046 -2.743454)
			(stroke
				(width 0.1)
				(type default)
			)
			(layer "F.SilkS")
		)
		(fp_line
			(start 13.751814 -4.072636)
			(end 12.344654 -2.722626)
			(stroke
				(width 0.1)
				(type default)
			)
			(layer "F.SilkS")
		)
		(fp_line
			(start 13.751814 -4.072636)
			(end 12.344654 -2.722626)
			(stroke
				(width 0.1)
				(type default)
			)
			(layer "F.SilkS")
		)
		(fp_line
			(start 13.944854 -0.882904)
			(end 13.976096 -0.882904)
			(stroke
				(width 0.1)
				(type default)
			)
			(layer "F.SilkS")
		)
		(fp_line
			(start 13.944854 -0.882904)
			(end 13.976096 -0.882904)
			(stroke
				(width 0.1)
				(type default)
			)
			(layer "F.SilkS")
		)
		(fp_line
			(start 13.95095 -0.916178)
			(end 13.944854 -0.882904)
			(stroke
				(width 0.1)
				(type default)
			)
			(layer "F.SilkS")
		)
		(fp_line
			(start 13.95095 -0.916178)
			(end 13.944854 -0.882904)
			(stroke
				(width 0.1)
				(type default)
			)
			(layer "F.SilkS")
		)
		(fp_line
			(start 13.95095 -0.916178)
			(end 15.307056 -2.21742)
			(stroke
				(width 0.1)
				(type default)
			)
			(layer "F.SilkS")
		)
		(fp_line
			(start 13.95095 -0.916178)
			(end 15.307056 -2.21742)
			(stroke
				(width 0.1)
				(type default)
			)
			(layer "F.SilkS")
		)
		(fp_line
			(start 13.962888 -0.985774)
			(end 13.95095 -0.916178)
			(stroke
				(width 0.1)
				(type default)
			)
			(layer "F.SilkS")
		)
		(fp_line
			(start 13.962888 -0.985774)
			(end 13.95095 -0.916178)
			(stroke
				(width 0.1)
				(type default)
			)
			(layer "F.SilkS")
		)
		(fp_line
			(start 13.962888 -0.985774)
			(end 15.319248 -2.286762)
			(stroke
				(width 0.1)
				(type default)
			)
			(layer "F.SilkS")
		)
		(fp_line
			(start 13.962888 -0.985774)
			(end 15.319248 -2.286762)
			(stroke
				(width 0.1)
				(type default)
			)
			(layer "F.SilkS")
		)
		(fp_line
			(start 13.975334 -1.055116)
			(end 13.962888 -0.985774)
			(stroke
				(width 0.1)
				(type default)
			)
			(layer "F.SilkS")
		)
		(fp_line
			(start 13.975334 -1.055116)
			(end 13.962888 -0.985774)
			(stroke
				(width 0.1)
				(type default)
			)
			(layer "F.SilkS")
		)
		(fp_line
			(start 13.975334 -1.055116)
			(end 15.331186 -2.356104)
			(stroke
				(width 0.1)
				(type default)
			)
			(layer "F.SilkS")
		)
		(fp_line
			(start 13.975334 -1.055116)
			(end 15.331186 -2.356104)
			(stroke
				(width 0.1)
				(type default)
			)
			(layer "F.SilkS")
		)
		(fp_line
			(start 13.976096 -0.882904)
			(end 14.036294 -0.882904)
			(stroke
				(width 0.1)
				(type default)
			)
			(layer "F.SilkS")
		)
		(fp_line
			(start 13.976096 -0.882904)
			(end 14.036294 -0.882904)
			(stroke
				(width 0.1)
				(type default)
			)
			(layer "F.SilkS")
		)
		(fp_line
			(start 13.976096 -0.882904)
			(end 15.294864 -2.147824)
			(stroke
				(width 0.1)
				(type default)
			)
			(layer "F.SilkS")
		)
		(fp_line
			(start 13.976096 -0.882904)
			(end 15.294864 -2.147824)
			(stroke
				(width 0.1)
				(type default)
			)
			(layer "F.SilkS")
		)
		(fp_line
			(start 13.987272 -1.124458)
			(end 13.975334 -1.055116)
			(stroke
				(width 0.1)
				(type default)
			)
			(layer "F.SilkS")
		)
		(fp_line
			(start 13.987272 -1.124458)
			(end 13.975334 -1.055116)
			(stroke
				(width 0.1)
				(type default)
			)
			(layer "F.SilkS")
		)
		(fp_line
			(start 13.987272 -1.124458)
			(end 15.343632 -2.425446)
			(stroke
				(width 0.1)
				(type default)
			)
			(layer "F.SilkS")
		)
		(fp_line
			(start 13.987272 -1.124458)
			(end 15.343632 -2.425446)
			(stroke
				(width 0.1)
				(type default)
			)
			(layer "F.SilkS")
		)
		(fp_line
			(start 13.999464 -1.194054)
			(end 13.987272 -1.124458)
			(stroke
				(width 0.1)
				(type default)
			)
			(layer "F.SilkS")
		)
		(fp_line
			(start 13.999464 -1.194054)
			(end 13.987272 -1.124458)
			(stroke
				(width 0.1)
				(type default)
			)
			(layer "F.SilkS")
		)
		(fp_line
			(start 13.999464 -1.194054)
			(end 15.355824 -2.495042)
			(stroke
				(width 0.1)
				(type default)
			)
			(layer "F.SilkS")
		)
		(fp_line
			(start 13.999464 -1.194054)
			(end 15.355824 -2.495042)
			(stroke
				(width 0.1)
				(type default)
			)
			(layer "F.SilkS")
		)
		(fp_line
			(start 14.01191 -1.26365)
			(end 13.999464 -1.194054)
			(stroke
				(width 0.1)
				(type default)
			)
			(layer "F.SilkS")
		)
		(fp_line
			(start 14.01191 -1.26365)
			(end 13.999464 -1.194054)
			(stroke
				(width 0.1)
				(type default)
			)
			(layer "F.SilkS")
		)
		(fp_line
			(start 14.01191 -1.26365)
			(end 15.367762 -2.564384)
			(stroke
				(width 0.1)
				(type default)
			)
			(layer "F.SilkS")
		)
		(fp_line
			(start 14.01191 -1.26365)
			(end 15.367762 -2.564384)
			(stroke
				(width 0.1)
				(type default)
			)
			(layer "F.SilkS")
		)
		(fp_line
			(start 14.023848 -1.332738)
			(end 14.01191 -1.26365)
			(stroke
				(width 0.1)
				(type default)
			)
			(layer "F.SilkS")
		)
		(fp_line
			(start 14.023848 -1.332738)
			(end 14.01191 -1.26365)
			(stroke
				(width 0.1)
				(type default)
			)
			(layer "F.SilkS")
		)
		(fp_line
			(start 14.023848 -1.332738)
			(end 15.380208 -2.633726)
			(stroke
				(width 0.1)
				(type default)
			)
			(layer "F.SilkS")
		)
		(fp_line
			(start 14.023848 -1.332738)
			(end 15.380208 -2.633726)
			(stroke
				(width 0.1)
				(type default)
			)
			(layer "F.SilkS")
		)
		(fp_line
			(start 14.03604 -1.40208)
			(end 14.023848 -1.332738)
			(stroke
				(width 0.1)
				(type default)
			)
			(layer "F.SilkS")
		)
		(fp_line
			(start 14.03604 -1.40208)
			(end 14.023848 -1.332738)
			(stroke
				(width 0.1)
				(type default)
			)
			(layer "F.SilkS")
		)
		(fp_line
			(start 14.03604 -1.40208)
			(end 15.392654 -2.703322)
			(stroke
				(width 0.1)
				(type default)
			)
			(layer "F.SilkS")
		)
		(fp_line
			(start 14.03604 -1.40208)
			(end 15.392654 -2.703322)
			(stroke
				(width 0.1)
				(type default)
			)
			(layer "F.SilkS")
		)
		(fp_line
			(start 14.036294 -0.882904)
			(end 14.096238 -0.882904)
			(stroke
				(width 0.1)
				(type default)
			)
			(layer "F.SilkS")
		)
		(fp_line
			(start 14.036294 -0.882904)
			(end 14.096238 -0.882904)
			(stroke
				(width 0.1)
				(type default)
			)
			(layer "F.SilkS")
		)
		(fp_line
			(start 14.036294 -0.882904)
			(end 15.282418 -2.078482)
			(stroke
				(width 0.1)
				(type default)
			)
			(layer "F.SilkS")
		)
		(fp_line
			(start 14.036294 -0.882904)
			(end 15.282418 -2.078482)
			(stroke
				(width 0.1)
				(type default)
			)
			(layer "F.SilkS")
		)
		(fp_line
			(start 14.048232 -1.471676)
			(end 14.03604 -1.40208)
			(stroke
				(width 0.1)
				(type default)
			)
			(layer "F.SilkS")
		)
		(fp_line
			(start 14.048232 -1.471676)
			(end 14.03604 -1.40208)
			(stroke
				(width 0.1)
				(type default)
			)
			(layer "F.SilkS")
		)
		(fp_line
			(start 14.048232 -1.471676)
			(end 15.404592 -2.772664)
			(stroke
				(width 0.1)
				(type default)
			)
			(layer "F.SilkS")
		)
		(fp_line
			(start 14.048232 -1.471676)
			(end 15.404592 -2.772664)
			(stroke
				(width 0.1)
				(type default)
			)
			(layer "F.SilkS")
		)
		(fp_line
			(start 14.060678 -1.541018)
			(end 14.048232 -1.471676)
			(stroke
				(width 0.1)
				(type default)
			)
			(layer "F.SilkS")
		)
		(fp_line
			(start 14.060678 -1.541018)
			(end 14.048232 -1.471676)
			(stroke
				(width 0.1)
				(type default)
			)
			(layer "F.SilkS")
		)
		(fp_line
			(start 14.060678 -1.541018)
			(end 15.416784 -2.84226)
			(stroke
				(width 0.1)
				(type default)
			)
			(layer "F.SilkS")
		)
		(fp_line
			(start 14.060678 -1.541018)
			(end 15.416784 -2.84226)
			(stroke
				(width 0.1)
				(type default)
			)
			(layer "F.SilkS")
		)
		(fp_line
			(start 14.072362 -1.61036)
			(end 14.060678 -1.541018)
			(stroke
				(width 0.1)
				(type default)
			)
			(layer "F.SilkS")
		)
		(fp_line
			(start 14.072362 -1.61036)
			(end 14.060678 -1.541018)
			(stroke
				(width 0.1)
				(type default)
			)
			(layer "F.SilkS")
		)
		(fp_line
			(start 14.072362 -1.61036)
			(end 15.42923 -2.911602)
			(stroke
				(width 0.1)
				(type default)
			)
			(layer "F.SilkS")
		)
		(fp_line
			(start 14.072362 -1.61036)
			(end 15.42923 -2.911602)
			(stroke
				(width 0.1)
				(type default)
			)
			(layer "F.SilkS")
		)
		(fp_line
			(start 14.084808 -1.679702)
			(end 14.072362 -1.61036)
			(stroke
				(width 0.1)
				(type default)
			)
			(layer "F.SilkS")
		)
		(fp_line
			(start 14.084808 -1.679702)
			(end 14.072362 -1.61036)
			(stroke
				(width 0.1)
				(type default)
			)
			(layer "F.SilkS")
		)
		(fp_line
			(start 14.084808 -1.679702)
			(end 14.097254 -1.749044)
			(stroke
				(width 0.1)
				(type default)
			)
			(layer "F.SilkS")
		)
		(fp_line
			(start 14.084808 -1.679702)
			(end 14.097254 -1.749044)
			(stroke
				(width 0.1)
				(type default)
			)
			(layer "F.SilkS")
		)
		(fp_line
			(start 14.096238 -0.882904)
			(end 14.156436 -0.882904)
			(stroke
				(width 0.1)
				(type default)
			)
			(layer "F.SilkS")
		)
		(fp_line
			(start 14.096238 -0.882904)
			(end 14.156436 -0.882904)
			(stroke
				(width 0.1)
				(type default)
			)
			(layer "F.SilkS")
		)
		(fp_line
			(start 14.096238 -0.882904)
			(end 15.270226 -2.00914)
			(stroke
				(width 0.1)
				(type default)
			)
			(layer "F.SilkS")
		)
		(fp_line
			(start 14.096238 -0.882904)
			(end 15.270226 -2.00914)
			(stroke
				(width 0.1)
				(type default)
			)
			(layer "F.SilkS")
		)
		(fp_line
			(start 14.109192 -1.81864)
			(end 14.097254 -1.749044)
			(stroke
				(width 0.1)
				(type default)
			)
			(layer "F.SilkS")
		)
		(fp_line
			(start 14.109192 -1.81864)
			(end 14.097254 -1.749044)
			(stroke
				(width 0.1)
				(type default)
			)
			(layer "F.SilkS")
		)
		(fp_line
			(start 14.121384 -1.887982)
			(end 14.109192 -1.81864)
			(stroke
				(width 0.1)
				(type default)
			)
			(layer "F.SilkS")
		)
		(fp_line
			(start 14.121384 -1.887982)
			(end 14.109192 -1.81864)
			(stroke
				(width 0.1)
				(type default)
			)
			(layer "F.SilkS")
		)
		(fp_line
			(start 14.13383 -1.957324)
			(end 14.121384 -1.887982)
			(stroke
				(width 0.1)
				(type default)
			)
			(layer "F.SilkS")
		)
		(fp_line
			(start 14.13383 -1.957324)
			(end 14.121384 -1.887982)
			(stroke
				(width 0.1)
				(type default)
			)
			(layer "F.SilkS")
		)
		(fp_line
			(start 14.145768 -2.02692)
			(end 14.13383 -1.957324)
			(stroke
				(width 0.1)
				(type default)
			)
			(layer "F.SilkS")
		)
		(fp_line
			(start 14.145768 -2.02692)
			(end 14.13383 -1.957324)
			(stroke
				(width 0.1)
				(type default)
			)
			(layer "F.SilkS")
		)
		(fp_line
			(start 14.156436 -0.882904)
			(end 14.216888 -0.882904)
			(stroke
				(width 0.1)
				(type default)
			)
			(layer "F.SilkS")
		)
		(fp_line
			(start 14.156436 -0.882904)
			(end 14.216888 -0.882904)
			(stroke
				(width 0.1)
				(type default)
			)
			(layer "F.SilkS")
		)
		(fp_line
			(start 14.156436 -0.882904)
			(end 15.258288 -1.939544)
			(stroke
				(width 0.1)
				(type default)
			)
			(layer "F.SilkS")
		)
		(fp_line
			(start 14.156436 -0.882904)
			(end 15.258288 -1.939544)
			(stroke
				(width 0.1)
				(type default)
			)
			(layer "F.SilkS")
		)
		(fp_line
			(start 14.15796 -2.096262)
			(end 14.145768 -2.02692)
			(stroke
				(width 0.1)
				(type default)
			)
			(layer "F.SilkS")
		)
		(fp_line
			(start 14.15796 -2.096262)
			(end 14.145768 -2.02692)
			(stroke
				(width 0.1)
				(type default)
			)
			(layer "F.SilkS")
		)
		(fp_line
			(start 14.170406 -2.165604)
			(end 14.15796 -2.096262)
			(stroke
				(width 0.1)
				(type default)
			)
			(layer "F.SilkS")
		)
		(fp_line
			(start 14.170406 -2.165604)
			(end 14.15796 -2.096262)
			(stroke
				(width 0.1)
				(type default)
			)
			(layer "F.SilkS")
		)
		(fp_line
			(start 14.182344 -2.234946)
			(end 14.170406 -2.165604)
			(stroke
				(width 0.1)
				(type default)
			)
			(layer "F.SilkS")
		)
		(fp_line
			(start 14.182344 -2.234946)
			(end 14.170406 -2.165604)
			(stroke
				(width 0.1)
				(type default)
			)
			(layer "F.SilkS")
		)
		(fp_line
			(start 14.194282 -2.304288)
			(end 14.182344 -2.234946)
			(stroke
				(width 0.1)
				(type default)
			)
			(layer "F.SilkS")
		)
		(fp_line
			(start 14.194282 -2.304288)
			(end 14.182344 -2.234946)
			(stroke
				(width 0.1)
				(type default)
			)
			(layer "F.SilkS")
		)
		(fp_line
			(start 14.206728 -2.373884)
			(end 14.194282 -2.304288)
			(stroke
				(width 0.1)
				(type default)
			)
			(layer "F.SilkS")
		)
		(fp_line
			(start 14.206728 -2.373884)
			(end 14.194282 -2.304288)
			(stroke
				(width 0.1)
				(type default)
			)
			(layer "F.SilkS")
		)
		(fp_line
			(start 14.216888 -0.882904)
			(end 14.277086 -0.882904)
			(stroke
				(width 0.1)
				(type default)
			)
			(layer "F.SilkS")
		)
		(fp_line
			(start 14.216888 -0.882904)
			(end 14.277086 -0.882904)
			(stroke
				(width 0.1)
				(type default)
			)
			(layer "F.SilkS")
		)
		(fp_line
			(start 14.216888 -0.882904)
			(end 15.245842 -1.869948)
			(stroke
				(width 0.1)
				(type default)
			)
			(layer "F.SilkS")
		)
		(fp_line
			(start 14.216888 -0.882904)
			(end 15.245842 -1.869948)
			(stroke
				(width 0.1)
				(type default)
			)
			(layer "F.SilkS")
		)
		(fp_line
			(start 14.21892 -2.443226)
			(end 14.206728 -2.373884)
			(stroke
				(width 0.1)
				(type default)
			)
			(layer "F.SilkS")
		)
		(fp_line
			(start 14.21892 -2.443226)
			(end 14.206728 -2.373884)
			(stroke
				(width 0.1)
				(type default)
			)
			(layer "F.SilkS")
		)
		(fp_line
			(start 14.230858 -2.512314)
			(end 14.21892 -2.443226)
			(stroke
				(width 0.1)
				(type default)
			)
			(layer "F.SilkS")
		)
		(fp_line
			(start 14.230858 -2.512314)
			(end 14.21892 -2.443226)
			(stroke
				(width 0.1)
				(type default)
			)
			(layer "F.SilkS")
		)
		(fp_line
			(start 14.243304 -2.58191)
			(end 14.230858 -2.512314)
			(stroke
				(width 0.1)
				(type default)
			)
			(layer "F.SilkS")
		)
		(fp_line
			(start 14.243304 -2.58191)
			(end 14.230858 -2.512314)
			(stroke
				(width 0.1)
				(type default)
			)
			(layer "F.SilkS")
		)
		(fp_line
			(start 14.255496 -2.651506)
			(end 14.243304 -2.58191)
			(stroke
				(width 0.1)
				(type default)
			)
			(layer "F.SilkS")
		)
		(fp_line
			(start 14.255496 -2.651506)
			(end 14.243304 -2.58191)
			(stroke
				(width 0.1)
				(type default)
			)
			(layer "F.SilkS")
		)
		(fp_line
			(start 14.267434 -2.720594)
			(end 14.255496 -2.651506)
			(stroke
				(width 0.1)
				(type default)
			)
			(layer "F.SilkS")
		)
		(fp_line
			(start 14.267434 -2.720594)
			(end 14.255496 -2.651506)
			(stroke
				(width 0.1)
				(type default)
			)
			(layer "F.SilkS")
		)
		(fp_line
			(start 14.277086 -0.882904)
			(end 14.33703 -0.882904)
			(stroke
				(width 0.1)
				(type default)
			)
			(layer "F.SilkS")
		)
		(fp_line
			(start 14.277086 -0.882904)
			(end 14.33703 -0.882904)
			(stroke
				(width 0.1)
				(type default)
			)
			(layer "F.SilkS")
		)
		(fp_line
			(start 14.277086 -0.882904)
			(end 15.233396 -1.800606)
			(stroke
				(width 0.1)
				(type default)
			)
			(layer "F.SilkS")
		)
		(fp_line
			(start 14.277086 -0.882904)
			(end 15.233396 -1.800606)
			(stroke
				(width 0.1)
				(type default)
			)
			(layer "F.SilkS")
		)
		(fp_line
			(start 14.27988 -2.79019)
			(end 14.267434 -2.720594)
			(stroke
				(width 0.1)
				(type default)
			)
			(layer "F.SilkS")
		)
		(fp_line
			(start 14.27988 -2.79019)
			(end 14.267434 -2.720594)
			(stroke
				(width 0.1)
				(type default)
			)
			(layer "F.SilkS")
		)
		(fp_line
			(start 14.291818 -2.859532)
			(end 14.27988 -2.79019)
			(stroke
				(width 0.1)
				(type default)
			)
			(layer "F.SilkS")
		)
		(fp_line
			(start 14.291818 -2.859532)
			(end 14.27988 -2.79019)
			(stroke
				(width 0.1)
				(type default)
			)
			(layer "F.SilkS")
		)
		(fp_line
			(start 14.30401 -2.928874)
			(end 14.291818 -2.859532)
			(stroke
				(width 0.1)
				(type default)
			)
			(layer "F.SilkS")
		)
		(fp_line
			(start 14.30401 -2.928874)
			(end 14.291818 -2.859532)
			(stroke
				(width 0.1)
				(type default)
			)
			(layer "F.SilkS")
		)
		(fp_line
			(start 14.316456 -2.998216)
			(end 14.30401 -2.928874)
			(stroke
				(width 0.1)
				(type default)
			)
			(layer "F.SilkS")
		)
		(fp_line
			(start 14.316456 -2.998216)
			(end 14.30401 -2.928874)
			(stroke
				(width 0.1)
				(type default)
			)
			(layer "F.SilkS")
		)
		(fp_line
			(start 14.328394 -3.067558)
			(end 14.316456 -2.998216)
			(stroke
				(width 0.1)
				(type default)
			)
			(layer "F.SilkS")
		)
		(fp_line
			(start 14.328394 -3.067558)
			(end 14.316456 -2.998216)
			(stroke
				(width 0.1)
				(type default)
			)
			(layer "F.SilkS")
		)
		(fp_line
			(start 14.33703 -0.882904)
			(end 14.396974 -0.882904)
			(stroke
				(width 0.1)
				(type default)
			)
			(layer "F.SilkS")
		)
		(fp_line
			(start 14.33703 -0.882904)
			(end 14.396974 -0.882904)
			(stroke
				(width 0.1)
				(type default)
			)
			(layer "F.SilkS")
		)
		(fp_line
			(start 14.33703 -0.882904)
			(end 15.221458 -1.731518)
			(stroke
				(width 0.1)
				(type default)
			)
			(layer "F.SilkS")
		)
		(fp_line
			(start 14.33703 -0.882904)
			(end 15.221458 -1.731518)
			(stroke
				(width 0.1)
				(type default)
			)
			(layer "F.SilkS")
		)
		(fp_line
			(start 14.340586 -3.137154)
			(end 14.328394 -3.067558)
			(stroke
				(width 0.1)
				(type default)
			)
			(layer "F.SilkS")
		)
		(fp_line
			(start 14.340586 -3.137154)
			(end 14.328394 -3.067558)
			(stroke
				(width 0.1)
				(type default)
			)
			(layer "F.SilkS")
		)
		(fp_line
			(start 14.352778 -3.206496)
			(end 14.340586 -3.137154)
			(stroke
				(width 0.1)
				(type default)
			)
			(layer "F.SilkS")
		)
		(fp_line
			(start 14.352778 -3.206496)
			(end 14.340586 -3.137154)
			(stroke
				(width 0.1)
				(type default)
			)
			(layer "F.SilkS")
		)
		(fp_line
			(start 14.36497 -3.275838)
			(end 14.352778 -3.206496)
			(stroke
				(width 0.1)
				(type default)
			)
			(layer "F.SilkS")
		)
		(fp_line
			(start 14.36497 -3.275838)
			(end 14.352778 -3.206496)
			(stroke
				(width 0.1)
				(type default)
			)
			(layer "F.SilkS")
		)
		(fp_line
			(start 14.376908 -3.34518)
			(end 14.36497 -3.275838)
			(stroke
				(width 0.1)
				(type default)
			)
			(layer "F.SilkS")
		)
		(fp_line
			(start 14.376908 -3.34518)
			(end 14.36497 -3.275838)
			(stroke
				(width 0.1)
				(type default)
			)
			(layer "F.SilkS")
		)
		(fp_line
			(start 14.389354 -3.414776)
			(end 14.376908 -3.34518)
			(stroke
				(width 0.1)
				(type default)
			)
			(layer "F.SilkS")
		)
		(fp_line
			(start 14.389354 -3.414776)
			(end 14.376908 -3.34518)
			(stroke
				(width 0.1)
				(type default)
			)
			(layer "F.SilkS")
		)
		(fp_line
			(start 14.396974 -0.882904)
			(end 14.45768 -0.882904)
			(stroke
				(width 0.1)
				(type default)
			)
			(layer "F.SilkS")
		)
		(fp_line
			(start 14.396974 -0.882904)
			(end 14.45768 -0.882904)
			(stroke
				(width 0.1)
				(type default)
			)
			(layer "F.SilkS")
		)
		(fp_line
			(start 14.396974 -0.882904)
			(end 15.209266 -1.661922)
			(stroke
				(width 0.1)
				(type default)
			)
			(layer "F.SilkS")
		)
		(fp_line
			(start 14.396974 -0.882904)
			(end 15.209266 -1.661922)
			(stroke
				(width 0.1)
				(type default)
			)
			(layer "F.SilkS")
		)
		(fp_line
			(start 14.401546 -3.484118)
			(end 14.389354 -3.414776)
			(stroke
				(width 0.1)
				(type default)
			)
			(layer "F.SilkS")
		)
		(fp_line
			(start 14.401546 -3.484118)
			(end 14.389354 -3.414776)
			(stroke
				(width 0.1)
				(type default)
			)
			(layer "F.SilkS")
		)
		(fp_line
			(start 14.413484 -3.55346)
			(end 14.401546 -3.484118)
			(stroke
				(width 0.1)
				(type default)
			)
			(layer "F.SilkS")
		)
		(fp_line
			(start 14.413484 -3.55346)
			(end 14.401546 -3.484118)
			(stroke
				(width 0.1)
				(type default)
			)
			(layer "F.SilkS")
		)
		(fp_line
			(start 14.42593 -3.622802)
			(end 14.413484 -3.55346)
			(stroke
				(width 0.1)
				(type default)
			)
			(layer "F.SilkS")
		)
		(fp_line
			(start 14.42593 -3.622802)
			(end 14.413484 -3.55346)
			(stroke
				(width 0.1)
				(type default)
			)
			(layer "F.SilkS")
		)
		(fp_line
			(start 14.438376 -3.692398)
			(end 14.42593 -3.622802)
			(stroke
				(width 0.1)
				(type default)
			)
			(layer "F.SilkS")
		)
		(fp_line
			(start 14.438376 -3.692398)
			(end 14.42593 -3.622802)
			(stroke
				(width 0.1)
				(type default)
			)
			(layer "F.SilkS")
		)
		(fp_line
			(start 14.45006 -3.76174)
			(end 14.438376 -3.692398)
			(stroke
				(width 0.1)
				(type default)
			)
			(layer "F.SilkS")
		)
		(fp_line
			(start 14.45006 -3.76174)
			(end 14.438376 -3.692398)
			(stroke
				(width 0.1)
				(type default)
			)
			(layer "F.SilkS")
		)
		(fp_line
			(start 14.45768 -0.882904)
			(end 14.517624 -0.882904)
			(stroke
				(width 0.1)
				(type default)
			)
			(layer "F.SilkS")
		)
		(fp_line
			(start 14.45768 -0.882904)
			(end 14.517624 -0.882904)
			(stroke
				(width 0.1)
				(type default)
			)
			(layer "F.SilkS")
		)
		(fp_line
			(start 14.45768 -0.882904)
			(end 15.19682 -1.592326)
			(stroke
				(width 0.1)
				(type default)
			)
			(layer "F.SilkS")
		)
		(fp_line
			(start 14.45768 -0.882904)
			(end 15.19682 -1.592326)
			(stroke
				(width 0.1)
				(type default)
			)
			(layer "F.SilkS")
		)
		(fp_line
			(start 14.462506 -3.831082)
			(end 14.45006 -3.76174)
			(stroke
				(width 0.1)
				(type default)
			)
			(layer "F.SilkS")
		)
		(fp_line
			(start 14.462506 -3.831082)
			(end 14.45006 -3.76174)
			(stroke
				(width 0.1)
				(type default)
			)
			(layer "F.SilkS")
		)
		(fp_line
			(start 14.474952 -3.900424)
			(end 14.462506 -3.831082)
			(stroke
				(width 0.1)
				(type default)
			)
			(layer "F.SilkS")
		)
		(fp_line
			(start 14.474952 -3.900424)
			(end 14.462506 -3.831082)
			(stroke
				(width 0.1)
				(type default)
			)
			(layer "F.SilkS")
		)
		(fp_line
			(start 14.486636 -3.969766)
			(end 14.474952 -3.900424)
			(stroke
				(width 0.1)
				(type default)
			)
			(layer "F.SilkS")
		)
		(fp_line
			(start 14.486636 -3.969766)
			(end 14.474952 -3.900424)
			(stroke
				(width 0.1)
				(type default)
			)
			(layer "F.SilkS")
		)
		(fp_line
			(start 14.498828 -4.039362)
			(end 14.486636 -3.969766)
			(stroke
				(width 0.1)
				(type default)
			)
			(layer "F.SilkS")
		)
		(fp_line
			(start 14.498828 -4.039362)
			(end 14.486636 -3.969766)
			(stroke
				(width 0.1)
				(type default)
			)
			(layer "F.SilkS")
		)
		(fp_line
			(start 14.511274 -4.108704)
			(end 14.498828 -4.039362)
			(stroke
				(width 0.1)
				(type default)
			)
			(layer "F.SilkS")
		)
		(fp_line
			(start 14.511274 -4.108704)
			(end 14.498828 -4.039362)
			(stroke
				(width 0.1)
				(type default)
			)
			(layer "F.SilkS")
		)
		(fp_line
			(start 14.517624 -0.882904)
			(end 14.577568 -0.882904)
			(stroke
				(width 0.1)
				(type default)
			)
			(layer "F.SilkS")
		)
		(fp_line
			(start 14.517624 -0.882904)
			(end 14.577568 -0.882904)
			(stroke
				(width 0.1)
				(type default)
			)
			(layer "F.SilkS")
		)
		(fp_line
			(start 14.517624 -0.882904)
			(end 15.184882 -1.522984)
			(stroke
				(width 0.1)
				(type default)
			)
			(layer "F.SilkS")
		)
		(fp_line
			(start 14.517624 -0.882904)
			(end 15.184882 -1.522984)
			(stroke
				(width 0.1)
				(type default)
			)
			(layer "F.SilkS")
		)
		(fp_line
			(start 14.523466 -4.178046)
			(end 14.511274 -4.108704)
			(stroke
				(width 0.1)
				(type default)
			)
			(layer "F.SilkS")
		)
		(fp_line
			(start 14.523466 -4.178046)
			(end 14.511274 -4.108704)
			(stroke
				(width 0.1)
				(type default)
			)
			(layer "F.SilkS")
		)
		(fp_line
			(start 14.523466 -4.178046)
			(end 14.535404 -4.247388)
			(stroke
				(width 0.1)
				(type default)
			)
			(layer "F.SilkS")
		)
		(fp_line
			(start 14.523466 -4.178046)
			(end 14.535404 -4.247388)
			(stroke
				(width 0.1)
				(type default)
			)
			(layer "F.SilkS")
		)
		(fp_line
			(start 14.535404 -4.247388)
			(end 14.54785 -4.316984)
			(stroke
				(width 0.1)
				(type default)
			)
			(layer "F.SilkS")
		)
		(fp_line
			(start 14.535404 -4.247388)
			(end 14.54785 -4.316984)
			(stroke
				(width 0.1)
				(type default)
			)
			(layer "F.SilkS")
		)
		(fp_line
			(start 14.54785 -4.316984)
			(end 14.560042 -4.386326)
			(stroke
				(width 0.1)
				(type default)
			)
			(layer "F.SilkS")
		)
		(fp_line
			(start 14.54785 -4.316984)
			(end 14.560042 -4.386326)
			(stroke
				(width 0.1)
				(type default)
			)
			(layer "F.SilkS")
		)
		(fp_line
			(start 14.560042 -4.386326)
			(end 14.57198 -4.455668)
			(stroke
				(width 0.1)
				(type default)
			)
			(layer "F.SilkS")
		)
		(fp_line
			(start 14.560042 -4.386326)
			(end 14.57198 -4.455668)
			(stroke
				(width 0.1)
				(type default)
			)
			(layer "F.SilkS")
		)
		(fp_line
			(start 14.57198 -4.455668)
			(end 14.584426 -4.52501)
			(stroke
				(width 0.1)
				(type default)
			)
			(layer "F.SilkS")
		)
		(fp_line
			(start 14.57198 -4.455668)
			(end 14.584426 -4.52501)
			(stroke
				(width 0.1)
				(type default)
			)
			(layer "F.SilkS")
		)
		(fp_line
			(start 14.577568 -0.882904)
			(end 14.637766 -0.882904)
			(stroke
				(width 0.1)
				(type default)
			)
			(layer "F.SilkS")
		)
		(fp_line
			(start 14.577568 -0.882904)
			(end 14.637766 -0.882904)
			(stroke
				(width 0.1)
				(type default)
			)
			(layer "F.SilkS")
		)
		(fp_line
			(start 14.577568 -0.882904)
			(end 15.17269 -1.453642)
			(stroke
				(width 0.1)
				(type default)
			)
			(layer "F.SilkS")
		)
		(fp_line
			(start 14.577568 -0.882904)
			(end 15.17269 -1.453642)
			(stroke
				(width 0.1)
				(type default)
			)
			(layer "F.SilkS")
		)
		(fp_line
			(start 14.584426 -4.52501)
			(end 14.596364 -4.594352)
			(stroke
				(width 0.1)
				(type default)
			)
			(layer "F.SilkS")
		)
		(fp_line
			(start 14.584426 -4.52501)
			(end 14.596364 -4.594352)
			(stroke
				(width 0.1)
				(type default)
			)
			(layer "F.SilkS")
		)
		(fp_line
			(start 14.596364 -4.594352)
			(end 14.608556 -4.663948)
			(stroke
				(width 0.1)
				(type default)
			)
			(layer "F.SilkS")
		)
		(fp_line
			(start 14.596364 -4.594352)
			(end 14.608556 -4.663948)
			(stroke
				(width 0.1)
				(type default)
			)
			(layer "F.SilkS")
		)
		(fp_line
			(start 14.608556 -4.663948)
			(end 14.621002 -4.733036)
			(stroke
				(width 0.1)
				(type default)
			)
			(layer "F.SilkS")
		)
		(fp_line
			(start 14.608556 -4.663948)
			(end 14.621002 -4.733036)
			(stroke
				(width 0.1)
				(type default)
			)
			(layer "F.SilkS")
		)
		(fp_line
			(start 14.621002 -4.733036)
			(end 14.63294 -4.802632)
			(stroke
				(width 0.1)
				(type default)
			)
			(layer "F.SilkS")
		)
		(fp_line
			(start 14.621002 -4.733036)
			(end 14.63294 -4.802632)
			(stroke
				(width 0.1)
				(type default)
			)
			(layer "F.SilkS")
		)
		(fp_line
			(start 14.63294 -4.802632)
			(end 14.645132 -4.872228)
			(stroke
				(width 0.1)
				(type default)
			)
			(layer "F.SilkS")
		)
		(fp_line
			(start 14.63294 -4.802632)
			(end 14.645132 -4.872228)
			(stroke
				(width 0.1)
				(type default)
			)
			(layer "F.SilkS")
		)
		(fp_line
			(start 14.637766 -0.882904)
			(end 14.697964 -0.882904)
			(stroke
				(width 0.1)
				(type default)
			)
			(layer "F.SilkS")
		)
		(fp_line
			(start 14.637766 -0.882904)
			(end 14.697964 -0.882904)
			(stroke
				(width 0.1)
				(type default)
			)
			(layer "F.SilkS")
		)
		(fp_line
			(start 14.637766 -0.882904)
			(end 15.160498 -1.384046)
			(stroke
				(width 0.1)
				(type default)
			)
			(layer "F.SilkS")
		)
		(fp_line
			(start 14.637766 -0.882904)
			(end 15.160498 -1.384046)
			(stroke
				(width 0.1)
				(type default)
			)
			(layer "F.SilkS")
		)
		(fp_line
			(start 14.645132 -4.872228)
			(end 14.657324 -4.941316)
			(stroke
				(width 0.1)
				(type default)
			)
			(layer "F.SilkS")
		)
		(fp_line
			(start 14.645132 -4.872228)
			(end 14.657324 -4.941316)
			(stroke
				(width 0.1)
				(type default)
			)
			(layer "F.SilkS")
		)
		(fp_line
			(start 14.657324 -4.941316)
			(end 14.669516 -5.010912)
			(stroke
				(width 0.1)
				(type default)
			)
			(layer "F.SilkS")
		)
		(fp_line
			(start 14.657324 -4.941316)
			(end 14.669516 -5.010912)
			(stroke
				(width 0.1)
				(type default)
			)
			(layer "F.SilkS")
		)
		(fp_line
			(start 14.669516 -5.010912)
			(end 14.681454 -5.080254)
			(stroke
				(width 0.1)
				(type default)
			)
			(layer "F.SilkS")
		)
		(fp_line
			(start 14.669516 -5.010912)
			(end 14.681454 -5.080254)
			(stroke
				(width 0.1)
				(type default)
			)
			(layer "F.SilkS")
		)
		(fp_line
			(start 14.681454 -5.080254)
			(end 14.6939 -5.149596)
			(stroke
				(width 0.1)
				(type default)
			)
			(layer "F.SilkS")
		)
		(fp_line
			(start 14.681454 -5.080254)
			(end 14.6939 -5.149596)
			(stroke
				(width 0.1)
				(type default)
			)
			(layer "F.SilkS")
		)
		(fp_line
			(start 14.69771 -5.171694)
			(end 14.6939 -5.149596)
			(stroke
				(width 0.1)
				(type default)
			)
			(layer "F.SilkS")
		)
		(fp_line
			(start 14.69771 -5.171694)
			(end 14.6939 -5.149596)
			(stroke
				(width 0.1)
				(type default)
			)
			(layer "F.SilkS")
		)
		(fp_line
			(start 14.697964 -0.882904)
			(end 14.757908 -0.882904)
			(stroke
				(width 0.1)
				(type default)
			)
			(layer "F.SilkS")
		)
		(fp_line
			(start 14.697964 -0.882904)
			(end 14.757908 -0.882904)
			(stroke
				(width 0.1)
				(type default)
			)
			(layer "F.SilkS")
		)
		(fp_line
			(start 14.697964 -0.882904)
			(end 15.148052 -1.314704)
			(stroke
				(width 0.1)
				(type default)
			)
			(layer "F.SilkS")
		)
		(fp_line
			(start 14.697964 -0.882904)
			(end 15.148052 -1.314704)
			(stroke
				(width 0.1)
				(type default)
			)
			(layer "F.SilkS")
		)
		(fp_line
			(start 14.71676 -5.171694)
			(end 14.6939 -5.149596)
			(stroke
				(width 0.1)
				(type default)
			)
			(layer "F.SilkS")
		)
		(fp_line
			(start 14.71676 -5.171694)
			(end 14.6939 -5.149596)
			(stroke
				(width 0.1)
				(type default)
			)
			(layer "F.SilkS")
		)
		(fp_line
			(start 14.71676 -5.171694)
			(end 14.69771 -5.171694)
			(stroke
				(width 0.1)
				(type default)
			)
			(layer "F.SilkS")
		)
		(fp_line
			(start 14.71676 -5.171694)
			(end 14.69771 -5.171694)
			(stroke
				(width 0.1)
				(type default)
			)
			(layer "F.SilkS")
		)
		(fp_line
			(start 14.757908 -0.882904)
			(end 14.81836 -0.882904)
			(stroke
				(width 0.1)
				(type default)
			)
			(layer "F.SilkS")
		)
		(fp_line
			(start 14.757908 -0.882904)
			(end 14.81836 -0.882904)
			(stroke
				(width 0.1)
				(type default)
			)
			(layer "F.SilkS")
		)
		(fp_line
			(start 14.757908 -0.882904)
			(end 15.13586 -1.245362)
			(stroke
				(width 0.1)
				(type default)
			)
			(layer "F.SilkS")
		)
		(fp_line
			(start 14.757908 -0.882904)
			(end 15.13586 -1.245362)
			(stroke
				(width 0.1)
				(type default)
			)
			(layer "F.SilkS")
		)
		(fp_line
			(start 14.776958 -5.171694)
			(end 14.681454 -5.080254)
			(stroke
				(width 0.1)
				(type default)
			)
			(layer "F.SilkS")
		)
		(fp_line
			(start 14.776958 -5.171694)
			(end 14.681454 -5.080254)
			(stroke
				(width 0.1)
				(type default)
			)
			(layer "F.SilkS")
		)
		(fp_line
			(start 14.776958 -5.171694)
			(end 14.71676 -5.171694)
			(stroke
				(width 0.1)
				(type default)
			)
			(layer "F.SilkS")
		)
		(fp_line
			(start 14.776958 -5.171694)
			(end 14.71676 -5.171694)
			(stroke
				(width 0.1)
				(type default)
			)
			(layer "F.SilkS")
		)
		(fp_line
			(start 14.81836 -0.882904)
			(end 14.878558 -0.882904)
			(stroke
				(width 0.1)
				(type default)
			)
			(layer "F.SilkS")
		)
		(fp_line
			(start 14.81836 -0.882904)
			(end 14.878558 -0.882904)
			(stroke
				(width 0.1)
				(type default)
			)
			(layer "F.SilkS")
		)
		(fp_line
			(start 14.81836 -0.882904)
			(end 15.123922 -1.17602)
			(stroke
				(width 0.1)
				(type default)
			)
			(layer "F.SilkS")
		)
		(fp_line
			(start 14.81836 -0.882904)
			(end 15.123922 -1.17602)
			(stroke
				(width 0.1)
				(type default)
			)
			(layer "F.SilkS")
		)
		(fp_line
			(start 14.837156 -5.171694)
			(end 14.669516 -5.010912)
			(stroke
				(width 0.1)
				(type default)
			)
			(layer "F.SilkS")
		)
		(fp_line
			(start 14.837156 -5.171694)
			(end 14.669516 -5.010912)
			(stroke
				(width 0.1)
				(type default)
			)
			(layer "F.SilkS")
		)
		(fp_line
			(start 14.837156 -5.171694)
			(end 14.776958 -5.171694)
			(stroke
				(width 0.1)
				(type default)
			)
			(layer "F.SilkS")
		)
		(fp_line
			(start 14.837156 -5.171694)
			(end 14.776958 -5.171694)
			(stroke
				(width 0.1)
				(type default)
			)
			(layer "F.SilkS")
		)
		(fp_line
			(start 14.878558 -0.882904)
			(end 14.938502 -0.882904)
			(stroke
				(width 0.1)
				(type default)
			)
			(layer "F.SilkS")
		)
		(fp_line
			(start 14.878558 -0.882904)
			(end 14.938502 -0.882904)
			(stroke
				(width 0.1)
				(type default)
			)
			(layer "F.SilkS")
		)
		(fp_line
			(start 14.878558 -0.882904)
			(end 15.111476 -1.106424)
			(stroke
				(width 0.1)
				(type default)
			)
			(layer "F.SilkS")
		)
		(fp_line
			(start 14.878558 -0.882904)
			(end 15.111476 -1.106424)
			(stroke
				(width 0.1)
				(type default)
			)
			(layer "F.SilkS")
		)
		(fp_line
			(start 14.8971 -5.171694)
			(end 14.657324 -4.941316)
			(stroke
				(width 0.1)
				(type default)
			)
			(layer "F.SilkS")
		)
		(fp_line
			(start 14.8971 -5.171694)
			(end 14.657324 -4.941316)
			(stroke
				(width 0.1)
				(type default)
			)
			(layer "F.SilkS")
		)
		(fp_line
			(start 14.8971 -5.171694)
			(end 14.837156 -5.171694)
			(stroke
				(width 0.1)
				(type default)
			)
			(layer "F.SilkS")
		)
		(fp_line
			(start 14.8971 -5.171694)
			(end 14.837156 -5.171694)
			(stroke
				(width 0.1)
				(type default)
			)
			(layer "F.SilkS")
		)
		(fp_line
			(start 14.938502 -0.882904)
			(end 14.998954 -0.882904)
			(stroke
				(width 0.1)
				(type default)
			)
			(layer "F.SilkS")
		)
		(fp_line
			(start 14.938502 -0.882904)
			(end 14.998954 -0.882904)
			(stroke
				(width 0.1)
				(type default)
			)
			(layer "F.SilkS")
		)
		(fp_line
			(start 14.938502 -0.882904)
			(end 15.09903 -1.036828)
			(stroke
				(width 0.1)
				(type default)
			)
			(layer "F.SilkS")
		)
		(fp_line
			(start 14.938502 -0.882904)
			(end 15.09903 -1.036828)
			(stroke
				(width 0.1)
				(type default)
			)
			(layer "F.SilkS")
		)
		(fp_line
			(start 14.957552 -5.171694)
			(end 14.645132 -4.872228)
			(stroke
				(width 0.1)
				(type default)
			)
			(layer "F.SilkS")
		)
		(fp_line
			(start 14.957552 -5.171694)
			(end 14.645132 -4.872228)
			(stroke
				(width 0.1)
				(type default)
			)
			(layer "F.SilkS")
		)
		(fp_line
			(start 14.957552 -5.171694)
			(end 14.8971 -5.171694)
			(stroke
				(width 0.1)
				(type default)
			)
			(layer "F.SilkS")
		)
		(fp_line
			(start 14.957552 -5.171694)
			(end 14.8971 -5.171694)
			(stroke
				(width 0.1)
				(type default)
			)
			(layer "F.SilkS")
		)
		(fp_line
			(start 14.998954 -0.882904)
			(end 15.059152 -0.882904)
			(stroke
				(width 0.1)
				(type default)
			)
			(layer "F.SilkS")
		)
		(fp_line
			(start 14.998954 -0.882904)
			(end 15.059152 -0.882904)
			(stroke
				(width 0.1)
				(type default)
			)
			(layer "F.SilkS")
		)
		(fp_line
			(start 14.998954 -0.882904)
			(end 15.087092 -0.96774)
			(stroke
				(width 0.1)
				(type default)
			)
			(layer "F.SilkS")
		)
		(fp_line
			(start 14.998954 -0.882904)
			(end 15.087092 -0.96774)
			(stroke
				(width 0.1)
				(type default)
			)
			(layer "F.SilkS")
		)
		(fp_line
			(start 15.01775 -5.171694)
			(end 14.63294 -4.802632)
			(stroke
				(width 0.1)
				(type default)
			)
			(layer "F.SilkS")
		)
		(fp_line
			(start 15.01775 -5.171694)
			(end 14.63294 -4.802632)
			(stroke
				(width 0.1)
				(type default)
			)
			(layer "F.SilkS")
		)
		(fp_line
			(start 15.01775 -5.171694)
			(end 14.957552 -5.171694)
			(stroke
				(width 0.1)
				(type default)
			)
			(layer "F.SilkS")
		)
		(fp_line
			(start 15.01775 -5.171694)
			(end 14.957552 -5.171694)
			(stroke
				(width 0.1)
				(type default)
			)
			(layer "F.SilkS")
		)
		(fp_line
			(start 15.059152 -0.882904)
			(end 15.072106 -0.882904)
			(stroke
				(width 0.1)
				(type default)
			)
			(layer "F.SilkS")
		)
		(fp_line
			(start 15.059152 -0.882904)
			(end 15.072106 -0.882904)
			(stroke
				(width 0.1)
				(type default)
			)
			(layer "F.SilkS")
		)
		(fp_line
			(start 15.059152 -0.882904)
			(end 15.0749 -0.898398)
			(stroke
				(width 0.1)
				(type default)
			)
			(layer "F.SilkS")
		)
		(fp_line
			(start 15.059152 -0.882904)
			(end 15.0749 -0.898398)
			(stroke
				(width 0.1)
				(type default)
			)
			(layer "F.SilkS")
		)
		(fp_line
			(start 15.072106 -0.882904)
			(end 15.0749 -0.898398)
			(stroke
				(width 0.1)
				(type default)
			)
			(layer "F.SilkS")
		)
		(fp_line
			(start 15.072106 -0.882904)
			(end 15.0749 -0.898398)
			(stroke
				(width 0.1)
				(type default)
			)
			(layer "F.SilkS")
		)
		(fp_line
			(start 15.077694 -5.171694)
			(end 14.621002 -4.733036)
			(stroke
				(width 0.1)
				(type default)
			)
			(layer "F.SilkS")
		)
		(fp_line
			(start 15.077694 -5.171694)
			(end 14.621002 -4.733036)
			(stroke
				(width 0.1)
				(type default)
			)
			(layer "F.SilkS")
		)
		(fp_line
			(start 15.077694 -5.171694)
			(end 15.01775 -5.171694)
			(stroke
				(width 0.1)
				(type default)
			)
			(layer "F.SilkS")
		)
		(fp_line
			(start 15.077694 -5.171694)
			(end 15.01775 -5.171694)
			(stroke
				(width 0.1)
				(type default)
			)
			(layer "F.SilkS")
		)
		(fp_line
			(start 15.087092 -0.96774)
			(end 15.0749 -0.898398)
			(stroke
				(width 0.1)
				(type default)
			)
			(layer "F.SilkS")
		)
		(fp_line
			(start 15.087092 -0.96774)
			(end 15.0749 -0.898398)
			(stroke
				(width 0.1)
				(type default)
			)
			(layer "F.SilkS")
		)
		(fp_line
			(start 15.09903 -1.036828)
			(end 15.087092 -0.96774)
			(stroke
				(width 0.1)
				(type default)
			)
			(layer "F.SilkS")
		)
		(fp_line
			(start 15.09903 -1.036828)
			(end 15.087092 -0.96774)
			(stroke
				(width 0.1)
				(type default)
			)
			(layer "F.SilkS")
		)
		(fp_line
			(start 15.111476 -1.106424)
			(end 15.09903 -1.036828)
			(stroke
				(width 0.1)
				(type default)
			)
			(layer "F.SilkS")
		)
		(fp_line
			(start 15.111476 -1.106424)
			(end 15.09903 -1.036828)
			(stroke
				(width 0.1)
				(type default)
			)
			(layer "F.SilkS")
		)
		(fp_line
			(start 15.123922 -1.17602)
			(end 15.111476 -1.106424)
			(stroke
				(width 0.1)
				(type default)
			)
			(layer "F.SilkS")
		)
		(fp_line
			(start 15.123922 -1.17602)
			(end 15.111476 -1.106424)
			(stroke
				(width 0.1)
				(type default)
			)
			(layer "F.SilkS")
		)
		(fp_line
			(start 15.13586 -1.245362)
			(end 15.123922 -1.17602)
			(stroke
				(width 0.1)
				(type default)
			)
			(layer "F.SilkS")
		)
		(fp_line
			(start 15.13586 -1.245362)
			(end 15.123922 -1.17602)
			(stroke
				(width 0.1)
				(type default)
			)
			(layer "F.SilkS")
		)
		(fp_line
			(start 15.137892 -5.171694)
			(end 14.608556 -4.663948)
			(stroke
				(width 0.1)
				(type default)
			)
			(layer "F.SilkS")
		)
		(fp_line
			(start 15.137892 -5.171694)
			(end 14.608556 -4.663948)
			(stroke
				(width 0.1)
				(type default)
			)
			(layer "F.SilkS")
		)
		(fp_line
			(start 15.137892 -5.171694)
			(end 15.077694 -5.171694)
			(stroke
				(width 0.1)
				(type default)
			)
			(layer "F.SilkS")
		)
		(fp_line
			(start 15.137892 -5.171694)
			(end 15.077694 -5.171694)
			(stroke
				(width 0.1)
				(type default)
			)
			(layer "F.SilkS")
		)
		(fp_line
			(start 15.148052 -1.314704)
			(end 15.13586 -1.245362)
			(stroke
				(width 0.1)
				(type default)
			)
			(layer "F.SilkS")
		)
		(fp_line
			(start 15.148052 -1.314704)
			(end 15.13586 -1.245362)
			(stroke
				(width 0.1)
				(type default)
			)
			(layer "F.SilkS")
		)
		(fp_line
			(start 15.160498 -1.384046)
			(end 15.148052 -1.314704)
			(stroke
				(width 0.1)
				(type default)
			)
			(layer "F.SilkS")
		)
		(fp_line
			(start 15.160498 -1.384046)
			(end 15.148052 -1.314704)
			(stroke
				(width 0.1)
				(type default)
			)
			(layer "F.SilkS")
		)
		(fp_line
			(start 15.17269 -1.453642)
			(end 15.160498 -1.384046)
			(stroke
				(width 0.1)
				(type default)
			)
			(layer "F.SilkS")
		)
		(fp_line
			(start 15.17269 -1.453642)
			(end 15.160498 -1.384046)
			(stroke
				(width 0.1)
				(type default)
			)
			(layer "F.SilkS")
		)
		(fp_line
			(start 15.184882 -1.522984)
			(end 15.17269 -1.453642)
			(stroke
				(width 0.1)
				(type default)
			)
			(layer "F.SilkS")
		)
		(fp_line
			(start 15.184882 -1.522984)
			(end 15.17269 -1.453642)
			(stroke
				(width 0.1)
				(type default)
			)
			(layer "F.SilkS")
		)
		(fp_line
			(start 15.184882 -1.522984)
			(end 15.19682 -1.592326)
			(stroke
				(width 0.1)
				(type default)
			)
			(layer "F.SilkS")
		)
		(fp_line
			(start 15.184882 -1.522984)
			(end 15.19682 -1.592326)
			(stroke
				(width 0.1)
				(type default)
			)
			(layer "F.SilkS")
		)
		(fp_line
			(start 15.19682 -1.592326)
			(end 15.209266 -1.661922)
			(stroke
				(width 0.1)
				(type default)
			)
			(layer "F.SilkS")
		)
		(fp_line
			(start 15.19682 -1.592326)
			(end 15.209266 -1.661922)
			(stroke
				(width 0.1)
				(type default)
			)
			(layer "F.SilkS")
		)
		(fp_line
			(start 15.198344 -5.171694)
			(end 14.596364 -4.594352)
			(stroke
				(width 0.1)
				(type default)
			)
			(layer "F.SilkS")
		)
		(fp_line
			(start 15.198344 -5.171694)
			(end 14.596364 -4.594352)
			(stroke
				(width 0.1)
				(type default)
			)
			(layer "F.SilkS")
		)
		(fp_line
			(start 15.198344 -5.171694)
			(end 15.137892 -5.171694)
			(stroke
				(width 0.1)
				(type default)
			)
			(layer "F.SilkS")
		)
		(fp_line
			(start 15.198344 -5.171694)
			(end 15.137892 -5.171694)
			(stroke
				(width 0.1)
				(type default)
			)
			(layer "F.SilkS")
		)
		(fp_line
			(start 15.209266 -1.661922)
			(end 15.221458 -1.731518)
			(stroke
				(width 0.1)
				(type default)
			)
			(layer "F.SilkS")
		)
		(fp_line
			(start 15.209266 -1.661922)
			(end 15.221458 -1.731518)
			(stroke
				(width 0.1)
				(type default)
			)
			(layer "F.SilkS")
		)
		(fp_line
			(start 15.221458 -1.731518)
			(end 15.233396 -1.800606)
			(stroke
				(width 0.1)
				(type default)
			)
			(layer "F.SilkS")
		)
		(fp_line
			(start 15.221458 -1.731518)
			(end 15.233396 -1.800606)
			(stroke
				(width 0.1)
				(type default)
			)
			(layer "F.SilkS")
		)
		(fp_line
			(start 15.233396 -1.800606)
			(end 15.245842 -1.869948)
			(stroke
				(width 0.1)
				(type default)
			)
			(layer "F.SilkS")
		)
		(fp_line
			(start 15.233396 -1.800606)
			(end 15.245842 -1.869948)
			(stroke
				(width 0.1)
				(type default)
			)
			(layer "F.SilkS")
		)
		(fp_line
			(start 15.245842 -1.869948)
			(end 15.258288 -1.939544)
			(stroke
				(width 0.1)
				(type default)
			)
			(layer "F.SilkS")
		)
		(fp_line
			(start 15.245842 -1.869948)
			(end 15.258288 -1.939544)
			(stroke
				(width 0.1)
				(type default)
			)
			(layer "F.SilkS")
		)
		(fp_line
			(start 15.258288 -5.171694)
			(end 14.584426 -4.52501)
			(stroke
				(width 0.1)
				(type default)
			)
			(layer "F.SilkS")
		)
		(fp_line
			(start 15.258288 -5.171694)
			(end 14.584426 -4.52501)
			(stroke
				(width 0.1)
				(type default)
			)
			(layer "F.SilkS")
		)
		(fp_line
			(start 15.258288 -5.171694)
			(end 15.198344 -5.171694)
			(stroke
				(width 0.1)
				(type default)
			)
			(layer "F.SilkS")
		)
		(fp_line
			(start 15.258288 -5.171694)
			(end 15.198344 -5.171694)
			(stroke
				(width 0.1)
				(type default)
			)
			(layer "F.SilkS")
		)
		(fp_line
			(start 15.258288 -1.939544)
			(end 15.270226 -2.00914)
			(stroke
				(width 0.1)
				(type default)
			)
			(layer "F.SilkS")
		)
		(fp_line
			(start 15.258288 -1.939544)
			(end 15.270226 -2.00914)
			(stroke
				(width 0.1)
				(type default)
			)
			(layer "F.SilkS")
		)
		(fp_line
			(start 15.270226 -2.00914)
			(end 15.282418 -2.078482)
			(stroke
				(width 0.1)
				(type default)
			)
			(layer "F.SilkS")
		)
		(fp_line
			(start 15.270226 -2.00914)
			(end 15.282418 -2.078482)
			(stroke
				(width 0.1)
				(type default)
			)
			(layer "F.SilkS")
		)
		(fp_line
			(start 15.282418 -2.078482)
			(end 15.294864 -2.147824)
			(stroke
				(width 0.1)
				(type default)
			)
			(layer "F.SilkS")
		)
		(fp_line
			(start 15.282418 -2.078482)
			(end 15.294864 -2.147824)
			(stroke
				(width 0.1)
				(type default)
			)
			(layer "F.SilkS")
		)
		(fp_line
			(start 15.294864 -2.147824)
			(end 15.307056 -2.21742)
			(stroke
				(width 0.1)
				(type default)
			)
			(layer "F.SilkS")
		)
		(fp_line
			(start 15.294864 -2.147824)
			(end 15.307056 -2.21742)
			(stroke
				(width 0.1)
				(type default)
			)
			(layer "F.SilkS")
		)
		(fp_line
			(start 15.307056 -2.21742)
			(end 15.319248 -2.286762)
			(stroke
				(width 0.1)
				(type default)
			)
			(layer "F.SilkS")
		)
		(fp_line
			(start 15.307056 -2.21742)
			(end 15.319248 -2.286762)
			(stroke
				(width 0.1)
				(type default)
			)
			(layer "F.SilkS")
		)
		(fp_line
			(start 15.318486 -5.171694)
			(end 14.57198 -4.455668)
			(stroke
				(width 0.1)
				(type default)
			)
			(layer "F.SilkS")
		)
		(fp_line
			(start 15.318486 -5.171694)
			(end 14.57198 -4.455668)
			(stroke
				(width 0.1)
				(type default)
			)
			(layer "F.SilkS")
		)
		(fp_line
			(start 15.318486 -5.171694)
			(end 15.258288 -5.171694)
			(stroke
				(width 0.1)
				(type default)
			)
			(layer "F.SilkS")
		)
		(fp_line
			(start 15.318486 -5.171694)
			(end 15.258288 -5.171694)
			(stroke
				(width 0.1)
				(type default)
			)
			(layer "F.SilkS")
		)
		(fp_line
			(start 15.319248 -2.286762)
			(end 15.331186 -2.356104)
			(stroke
				(width 0.1)
				(type default)
			)
			(layer "F.SilkS")
		)
		(fp_line
			(start 15.319248 -2.286762)
			(end 15.331186 -2.356104)
			(stroke
				(width 0.1)
				(type default)
			)
			(layer "F.SilkS")
		)
		(fp_line
			(start 15.331186 -2.356104)
			(end 15.343632 -2.425446)
			(stroke
				(width 0.1)
				(type default)
			)
			(layer "F.SilkS")
		)
		(fp_line
			(start 15.331186 -2.356104)
			(end 15.343632 -2.425446)
			(stroke
				(width 0.1)
				(type default)
			)
			(layer "F.SilkS")
		)
		(fp_line
			(start 15.343632 -2.425446)
			(end 15.355824 -2.495042)
			(stroke
				(width 0.1)
				(type default)
			)
			(layer "F.SilkS")
		)
		(fp_line
			(start 15.343632 -2.425446)
			(end 15.355824 -2.495042)
			(stroke
				(width 0.1)
				(type default)
			)
			(layer "F.SilkS")
		)
		(fp_line
			(start 15.355824 -2.495042)
			(end 15.367762 -2.564384)
			(stroke
				(width 0.1)
				(type default)
			)
			(layer "F.SilkS")
		)
		(fp_line
			(start 15.355824 -2.495042)
			(end 15.367762 -2.564384)
			(stroke
				(width 0.1)
				(type default)
			)
			(layer "F.SilkS")
		)
		(fp_line
			(start 15.367762 -2.564384)
			(end 15.380208 -2.633726)
			(stroke
				(width 0.1)
				(type default)
			)
			(layer "F.SilkS")
		)
		(fp_line
			(start 15.367762 -2.564384)
			(end 15.380208 -2.633726)
			(stroke
				(width 0.1)
				(type default)
			)
			(layer "F.SilkS")
		)
		(fp_line
			(start 15.378938 -5.171694)
			(end 14.560042 -4.386326)
			(stroke
				(width 0.1)
				(type default)
			)
			(layer "F.SilkS")
		)
		(fp_line
			(start 15.378938 -5.171694)
			(end 14.560042 -4.386326)
			(stroke
				(width 0.1)
				(type default)
			)
			(layer "F.SilkS")
		)
		(fp_line
			(start 15.378938 -5.171694)
			(end 15.318486 -5.171694)
			(stroke
				(width 0.1)
				(type default)
			)
			(layer "F.SilkS")
		)
		(fp_line
			(start 15.378938 -5.171694)
			(end 15.318486 -5.171694)
			(stroke
				(width 0.1)
				(type default)
			)
			(layer "F.SilkS")
		)
		(fp_line
			(start 15.380208 -2.633726)
			(end 15.392654 -2.703322)
			(stroke
				(width 0.1)
				(type default)
			)
			(layer "F.SilkS")
		)
		(fp_line
			(start 15.380208 -2.633726)
			(end 15.392654 -2.703322)
			(stroke
				(width 0.1)
				(type default)
			)
			(layer "F.SilkS")
		)
		(fp_line
			(start 15.392654 -2.703322)
			(end 15.404592 -2.772664)
			(stroke
				(width 0.1)
				(type default)
			)
			(layer "F.SilkS")
		)
		(fp_line
			(start 15.392654 -2.703322)
			(end 15.404592 -2.772664)
			(stroke
				(width 0.1)
				(type default)
			)
			(layer "F.SilkS")
		)
		(fp_line
			(start 15.404592 -2.772664)
			(end 15.416784 -2.84226)
			(stroke
				(width 0.1)
				(type default)
			)
			(layer "F.SilkS")
		)
		(fp_line
			(start 15.404592 -2.772664)
			(end 15.416784 -2.84226)
			(stroke
				(width 0.1)
				(type default)
			)
			(layer "F.SilkS")
		)
		(fp_line
			(start 15.42923 -2.911602)
			(end 15.416784 -2.84226)
			(stroke
				(width 0.1)
				(type default)
			)
			(layer "F.SilkS")
		)
		(fp_line
			(start 15.42923 -2.911602)
			(end 15.416784 -2.84226)
			(stroke
				(width 0.1)
				(type default)
			)
			(layer "F.SilkS")
		)
		(fp_line
			(start 15.438882 -5.171694)
			(end 14.54785 -4.316984)
			(stroke
				(width 0.1)
				(type default)
			)
			(layer "F.SilkS")
		)
		(fp_line
			(start 15.438882 -5.171694)
			(end 14.54785 -4.316984)
			(stroke
				(width 0.1)
				(type default)
			)
			(layer "F.SilkS")
		)
		(fp_line
			(start 15.438882 -5.171694)
			(end 15.378938 -5.171694)
			(stroke
				(width 0.1)
				(type default)
			)
			(layer "F.SilkS")
		)
		(fp_line
			(start 15.438882 -5.171694)
			(end 15.378938 -5.171694)
			(stroke
				(width 0.1)
				(type default)
			)
			(layer "F.SilkS")
		)
		(fp_line
			(start 15.441168 -2.980944)
			(end 14.084808 -1.679702)
			(stroke
				(width 0.1)
				(type default)
			)
			(layer "F.SilkS")
		)
		(fp_line
			(start 15.441168 -2.980944)
			(end 14.084808 -1.679702)
			(stroke
				(width 0.1)
				(type default)
			)
			(layer "F.SilkS")
		)
		(fp_line
			(start 15.441168 -2.980944)
			(end 15.42923 -2.911602)
			(stroke
				(width 0.1)
				(type default)
			)
			(layer "F.SilkS")
		)
		(fp_line
			(start 15.441168 -2.980944)
			(end 15.42923 -2.911602)
			(stroke
				(width 0.1)
				(type default)
			)
			(layer "F.SilkS")
		)
		(fp_line
			(start 15.45336 -3.050286)
			(end 14.097254 -1.749044)
			(stroke
				(width 0.1)
				(type default)
			)
			(layer "F.SilkS")
		)
		(fp_line
			(start 15.45336 -3.050286)
			(end 14.097254 -1.749044)
			(stroke
				(width 0.1)
				(type default)
			)
			(layer "F.SilkS")
		)
		(fp_line
			(start 15.45336 -3.050286)
			(end 15.441168 -2.980944)
			(stroke
				(width 0.1)
				(type default)
			)
			(layer "F.SilkS")
		)
		(fp_line
			(start 15.45336 -3.050286)
			(end 15.441168 -2.980944)
			(stroke
				(width 0.1)
				(type default)
			)
			(layer "F.SilkS")
		)
		(fp_line
			(start 15.465552 -3.119882)
			(end 14.109192 -1.81864)
			(stroke
				(width 0.1)
				(type default)
			)
			(layer "F.SilkS")
		)
		(fp_line
			(start 15.465552 -3.119882)
			(end 14.109192 -1.81864)
			(stroke
				(width 0.1)
				(type default)
			)
			(layer "F.SilkS")
		)
		(fp_line
			(start 15.465552 -3.119882)
			(end 15.45336 -3.050286)
			(stroke
				(width 0.1)
				(type default)
			)
			(layer "F.SilkS")
		)
		(fp_line
			(start 15.465552 -3.119882)
			(end 15.45336 -3.050286)
			(stroke
				(width 0.1)
				(type default)
			)
			(layer "F.SilkS")
		)
		(fp_line
			(start 15.477998 -3.189224)
			(end 14.121384 -1.887982)
			(stroke
				(width 0.1)
				(type default)
			)
			(layer "F.SilkS")
		)
		(fp_line
			(start 15.477998 -3.189224)
			(end 14.121384 -1.887982)
			(stroke
				(width 0.1)
				(type default)
			)
			(layer "F.SilkS")
		)
		(fp_line
			(start 15.477998 -3.189224)
			(end 15.465552 -3.119882)
			(stroke
				(width 0.1)
				(type default)
			)
			(layer "F.SilkS")
		)
		(fp_line
			(start 15.477998 -3.189224)
			(end 15.465552 -3.119882)
			(stroke
				(width 0.1)
				(type default)
			)
			(layer "F.SilkS")
		)
		(fp_line
			(start 15.491714 -3.260344)
			(end 14.13383 -1.957324)
			(stroke
				(width 0.1)
				(type default)
			)
			(layer "F.SilkS")
		)
		(fp_line
			(start 15.491714 -3.260344)
			(end 14.13383 -1.957324)
			(stroke
				(width 0.1)
				(type default)
			)
			(layer "F.SilkS")
		)
		(fp_line
			(start 15.49908 -5.171694)
			(end 14.535404 -4.247388)
			(stroke
				(width 0.1)
				(type default)
			)
			(layer "F.SilkS")
		)
		(fp_line
			(start 15.49908 -5.171694)
			(end 14.535404 -4.247388)
			(stroke
				(width 0.1)
				(type default)
			)
			(layer "F.SilkS")
		)
		(fp_line
			(start 15.49908 -5.171694)
			(end 15.438882 -5.171694)
			(stroke
				(width 0.1)
				(type default)
			)
			(layer "F.SilkS")
		)
		(fp_line
			(start 15.49908 -5.171694)
			(end 15.438882 -5.171694)
			(stroke
				(width 0.1)
				(type default)
			)
			(layer "F.SilkS")
		)
		(fp_line
			(start 15.508478 -3.334004)
			(end 14.145768 -2.02692)
			(stroke
				(width 0.1)
				(type default)
			)
			(layer "F.SilkS")
		)
		(fp_line
			(start 15.508478 -3.334004)
			(end 14.145768 -2.02692)
			(stroke
				(width 0.1)
				(type default)
			)
			(layer "F.SilkS")
		)
		(fp_line
			(start 15.524988 -3.40741)
			(end 14.15796 -2.096262)
			(stroke
				(width 0.1)
				(type default)
			)
			(layer "F.SilkS")
		)
		(fp_line
			(start 15.524988 -3.40741)
			(end 14.15796 -2.096262)
			(stroke
				(width 0.1)
				(type default)
			)
			(layer "F.SilkS")
		)
		(fp_line
			(start 15.54099 -3.480562)
			(end 14.170406 -2.165604)
			(stroke
				(width 0.1)
				(type default)
			)
			(layer "F.SilkS")
		)
		(fp_line
			(start 15.54099 -3.480562)
			(end 14.170406 -2.165604)
			(stroke
				(width 0.1)
				(type default)
			)
			(layer "F.SilkS")
		)
		(fp_line
			(start 15.559278 -5.171694)
			(end 14.523466 -4.178046)
			(stroke
				(width 0.1)
				(type default)
			)
			(layer "F.SilkS")
		)
		(fp_line
			(start 15.559278 -5.171694)
			(end 14.523466 -4.178046)
			(stroke
				(width 0.1)
				(type default)
			)
			(layer "F.SilkS")
		)
		(fp_line
			(start 15.559278 -5.171694)
			(end 15.49908 -5.171694)
			(stroke
				(width 0.1)
				(type default)
			)
			(layer "F.SilkS")
		)
		(fp_line
			(start 15.559278 -5.171694)
			(end 15.49908 -5.171694)
			(stroke
				(width 0.1)
				(type default)
			)
			(layer "F.SilkS")
		)
		(fp_line
			(start 15.570962 -3.566922)
			(end 14.182344 -2.234946)
			(stroke
				(width 0.1)
				(type default)
			)
			(layer "F.SilkS")
		)
		(fp_line
			(start 15.570962 -3.566922)
			(end 14.182344 -2.234946)
			(stroke
				(width 0.1)
				(type default)
			)
			(layer "F.SilkS")
		)
		(fp_line
			(start 15.601442 -3.654044)
			(end 14.194282 -2.304288)
			(stroke
				(width 0.1)
				(type default)
			)
			(layer "F.SilkS")
		)
		(fp_line
			(start 15.601442 -3.654044)
			(end 14.194282 -2.304288)
			(stroke
				(width 0.1)
				(type default)
			)
			(layer "F.SilkS")
		)
		(fp_line
			(start 15.619222 -5.171694)
			(end 14.511274 -4.108704)
			(stroke
				(width 0.1)
				(type default)
			)
			(layer "F.SilkS")
		)
		(fp_line
			(start 15.619222 -5.171694)
			(end 14.511274 -4.108704)
			(stroke
				(width 0.1)
				(type default)
			)
			(layer "F.SilkS")
		)
		(fp_line
			(start 15.619222 -5.171694)
			(end 15.559278 -5.171694)
			(stroke
				(width 0.1)
				(type default)
			)
			(layer "F.SilkS")
		)
		(fp_line
			(start 15.619222 -5.171694)
			(end 15.559278 -5.171694)
			(stroke
				(width 0.1)
				(type default)
			)
			(layer "F.SilkS")
		)
		(fp_line
			(start 15.649702 -3.75793)
			(end 14.206728 -2.373884)
			(stroke
				(width 0.1)
				(type default)
			)
			(layer "F.SilkS")
		)
		(fp_line
			(start 15.649702 -3.75793)
			(end 14.206728 -2.373884)
			(stroke
				(width 0.1)
				(type default)
			)
			(layer "F.SilkS")
		)
		(fp_line
			(start 15.679166 -5.171694)
			(end 14.498828 -4.039362)
			(stroke
				(width 0.1)
				(type default)
			)
			(layer "F.SilkS")
		)
		(fp_line
			(start 15.679166 -5.171694)
			(end 14.498828 -4.039362)
			(stroke
				(width 0.1)
				(type default)
			)
			(layer "F.SilkS")
		)
		(fp_line
			(start 15.679166 -5.171694)
			(end 15.619222 -5.171694)
			(stroke
				(width 0.1)
				(type default)
			)
			(layer "F.SilkS")
		)
		(fp_line
			(start 15.679166 -5.171694)
			(end 15.619222 -5.171694)
			(stroke
				(width 0.1)
				(type default)
			)
			(layer "F.SilkS")
		)
		(fp_line
			(start 15.729458 -3.892296)
			(end 14.21892 -2.443226)
			(stroke
				(width 0.1)
				(type default)
			)
			(layer "F.SilkS")
		)
		(fp_line
			(start 15.729458 -3.892296)
			(end 14.21892 -2.443226)
			(stroke
				(width 0.1)
				(type default)
			)
			(layer "F.SilkS")
		)
		(fp_line
			(start 15.739618 -5.171694)
			(end 14.486636 -3.969766)
			(stroke
				(width 0.1)
				(type default)
			)
			(layer "F.SilkS")
		)
		(fp_line
			(start 15.739618 -5.171694)
			(end 14.486636 -3.969766)
			(stroke
				(width 0.1)
				(type default)
			)
			(layer "F.SilkS")
		)
		(fp_line
			(start 15.739618 -5.171694)
			(end 15.679166 -5.171694)
			(stroke
				(width 0.1)
				(type default)
			)
			(layer "F.SilkS")
		)
		(fp_line
			(start 15.739618 -5.171694)
			(end 15.679166 -5.171694)
			(stroke
				(width 0.1)
				(type default)
			)
			(layer "F.SilkS")
		)
		(fp_line
			(start 15.781274 -4.923028)
			(end 14.42593 -3.622802)
			(stroke
				(width 0.1)
				(type default)
			)
			(layer "F.SilkS")
		)
		(fp_line
			(start 15.781274 -4.923028)
			(end 14.42593 -3.622802)
			(stroke
				(width 0.1)
				(type default)
			)
			(layer "F.SilkS")
		)
		(fp_line
			(start 15.781274 -4.923028)
			(end 15.79372 -4.992624)
			(stroke
				(width 0.1)
				(type default)
			)
			(layer "F.SilkS")
		)
		(fp_line
			(start 15.781274 -4.923028)
			(end 15.79372 -4.992624)
			(stroke
				(width 0.1)
				(type default)
			)
			(layer "F.SilkS")
		)
		(fp_line
			(start 15.79372 -4.992624)
			(end 14.438376 -3.692398)
			(stroke
				(width 0.1)
				(type default)
			)
			(layer "F.SilkS")
		)
		(fp_line
			(start 15.79372 -4.992624)
			(end 14.438376 -3.692398)
			(stroke
				(width 0.1)
				(type default)
			)
			(layer "F.SilkS")
		)
		(fp_line
			(start 15.79372 -4.992624)
			(end 15.805658 -5.061966)
			(stroke
				(width 0.1)
				(type default)
			)
			(layer "F.SilkS")
		)
		(fp_line
			(start 15.79372 -4.992624)
			(end 15.805658 -5.061966)
			(stroke
				(width 0.1)
				(type default)
			)
			(layer "F.SilkS")
		)
		(fp_line
			(start 15.799816 -5.171694)
			(end 14.474952 -3.900424)
			(stroke
				(width 0.1)
				(type default)
			)
			(layer "F.SilkS")
		)
		(fp_line
			(start 15.799816 -5.171694)
			(end 14.474952 -3.900424)
			(stroke
				(width 0.1)
				(type default)
			)
			(layer "F.SilkS")
		)
		(fp_line
			(start 15.799816 -5.171694)
			(end 15.739618 -5.171694)
			(stroke
				(width 0.1)
				(type default)
			)
			(layer "F.SilkS")
		)
		(fp_line
			(start 15.799816 -5.171694)
			(end 15.739618 -5.171694)
			(stroke
				(width 0.1)
				(type default)
			)
			(layer "F.SilkS")
		)
		(fp_line
			(start 15.805658 -5.061966)
			(end 14.45006 -3.76174)
			(stroke
				(width 0.1)
				(type default)
			)
			(layer "F.SilkS")
		)
		(fp_line
			(start 15.805658 -5.061966)
			(end 14.45006 -3.76174)
			(stroke
				(width 0.1)
				(type default)
			)
			(layer "F.SilkS")
		)
		(fp_line
			(start 15.805658 -5.061966)
			(end 15.81785 -5.131308)
			(stroke
				(width 0.1)
				(type default)
			)
			(layer "F.SilkS")
		)
		(fp_line
			(start 15.805658 -5.061966)
			(end 15.81785 -5.131308)
			(stroke
				(width 0.1)
				(type default)
			)
			(layer "F.SilkS")
		)
		(fp_line
			(start 15.81785 -5.131308)
			(end 14.462506 -3.831082)
			(stroke
				(width 0.1)
				(type default)
			)
			(layer "F.SilkS")
		)
		(fp_line
			(start 15.81785 -5.131308)
			(end 14.462506 -3.831082)
			(stroke
				(width 0.1)
				(type default)
			)
			(layer "F.SilkS")
		)
		(fp_line
			(start 15.81785 -5.131308)
			(end 15.824962 -5.171694)
			(stroke
				(width 0.1)
				(type default)
			)
			(layer "F.SilkS")
		)
		(fp_line
			(start 15.81785 -5.131308)
			(end 15.824962 -5.171694)
			(stroke
				(width 0.1)
				(type default)
			)
			(layer "F.SilkS")
		)
		(fp_line
			(start 15.824962 -5.171694)
			(end 15.799816 -5.171694)
			(stroke
				(width 0.1)
				(type default)
			)
			(layer "F.SilkS")
		)
		(fp_line
			(start 15.824962 -5.171694)
			(end 15.799816 -5.171694)
			(stroke
				(width 0.1)
				(type default)
			)
			(layer "F.SilkS")
		)
		(fp_line
			(start 15.884652 -4.96443)
			(end 14.413484 -3.55346)
			(stroke
				(width 0.1)
				(type default)
			)
			(layer "F.SilkS")
		)
		(fp_line
			(start 15.884652 -4.96443)
			(end 14.413484 -3.55346)
			(stroke
				(width 0.1)
				(type default)
			)
			(layer "F.SilkS")
		)
		(fp_line
			(start 16.049498 -5.065268)
			(end 14.401546 -3.484118)
			(stroke
				(width 0.1)
				(type default)
			)
			(layer "F.SilkS")
		)
		(fp_line
			(start 16.049498 -5.065268)
			(end 14.401546 -3.484118)
			(stroke
				(width 0.1)
				(type default)
			)
			(layer "F.SilkS")
		)
		(fp_line
			(start 16.169132 -5.12191)
			(end 14.389354 -3.414776)
			(stroke
				(width 0.1)
				(type default)
			)
			(layer "F.SilkS")
		)
		(fp_line
			(start 16.169132 -5.12191)
			(end 14.389354 -3.414776)
			(stroke
				(width 0.1)
				(type default)
			)
			(layer "F.SilkS")
		)
		(fp_line
			(start 16.270986 -5.161788)
			(end 14.376908 -3.34518)
			(stroke
				(width 0.1)
				(type default)
			)
			(layer "F.SilkS")
		)
		(fp_line
			(start 16.270986 -5.161788)
			(end 14.376908 -3.34518)
			(stroke
				(width 0.1)
				(type default)
			)
			(layer "F.SilkS")
		)
		(fp_line
			(start 16.355568 -5.18541)
			(end 14.36497 -3.275838)
			(stroke
				(width 0.1)
				(type default)
			)
			(layer "F.SilkS")
		)
		(fp_line
			(start 16.355568 -5.18541)
			(end 14.36497 -3.275838)
			(stroke
				(width 0.1)
				(type default)
			)
			(layer "F.SilkS")
		)
		(fp_line
			(start 16.439896 -5.208778)
			(end 14.352778 -3.206496)
			(stroke
				(width 0.1)
				(type default)
			)
			(layer "F.SilkS")
		)
		(fp_line
			(start 16.439896 -5.208778)
			(end 14.352778 -3.206496)
			(stroke
				(width 0.1)
				(type default)
			)
			(layer "F.SilkS")
		)
		(fp_line
			(start 16.52397 -5.231638)
			(end 14.340586 -3.137154)
			(stroke
				(width 0.1)
				(type default)
			)
			(layer "F.SilkS")
		)
		(fp_line
			(start 16.52397 -5.231638)
			(end 14.340586 -3.137154)
			(stroke
				(width 0.1)
				(type default)
			)
			(layer "F.SilkS")
		)
		(fp_line
			(start 16.533622 -0.882904)
			(end 16.562832 -0.882904)
			(stroke
				(width 0.1)
				(type default)
			)
			(layer "F.SilkS")
		)
		(fp_line
			(start 16.533622 -0.882904)
			(end 16.562832 -0.882904)
			(stroke
				(width 0.1)
				(type default)
			)
			(layer "F.SilkS")
		)
		(fp_line
			(start 16.539718 -0.918464)
			(end 16.533622 -0.882904)
			(stroke
				(width 0.1)
				(type default)
			)
			(layer "F.SilkS")
		)
		(fp_line
			(start 16.539718 -0.918464)
			(end 16.533622 -0.882904)
			(stroke
				(width 0.1)
				(type default)
			)
			(layer "F.SilkS")
		)
		(fp_line
			(start 16.539718 -0.918464)
			(end 17.896586 -2.21996)
			(stroke
				(width 0.1)
				(type default)
			)
			(layer "F.SilkS")
		)
		(fp_line
			(start 16.539718 -0.918464)
			(end 17.896586 -2.21996)
			(stroke
				(width 0.1)
				(type default)
			)
			(layer "F.SilkS")
		)
		(fp_line
			(start 16.552164 -0.987806)
			(end 16.539718 -0.918464)
			(stroke
				(width 0.1)
				(type default)
			)
			(layer "F.SilkS")
		)
		(fp_line
			(start 16.552164 -0.987806)
			(end 16.539718 -0.918464)
			(stroke
				(width 0.1)
				(type default)
			)
			(layer "F.SilkS")
		)
		(fp_line
			(start 16.552164 -0.987806)
			(end 17.908524 -2.289048)
			(stroke
				(width 0.1)
				(type default)
			)
			(layer "F.SilkS")
		)
		(fp_line
			(start 16.552164 -0.987806)
			(end 17.908524 -2.289048)
			(stroke
				(width 0.1)
				(type default)
			)
			(layer "F.SilkS")
		)
		(fp_line
			(start 16.562832 -0.882904)
			(end 16.623284 -0.882904)
			(stroke
				(width 0.1)
				(type default)
			)
			(layer "F.SilkS")
		)
		(fp_line
			(start 16.562832 -0.882904)
			(end 16.623284 -0.882904)
			(stroke
				(width 0.1)
				(type default)
			)
			(layer "F.SilkS")
		)
		(fp_line
			(start 16.562832 -0.882904)
			(end 17.88414 -2.150364)
			(stroke
				(width 0.1)
				(type default)
			)
			(layer "F.SilkS")
		)
		(fp_line
			(start 16.562832 -0.882904)
			(end 17.88414 -2.150364)
			(stroke
				(width 0.1)
				(type default)
			)
			(layer "F.SilkS")
		)
		(fp_line
			(start 16.564356 -1.057148)
			(end 16.552164 -0.987806)
			(stroke
				(width 0.1)
				(type default)
			)
			(layer "F.SilkS")
		)
		(fp_line
			(start 16.564356 -1.057148)
			(end 16.552164 -0.987806)
			(stroke
				(width 0.1)
				(type default)
			)
			(layer "F.SilkS")
		)
		(fp_line
			(start 16.564356 -1.057148)
			(end 17.920716 -2.35839)
			(stroke
				(width 0.1)
				(type default)
			)
			(layer "F.SilkS")
		)
		(fp_line
			(start 16.564356 -1.057148)
			(end 17.920716 -2.35839)
			(stroke
				(width 0.1)
				(type default)
			)
			(layer "F.SilkS")
		)
		(fp_line
			(start 16.576294 -1.126744)
			(end 16.564356 -1.057148)
			(stroke
				(width 0.1)
				(type default)
			)
			(layer "F.SilkS")
		)
		(fp_line
			(start 16.576294 -1.126744)
			(end 16.564356 -1.057148)
			(stroke
				(width 0.1)
				(type default)
			)
			(layer "F.SilkS")
		)
		(fp_line
			(start 16.576294 -1.126744)
			(end 17.932908 -2.427732)
			(stroke
				(width 0.1)
				(type default)
			)
			(layer "F.SilkS")
		)
		(fp_line
			(start 16.576294 -1.126744)
			(end 17.932908 -2.427732)
			(stroke
				(width 0.1)
				(type default)
			)
			(layer "F.SilkS")
		)
		(fp_line
			(start 16.58874 -1.196086)
			(end 16.576294 -1.126744)
			(stroke
				(width 0.1)
				(type default)
			)
			(layer "F.SilkS")
		)
		(fp_line
			(start 16.58874 -1.196086)
			(end 16.576294 -1.126744)
			(stroke
				(width 0.1)
				(type default)
			)
			(layer "F.SilkS")
		)
		(fp_line
			(start 16.58874 -1.196086)
			(end 17.9451 -2.497328)
			(stroke
				(width 0.1)
				(type default)
			)
			(layer "F.SilkS")
		)
		(fp_line
			(start 16.58874 -1.196086)
			(end 17.9451 -2.497328)
			(stroke
				(width 0.1)
				(type default)
			)
			(layer "F.SilkS")
		)
		(fp_line
			(start 16.590772 -5.237734)
			(end 14.328394 -3.067558)
			(stroke
				(width 0.1)
				(type default)
			)
			(layer "F.SilkS")
		)
		(fp_line
			(start 16.590772 -5.237734)
			(end 14.328394 -3.067558)
			(stroke
				(width 0.1)
				(type default)
			)
			(layer "F.SilkS")
		)
		(fp_line
			(start 16.600932 -1.265428)
			(end 16.58874 -1.196086)
			(stroke
				(width 0.1)
				(type default)
			)
			(layer "F.SilkS")
		)
		(fp_line
			(start 16.600932 -1.265428)
			(end 16.58874 -1.196086)
			(stroke
				(width 0.1)
				(type default)
			)
			(layer "F.SilkS")
		)
		(fp_line
			(start 16.600932 -1.265428)
			(end 17.957038 -2.56667)
			(stroke
				(width 0.1)
				(type default)
			)
			(layer "F.SilkS")
		)
		(fp_line
			(start 16.600932 -1.265428)
			(end 17.957038 -2.56667)
			(stroke
				(width 0.1)
				(type default)
			)
			(layer "F.SilkS")
		)
		(fp_line
			(start 16.61287 -1.33477)
			(end 16.600932 -1.265428)
			(stroke
				(width 0.1)
				(type default)
			)
			(layer "F.SilkS")
		)
		(fp_line
			(start 16.61287 -1.33477)
			(end 16.600932 -1.265428)
			(stroke
				(width 0.1)
				(type default)
			)
			(layer "F.SilkS")
		)
		(fp_line
			(start 16.61287 -1.33477)
			(end 17.969484 -2.636012)
			(stroke
				(width 0.1)
				(type default)
			)
			(layer "F.SilkS")
		)
		(fp_line
			(start 16.61287 -1.33477)
			(end 17.969484 -2.636012)
			(stroke
				(width 0.1)
				(type default)
			)
			(layer "F.SilkS")
		)
		(fp_line
			(start 16.623284 -0.882904)
			(end 16.683228 -0.882904)
			(stroke
				(width 0.1)
				(type default)
			)
			(layer "F.SilkS")
		)
		(fp_line
			(start 16.623284 -0.882904)
			(end 16.683228 -0.882904)
			(stroke
				(width 0.1)
				(type default)
			)
			(layer "F.SilkS")
		)
		(fp_line
			(start 16.623284 -0.882904)
			(end 17.871948 -2.081022)
			(stroke
				(width 0.1)
				(type default)
			)
			(layer "F.SilkS")
		)
		(fp_line
			(start 16.623284 -0.882904)
			(end 17.871948 -2.081022)
			(stroke
				(width 0.1)
				(type default)
			)
			(layer "F.SilkS")
		)
		(fp_line
			(start 16.625316 -1.404366)
			(end 16.61287 -1.33477)
			(stroke
				(width 0.1)
				(type default)
			)
			(layer "F.SilkS")
		)
		(fp_line
			(start 16.625316 -1.404366)
			(end 16.61287 -1.33477)
			(stroke
				(width 0.1)
				(type default)
			)
			(layer "F.SilkS")
		)
		(fp_line
			(start 16.625316 -1.404366)
			(end 17.981676 -2.705608)
			(stroke
				(width 0.1)
				(type default)
			)
			(layer "F.SilkS")
		)
		(fp_line
			(start 16.625316 -1.404366)
			(end 17.981676 -2.705608)
			(stroke
				(width 0.1)
				(type default)
			)
			(layer "F.SilkS")
		)
		(fp_line
			(start 16.637762 -1.473962)
			(end 16.625316 -1.404366)
			(stroke
				(width 0.1)
				(type default)
			)
			(layer "F.SilkS")
		)
		(fp_line
			(start 16.637762 -1.473962)
			(end 16.625316 -1.404366)
			(stroke
				(width 0.1)
				(type default)
			)
			(layer "F.SilkS")
		)
		(fp_line
			(start 16.637762 -1.473962)
			(end 17.993614 -2.77495)
			(stroke
				(width 0.1)
				(type default)
			)
			(layer "F.SilkS")
		)
		(fp_line
			(start 16.637762 -1.473962)
			(end 17.993614 -2.77495)
			(stroke
				(width 0.1)
				(type default)
			)
			(layer "F.SilkS")
		)
		(fp_line
			(start 16.6497 -1.54305)
			(end 16.637762 -1.473962)
			(stroke
				(width 0.1)
				(type default)
			)
			(layer "F.SilkS")
		)
		(fp_line
			(start 16.6497 -1.54305)
			(end 16.637762 -1.473962)
			(stroke
				(width 0.1)
				(type default)
			)
			(layer "F.SilkS")
		)
		(fp_line
			(start 16.6497 -1.54305)
			(end 18.00606 -2.844292)
			(stroke
				(width 0.1)
				(type default)
			)
			(layer "F.SilkS")
		)
		(fp_line
			(start 16.6497 -1.54305)
			(end 18.00606 -2.844292)
			(stroke
				(width 0.1)
				(type default)
			)
			(layer "F.SilkS")
		)
		(fp_line
			(start 16.657066 -5.24383)
			(end 14.316456 -2.998216)
			(stroke
				(width 0.1)
				(type default)
			)
			(layer "F.SilkS")
		)
		(fp_line
			(start 16.657066 -5.24383)
			(end 14.316456 -2.998216)
			(stroke
				(width 0.1)
				(type default)
			)
			(layer "F.SilkS")
		)
		(fp_line
			(start 16.661892 -1.612646)
			(end 16.6497 -1.54305)
			(stroke
				(width 0.1)
				(type default)
			)
			(layer "F.SilkS")
		)
		(fp_line
			(start 16.661892 -1.612646)
			(end 16.6497 -1.54305)
			(stroke
				(width 0.1)
				(type default)
			)
			(layer "F.SilkS")
		)
		(fp_line
			(start 16.661892 -1.612646)
			(end 18.017998 -2.913634)
			(stroke
				(width 0.1)
				(type default)
			)
			(layer "F.SilkS")
		)
		(fp_line
			(start 16.661892 -1.612646)
			(end 18.017998 -2.913634)
			(stroke
				(width 0.1)
				(type default)
			)
			(layer "F.SilkS")
		)
		(fp_line
			(start 16.674084 -1.681988)
			(end 16.661892 -1.612646)
			(stroke
				(width 0.1)
				(type default)
			)
			(layer "F.SilkS")
		)
		(fp_line
			(start 16.674084 -1.681988)
			(end 16.661892 -1.612646)
			(stroke
				(width 0.1)
				(type default)
			)
			(layer "F.SilkS")
		)
		(fp_line
			(start 16.674084 -1.681988)
			(end 18.03019 -2.982976)
			(stroke
				(width 0.1)
				(type default)
			)
			(layer "F.SilkS")
		)
		(fp_line
			(start 16.674084 -1.681988)
			(end 18.03019 -2.982976)
			(stroke
				(width 0.1)
				(type default)
			)
			(layer "F.SilkS")
		)
		(fp_line
			(start 16.683228 -0.882904)
			(end 16.743426 -0.882904)
			(stroke
				(width 0.1)
				(type default)
			)
			(layer "F.SilkS")
		)
		(fp_line
			(start 16.683228 -0.882904)
			(end 16.743426 -0.882904)
			(stroke
				(width 0.1)
				(type default)
			)
			(layer "F.SilkS")
		)
		(fp_line
			(start 16.683228 -0.882904)
			(end 17.86001 -2.011426)
			(stroke
				(width 0.1)
				(type default)
			)
			(layer "F.SilkS")
		)
		(fp_line
			(start 16.683228 -0.882904)
			(end 17.86001 -2.011426)
			(stroke
				(width 0.1)
				(type default)
			)
			(layer "F.SilkS")
		)
		(fp_line
			(start 16.686276 -1.751584)
			(end 16.674084 -1.681988)
			(stroke
				(width 0.1)
				(type default)
			)
			(layer "F.SilkS")
		)
		(fp_line
			(start 16.686276 -1.751584)
			(end 16.674084 -1.681988)
			(stroke
				(width 0.1)
				(type default)
			)
			(layer "F.SilkS")
		)
		(fp_line
			(start 16.686276 -1.751584)
			(end 18.042636 -3.052572)
			(stroke
				(width 0.1)
				(type default)
			)
			(layer "F.SilkS")
		)
		(fp_line
			(start 16.686276 -1.751584)
			(end 18.042636 -3.052572)
			(stroke
				(width 0.1)
				(type default)
			)
			(layer "F.SilkS")
		)
		(fp_line
			(start 16.698214 -1.820926)
			(end 16.686276 -1.751584)
			(stroke
				(width 0.1)
				(type default)
			)
			(layer "F.SilkS")
		)
		(fp_line
			(start 16.698214 -1.820926)
			(end 16.686276 -1.751584)
			(stroke
				(width 0.1)
				(type default)
			)
			(layer "F.SilkS")
		)
		(fp_line
			(start 16.698214 -1.820926)
			(end 18.054574 -3.121914)
			(stroke
				(width 0.1)
				(type default)
			)
			(layer "F.SilkS")
		)
		(fp_line
			(start 16.698214 -1.820926)
			(end 18.054574 -3.121914)
			(stroke
				(width 0.1)
				(type default)
			)
			(layer "F.SilkS")
		)
		(fp_line
			(start 16.71066 -1.890268)
			(end 16.698214 -1.820926)
			(stroke
				(width 0.1)
				(type default)
			)
			(layer "F.SilkS")
		)
		(fp_line
			(start 16.71066 -1.890268)
			(end 16.698214 -1.820926)
			(stroke
				(width 0.1)
				(type default)
			)
			(layer "F.SilkS")
		)
		(fp_line
			(start 16.71066 -1.890268)
			(end 18.066766 -3.191002)
			(stroke
				(width 0.1)
				(type default)
			)
			(layer "F.SilkS")
		)
		(fp_line
			(start 16.71066 -1.890268)
			(end 18.066766 -3.191002)
			(stroke
				(width 0.1)
				(type default)
			)
			(layer "F.SilkS")
		)
		(fp_line
			(start 16.723106 -1.95961)
			(end 16.71066 -1.890268)
			(stroke
				(width 0.1)
				(type default)
			)
			(layer "F.SilkS")
		)
		(fp_line
			(start 16.723106 -1.95961)
			(end 16.71066 -1.890268)
			(stroke
				(width 0.1)
				(type default)
			)
			(layer "F.SilkS")
		)
		(fp_line
			(start 16.723106 -1.95961)
			(end 18.079212 -3.260598)
			(stroke
				(width 0.1)
				(type default)
			)
			(layer "F.SilkS")
		)
		(fp_line
			(start 16.723106 -1.95961)
			(end 18.079212 -3.260598)
			(stroke
				(width 0.1)
				(type default)
			)
			(layer "F.SilkS")
		)
		(fp_line
			(start 16.723868 -5.25018)
			(end 14.30401 -2.928874)
			(stroke
				(width 0.1)
				(type default)
			)
			(layer "F.SilkS")
		)
		(fp_line
			(start 16.723868 -5.25018)
			(end 14.30401 -2.928874)
			(stroke
				(width 0.1)
				(type default)
			)
			(layer "F.SilkS")
		)
		(fp_line
			(start 16.735044 -2.028952)
			(end 16.723106 -1.95961)
			(stroke
				(width 0.1)
				(type default)
			)
			(layer "F.SilkS")
		)
		(fp_line
			(start 16.735044 -2.028952)
			(end 16.723106 -1.95961)
			(stroke
				(width 0.1)
				(type default)
			)
			(layer "F.SilkS")
		)
		(fp_line
			(start 16.735044 -2.028952)
			(end 18.089372 -3.328416)
			(stroke
				(width 0.1)
				(type default)
			)
			(layer "F.SilkS")
		)
		(fp_line
			(start 16.735044 -2.028952)
			(end 18.089372 -3.328416)
			(stroke
				(width 0.1)
				(type default)
			)
			(layer "F.SilkS")
		)
		(fp_line
			(start 16.743426 -0.882904)
			(end 16.803624 -0.882904)
			(stroke
				(width 0.1)
				(type default)
			)
			(layer "F.SilkS")
		)
		(fp_line
			(start 16.743426 -0.882904)
			(end 16.803624 -0.882904)
			(stroke
				(width 0.1)
				(type default)
			)
			(layer "F.SilkS")
		)
		(fp_line
			(start 16.743426 -0.882904)
			(end 17.847564 -1.942338)
			(stroke
				(width 0.1)
				(type default)
			)
			(layer "F.SilkS")
		)
		(fp_line
			(start 16.743426 -0.882904)
			(end 17.847564 -1.942338)
			(stroke
				(width 0.1)
				(type default)
			)
			(layer "F.SilkS")
		)
		(fp_line
			(start 16.747236 -2.098548)
			(end 16.735044 -2.028952)
			(stroke
				(width 0.1)
				(type default)
			)
			(layer "F.SilkS")
		)
		(fp_line
			(start 16.747236 -2.098548)
			(end 16.735044 -2.028952)
			(stroke
				(width 0.1)
				(type default)
			)
			(layer "F.SilkS")
		)
		(fp_line
			(start 16.747236 -2.098548)
			(end 18.097246 -3.393694)
			(stroke
				(width 0.1)
				(type default)
			)
			(layer "F.SilkS")
		)
		(fp_line
			(start 16.747236 -2.098548)
			(end 18.097246 -3.393694)
			(stroke
				(width 0.1)
				(type default)
			)
			(layer "F.SilkS")
		)
		(fp_line
			(start 16.759682 -2.16789)
			(end 16.747236 -2.098548)
			(stroke
				(width 0.1)
				(type default)
			)
			(layer "F.SilkS")
		)
		(fp_line
			(start 16.759682 -2.16789)
			(end 16.747236 -2.098548)
			(stroke
				(width 0.1)
				(type default)
			)
			(layer "F.SilkS")
		)
		(fp_line
			(start 16.759682 -2.16789)
			(end 18.105374 -3.458718)
			(stroke
				(width 0.1)
				(type default)
			)
			(layer "F.SilkS")
		)
		(fp_line
			(start 16.759682 -2.16789)
			(end 18.105374 -3.458718)
			(stroke
				(width 0.1)
				(type default)
			)
			(layer "F.SilkS")
		)
		(fp_line
			(start 16.77162 -2.237232)
			(end 16.759682 -2.16789)
			(stroke
				(width 0.1)
				(type default)
			)
			(layer "F.SilkS")
		)
		(fp_line
			(start 16.77162 -2.237232)
			(end 16.759682 -2.16789)
			(stroke
				(width 0.1)
				(type default)
			)
			(layer "F.SilkS")
		)
		(fp_line
			(start 16.77162 -2.237232)
			(end 18.113248 -3.52425)
			(stroke
				(width 0.1)
				(type default)
			)
			(layer "F.SilkS")
		)
		(fp_line
			(start 16.77162 -2.237232)
			(end 18.113248 -3.52425)
			(stroke
				(width 0.1)
				(type default)
			)
			(layer "F.SilkS")
		)
		(fp_line
			(start 16.783812 -2.306828)
			(end 16.77162 -2.237232)
			(stroke
				(width 0.1)
				(type default)
			)
			(layer "F.SilkS")
		)
		(fp_line
			(start 16.783812 -2.306828)
			(end 16.77162 -2.237232)
			(stroke
				(width 0.1)
				(type default)
			)
			(layer "F.SilkS")
		)
		(fp_line
			(start 16.783812 -2.306828)
			(end 18.121122 -3.589782)
			(stroke
				(width 0.1)
				(type default)
			)
			(layer "F.SilkS")
		)
		(fp_line
			(start 16.783812 -2.306828)
			(end 18.121122 -3.589782)
			(stroke
				(width 0.1)
				(type default)
			)
			(layer "F.SilkS")
		)
		(fp_line
			(start 16.790162 -5.256022)
			(end 14.291818 -2.859532)
			(stroke
				(width 0.1)
				(type default)
			)
			(layer "F.SilkS")
		)
		(fp_line
			(start 16.790162 -5.256022)
			(end 14.291818 -2.859532)
			(stroke
				(width 0.1)
				(type default)
			)
			(layer "F.SilkS")
		)
		(fp_line
			(start 16.796258 -2.37617)
			(end 16.783812 -2.306828)
			(stroke
				(width 0.1)
				(type default)
			)
			(layer "F.SilkS")
		)
		(fp_line
			(start 16.796258 -2.37617)
			(end 16.783812 -2.306828)
			(stroke
				(width 0.1)
				(type default)
			)
			(layer "F.SilkS")
		)
		(fp_line
			(start 16.796258 -2.37617)
			(end 18.129504 -3.65506)
			(stroke
				(width 0.1)
				(type default)
			)
			(layer "F.SilkS")
		)
		(fp_line
			(start 16.796258 -2.37617)
			(end 18.129504 -3.65506)
			(stroke
				(width 0.1)
				(type default)
			)
			(layer "F.SilkS")
		)
		(fp_line
			(start 16.803624 -0.882904)
			(end 16.863568 -0.882904)
			(stroke
				(width 0.1)
				(type default)
			)
			(layer "F.SilkS")
		)
		(fp_line
			(start 16.803624 -0.882904)
			(end 16.863568 -0.882904)
			(stroke
				(width 0.1)
				(type default)
			)
			(layer "F.SilkS")
		)
		(fp_line
			(start 16.803624 -0.882904)
			(end 17.835626 -1.872742)
			(stroke
				(width 0.1)
				(type default)
			)
			(layer "F.SilkS")
		)
		(fp_line
			(start 16.803624 -0.882904)
			(end 17.835626 -1.872742)
			(stroke
				(width 0.1)
				(type default)
			)
			(layer "F.SilkS")
		)
		(fp_line
			(start 16.808196 -2.445512)
			(end 16.796258 -2.37617)
			(stroke
				(width 0.1)
				(type default)
			)
			(layer "F.SilkS")
		)
		(fp_line
			(start 16.808196 -2.445512)
			(end 16.796258 -2.37617)
			(stroke
				(width 0.1)
				(type default)
			)
			(layer "F.SilkS")
		)
		(fp_line
			(start 16.808196 -2.445512)
			(end 18.13687 -3.720338)
			(stroke
				(width 0.1)
				(type default)
			)
			(layer "F.SilkS")
		)
		(fp_line
			(start 16.808196 -2.445512)
			(end 18.13687 -3.720338)
			(stroke
				(width 0.1)
				(type default)
			)
			(layer "F.SilkS")
		)
		(fp_line
			(start 16.820134 -2.515108)
			(end 16.808196 -2.445512)
			(stroke
				(width 0.1)
				(type default)
			)
			(layer "F.SilkS")
		)
		(fp_line
			(start 16.820134 -2.515108)
			(end 16.808196 -2.445512)
			(stroke
				(width 0.1)
				(type default)
			)
			(layer "F.SilkS")
		)
		(fp_line
			(start 16.820134 -2.515108)
			(end 16.83258 -2.58445)
			(stroke
				(width 0.1)
				(type default)
			)
			(layer "F.SilkS")
		)
		(fp_line
			(start 16.820134 -2.515108)
			(end 16.83258 -2.58445)
			(stroke
				(width 0.1)
				(type default)
			)
			(layer "F.SilkS")
		)
		(fp_line
			(start 16.820134 -2.515108)
			(end 18.138394 -3.779266)
			(stroke
				(width 0.1)
				(type default)
			)
			(layer "F.SilkS")
		)
		(fp_line
			(start 16.820134 -2.515108)
			(end 18.138394 -3.779266)
			(stroke
				(width 0.1)
				(type default)
			)
			(layer "F.SilkS")
		)
		(fp_line
			(start 16.845026 -2.653792)
			(end 16.83258 -2.58445)
			(stroke
				(width 0.1)
				(type default)
			)
			(layer "F.SilkS")
		)
		(fp_line
			(start 16.845026 -2.653792)
			(end 16.83258 -2.58445)
			(stroke
				(width 0.1)
				(type default)
			)
			(layer "F.SilkS")
		)
		(fp_line
			(start 16.845026 -2.653792)
			(end 18.137378 -3.89382)
			(stroke
				(width 0.1)
				(type default)
			)
			(layer "F.SilkS")
		)
		(fp_line
			(start 16.845026 -2.653792)
			(end 18.137378 -3.89382)
			(stroke
				(width 0.1)
				(type default)
			)
			(layer "F.SilkS")
		)
		(fp_line
			(start 16.854678 -5.26034)
			(end 14.27988 -2.79019)
			(stroke
				(width 0.1)
				(type default)
			)
			(layer "F.SilkS")
		)
		(fp_line
			(start 16.854678 -5.26034)
			(end 14.27988 -2.79019)
			(stroke
				(width 0.1)
				(type default)
			)
			(layer "F.SilkS")
		)
		(fp_line
			(start 16.857218 -2.723134)
			(end 16.845026 -2.653792)
			(stroke
				(width 0.1)
				(type default)
			)
			(layer "F.SilkS")
		)
		(fp_line
			(start 16.857218 -2.723134)
			(end 16.845026 -2.653792)
			(stroke
				(width 0.1)
				(type default)
			)
			(layer "F.SilkS")
		)
		(fp_line
			(start 16.857218 -2.723134)
			(end 18.13687 -3.95097)
			(stroke
				(width 0.1)
				(type default)
			)
			(layer "F.SilkS")
		)
		(fp_line
			(start 16.857218 -2.723134)
			(end 18.13687 -3.95097)
			(stroke
				(width 0.1)
				(type default)
			)
			(layer "F.SilkS")
		)
		(fp_line
			(start 16.863568 -0.882904)
			(end 16.92402 -0.882904)
			(stroke
				(width 0.1)
				(type default)
			)
			(layer "F.SilkS")
		)
		(fp_line
			(start 16.863568 -0.882904)
			(end 16.92402 -0.882904)
			(stroke
				(width 0.1)
				(type default)
			)
			(layer "F.SilkS")
		)
		(fp_line
			(start 16.863568 -0.882904)
			(end 17.823434 -1.8034)
			(stroke
				(width 0.1)
				(type default)
			)
			(layer "F.SilkS")
		)
		(fp_line
			(start 16.863568 -0.882904)
			(end 17.823434 -1.8034)
			(stroke
				(width 0.1)
				(type default)
			)
			(layer "F.SilkS")
		)
		(fp_line
			(start 16.869156 -2.79273)
			(end 16.857218 -2.723134)
			(stroke
				(width 0.1)
				(type default)
			)
			(layer "F.SilkS")
		)
		(fp_line
			(start 16.869156 -2.79273)
			(end 16.857218 -2.723134)
			(stroke
				(width 0.1)
				(type default)
			)
			(layer "F.SilkS")
		)
		(fp_line
			(start 16.869156 -2.79273)
			(end 18.136362 -4.008374)
			(stroke
				(width 0.1)
				(type default)
			)
			(layer "F.SilkS")
		)
		(fp_line
			(start 16.869156 -2.79273)
			(end 18.136362 -4.008374)
			(stroke
				(width 0.1)
				(type default)
			)
			(layer "F.SilkS")
		)
		(fp_line
			(start 16.881602 -2.862072)
			(end 16.869156 -2.79273)
			(stroke
				(width 0.1)
				(type default)
			)
			(layer "F.SilkS")
		)
		(fp_line
			(start 16.881602 -2.862072)
			(end 16.869156 -2.79273)
			(stroke
				(width 0.1)
				(type default)
			)
			(layer "F.SilkS")
		)
		(fp_line
			(start 16.881602 -2.862072)
			(end 18.136362 -4.065524)
			(stroke
				(width 0.1)
				(type default)
			)
			(layer "F.SilkS")
		)
		(fp_line
			(start 16.881602 -2.862072)
			(end 18.136362 -4.065524)
			(stroke
				(width 0.1)
				(type default)
			)
			(layer "F.SilkS")
		)
		(fp_line
			(start 16.89354 -2.931414)
			(end 16.881602 -2.862072)
			(stroke
				(width 0.1)
				(type default)
			)
			(layer "F.SilkS")
		)
		(fp_line
			(start 16.89354 -2.931414)
			(end 16.881602 -2.862072)
			(stroke
				(width 0.1)
				(type default)
			)
			(layer "F.SilkS")
		)
		(fp_line
			(start 16.89354 -2.931414)
			(end 18.134838 -4.121912)
			(stroke
				(width 0.1)
				(type default)
			)
			(layer "F.SilkS")
		)
		(fp_line
			(start 16.89354 -2.931414)
			(end 18.134838 -4.121912)
			(stroke
				(width 0.1)
				(type default)
			)
			(layer "F.SilkS")
		)
		(fp_line
			(start 16.905732 -3.000756)
			(end 16.89354 -2.931414)
			(stroke
				(width 0.1)
				(type default)
			)
			(layer "F.SilkS")
		)
		(fp_line
			(start 16.905732 -3.000756)
			(end 16.89354 -2.931414)
			(stroke
				(width 0.1)
				(type default)
			)
			(layer "F.SilkS")
		)
		(fp_line
			(start 16.905732 -3.000756)
			(end 18.125948 -4.171188)
			(stroke
				(width 0.1)
				(type default)
			)
			(layer "F.SilkS")
		)
		(fp_line
			(start 16.905732 -3.000756)
			(end 18.125948 -4.171188)
			(stroke
				(width 0.1)
				(type default)
			)
			(layer "F.SilkS")
		)
		(fp_line
			(start 16.909796 -5.255514)
			(end 14.267434 -2.720594)
			(stroke
				(width 0.1)
				(type default)
			)
			(layer "F.SilkS")
		)
		(fp_line
			(start 16.909796 -5.255514)
			(end 14.267434 -2.720594)
			(stroke
				(width 0.1)
				(type default)
			)
			(layer "F.SilkS")
		)
		(fp_line
			(start 16.918178 -3.070352)
			(end 16.905732 -3.000756)
			(stroke
				(width 0.1)
				(type default)
			)
			(layer "F.SilkS")
		)
		(fp_line
			(start 16.918178 -3.070352)
			(end 16.905732 -3.000756)
			(stroke
				(width 0.1)
				(type default)
			)
			(layer "F.SilkS")
		)
		(fp_line
			(start 16.918178 -3.070352)
			(end 18.117058 -4.220464)
			(stroke
				(width 0.1)
				(type default)
			)
			(layer "F.SilkS")
		)
		(fp_line
			(start 16.918178 -3.070352)
			(end 18.117058 -4.220464)
			(stroke
				(width 0.1)
				(type default)
			)
			(layer "F.SilkS")
		)
		(fp_line
			(start 16.92402 -0.882904)
			(end 16.984218 -0.882904)
			(stroke
				(width 0.1)
				(type default)
			)
			(layer "F.SilkS")
		)
		(fp_line
			(start 16.92402 -0.882904)
			(end 16.984218 -0.882904)
			(stroke
				(width 0.1)
				(type default)
			)
			(layer "F.SilkS")
		)
		(fp_line
			(start 16.92402 -0.882904)
			(end 17.810988 -1.734058)
			(stroke
				(width 0.1)
				(type default)
			)
			(layer "F.SilkS")
		)
		(fp_line
			(start 16.92402 -0.882904)
			(end 17.810988 -1.734058)
			(stroke
				(width 0.1)
				(type default)
			)
			(layer "F.SilkS")
		)
		(fp_line
			(start 16.930624 -3.139694)
			(end 16.918178 -3.070352)
			(stroke
				(width 0.1)
				(type default)
			)
			(layer "F.SilkS")
		)
		(fp_line
			(start 16.930624 -3.139694)
			(end 16.918178 -3.070352)
			(stroke
				(width 0.1)
				(type default)
			)
			(layer "F.SilkS")
		)
		(fp_line
			(start 16.96466 -5.25018)
			(end 14.255496 -2.651506)
			(stroke
				(width 0.1)
				(type default)
			)
			(layer "F.SilkS")
		)
		(fp_line
			(start 16.96466 -5.25018)
			(end 14.255496 -2.651506)
			(stroke
				(width 0.1)
				(type default)
			)
			(layer "F.SilkS")
		)
		(fp_line
			(start 16.984218 -0.882904)
			(end 17.044162 -0.882904)
			(stroke
				(width 0.1)
				(type default)
			)
			(layer "F.SilkS")
		)
		(fp_line
			(start 16.984218 -0.882904)
			(end 17.044162 -0.882904)
			(stroke
				(width 0.1)
				(type default)
			)
			(layer "F.SilkS")
		)
		(fp_line
			(start 16.984218 -0.882904)
			(end 17.79905 -1.664716)
			(stroke
				(width 0.1)
				(type default)
			)
			(layer "F.SilkS")
		)
		(fp_line
			(start 16.984218 -0.882904)
			(end 17.79905 -1.664716)
			(stroke
				(width 0.1)
				(type default)
			)
			(layer "F.SilkS")
		)
		(fp_line
			(start 17.01927 -5.245354)
			(end 14.243304 -2.58191)
			(stroke
				(width 0.1)
				(type default)
			)
			(layer "F.SilkS")
		)
		(fp_line
			(start 17.01927 -5.245354)
			(end 14.243304 -2.58191)
			(stroke
				(width 0.1)
				(type default)
			)
			(layer "F.SilkS")
		)
		(fp_line
			(start 17.044162 -0.882904)
			(end 17.10436 -0.882904)
			(stroke
				(width 0.1)
				(type default)
			)
			(layer "F.SilkS")
		)
		(fp_line
			(start 17.044162 -0.882904)
			(end 17.10436 -0.882904)
			(stroke
				(width 0.1)
				(type default)
			)
			(layer "F.SilkS")
		)
		(fp_line
			(start 17.044162 -0.882904)
			(end 17.786858 -1.595374)
			(stroke
				(width 0.1)
				(type default)
			)
			(layer "F.SilkS")
		)
		(fp_line
			(start 17.044162 -0.882904)
			(end 17.786858 -1.595374)
			(stroke
				(width 0.1)
				(type default)
			)
			(layer "F.SilkS")
		)
		(fp_line
			(start 17.074388 -5.240274)
			(end 14.230858 -2.512314)
			(stroke
				(width 0.1)
				(type default)
			)
			(layer "F.SilkS")
		)
		(fp_line
			(start 17.074388 -5.240274)
			(end 14.230858 -2.512314)
			(stroke
				(width 0.1)
				(type default)
			)
			(layer "F.SilkS")
		)
		(fp_line
			(start 17.10436 -0.882904)
			(end 17.164812 -0.882904)
			(stroke
				(width 0.1)
				(type default)
			)
			(layer "F.SilkS")
		)
		(fp_line
			(start 17.10436 -0.882904)
			(end 17.164812 -0.882904)
			(stroke
				(width 0.1)
				(type default)
			)
			(layer "F.SilkS")
		)
		(fp_line
			(start 17.10436 -0.882904)
			(end 17.774666 -1.525778)
			(stroke
				(width 0.1)
				(type default)
			)
			(layer "F.SilkS")
		)
		(fp_line
			(start 17.10436 -0.882904)
			(end 17.774666 -1.525778)
			(stroke
				(width 0.1)
				(type default)
			)
			(layer "F.SilkS")
		)
		(fp_line
			(start 17.129252 -5.235194)
			(end 15.934944 -4.0894)
			(stroke
				(width 0.1)
				(type default)
			)
			(layer "F.SilkS")
		)
		(fp_line
			(start 17.129252 -5.235194)
			(end 15.934944 -4.0894)
			(stroke
				(width 0.1)
				(type default)
			)
			(layer "F.SilkS")
		)
		(fp_line
			(start 17.164812 -0.882904)
			(end 17.224756 -0.882904)
			(stroke
				(width 0.1)
				(type default)
			)
			(layer "F.SilkS")
		)
		(fp_line
			(start 17.164812 -0.882904)
			(end 17.224756 -0.882904)
			(stroke
				(width 0.1)
				(type default)
			)
			(layer "F.SilkS")
		)
		(fp_line
			(start 17.164812 -0.882904)
			(end 17.762474 -1.456436)
			(stroke
				(width 0.1)
				(type default)
			)
			(layer "F.SilkS")
		)
		(fp_line
			(start 17.164812 -0.882904)
			(end 17.762474 -1.456436)
			(stroke
				(width 0.1)
				(type default)
			)
			(layer "F.SilkS")
		)
		(fp_line
			(start 17.184116 -5.230114)
			(end 16.052292 -4.144264)
			(stroke
				(width 0.1)
				(type default)
			)
			(layer "F.SilkS")
		)
		(fp_line
			(start 17.184116 -5.230114)
			(end 16.052292 -4.144264)
			(stroke
				(width 0.1)
				(type default)
			)
			(layer "F.SilkS")
		)
		(fp_line
			(start 17.224756 -0.882904)
			(end 17.284954 -0.882904)
			(stroke
				(width 0.1)
				(type default)
			)
			(layer "F.SilkS")
		)
		(fp_line
			(start 17.224756 -0.882904)
			(end 17.284954 -0.882904)
			(stroke
				(width 0.1)
				(type default)
			)
			(layer "F.SilkS")
		)
		(fp_line
			(start 17.224756 -0.882904)
			(end 17.750536 -1.387348)
			(stroke
				(width 0.1)
				(type default)
			)
			(layer "F.SilkS")
		)
		(fp_line
			(start 17.224756 -0.882904)
			(end 17.750536 -1.387348)
			(stroke
				(width 0.1)
				(type default)
			)
			(layer "F.SilkS")
		)
		(fp_line
			(start 17.235678 -5.221986)
			(end 16.13789 -4.168648)
			(stroke
				(width 0.1)
				(type default)
			)
			(layer "F.SilkS")
		)
		(fp_line
			(start 17.235678 -5.221986)
			(end 16.13789 -4.168648)
			(stroke
				(width 0.1)
				(type default)
			)
			(layer "F.SilkS")
		)
		(fp_line
			(start 17.280636 -5.207254)
			(end 16.218154 -4.187698)
			(stroke
				(width 0.1)
				(type default)
			)
			(layer "F.SilkS")
		)
		(fp_line
			(start 17.280636 -5.207254)
			(end 16.218154 -4.187698)
			(stroke
				(width 0.1)
				(type default)
			)
			(layer "F.SilkS")
		)
		(fp_line
			(start 17.284954 -0.882904)
			(end 17.345406 -0.882904)
			(stroke
				(width 0.1)
				(type default)
			)
			(layer "F.SilkS")
		)
		(fp_line
			(start 17.284954 -0.882904)
			(end 17.345406 -0.882904)
			(stroke
				(width 0.1)
				(type default)
			)
			(layer "F.SilkS")
		)
		(fp_line
			(start 17.284954 -0.882904)
			(end 17.73809 -1.317752)
			(stroke
				(width 0.1)
				(type default)
			)
			(layer "F.SilkS")
		)
		(fp_line
			(start 17.284954 -0.882904)
			(end 17.73809 -1.317752)
			(stroke
				(width 0.1)
				(type default)
			)
			(layer "F.SilkS")
		)
		(fp_line
			(start 17.32534 -5.192522)
			(end 16.283178 -4.192524)
			(stroke
				(width 0.1)
				(type default)
			)
			(layer "F.SilkS")
		)
		(fp_line
			(start 17.32534 -5.192522)
			(end 16.283178 -4.192524)
			(stroke
				(width 0.1)
				(type default)
			)
			(layer "F.SilkS")
		)
		(fp_line
			(start 17.345406 -0.882904)
			(end 17.40535 -0.882904)
			(stroke
				(width 0.1)
				(type default)
			)
			(layer "F.SilkS")
		)
		(fp_line
			(start 17.345406 -0.882904)
			(end 17.40535 -0.882904)
			(stroke
				(width 0.1)
				(type default)
			)
			(layer "F.SilkS")
		)
		(fp_line
			(start 17.345406 -0.882904)
			(end 17.725898 -1.248156)
			(stroke
				(width 0.1)
				(type default)
			)
			(layer "F.SilkS")
		)
		(fp_line
			(start 17.345406 -0.882904)
			(end 17.725898 -1.248156)
			(stroke
				(width 0.1)
				(type default)
			)
			(layer "F.SilkS")
		)
		(fp_line
			(start 17.370044 -5.17779)
			(end 16.347948 -4.197096)
			(stroke
				(width 0.1)
				(type default)
			)
			(layer "F.SilkS")
		)
		(fp_line
			(start 17.370044 -5.17779)
			(end 16.347948 -4.197096)
			(stroke
				(width 0.1)
				(type default)
			)
			(layer "F.SilkS")
		)
		(fp_line
			(start 17.40535 -0.882904)
			(end 17.465294 -0.882904)
			(stroke
				(width 0.1)
				(type default)
			)
			(layer "F.SilkS")
		)
		(fp_line
			(start 17.40535 -0.882904)
			(end 17.465294 -0.882904)
			(stroke
				(width 0.1)
				(type default)
			)
			(layer "F.SilkS")
		)
		(fp_line
			(start 17.40535 -0.882904)
			(end 17.71396 -1.178814)
			(stroke
				(width 0.1)
				(type default)
			)
			(layer "F.SilkS")
		)
		(fp_line
			(start 17.40535 -0.882904)
			(end 17.71396 -1.178814)
			(stroke
				(width 0.1)
				(type default)
			)
			(layer "F.SilkS")
		)
		(fp_line
			(start 17.415002 -5.163058)
			(end 16.40967 -4.198366)
			(stroke
				(width 0.1)
				(type default)
			)
			(layer "F.SilkS")
		)
		(fp_line
			(start 17.415002 -5.163058)
			(end 16.40967 -4.198366)
			(stroke
				(width 0.1)
				(type default)
			)
			(layer "F.SilkS")
		)
		(fp_line
			(start 17.45996 -5.148326)
			(end 16.465804 -4.194556)
			(stroke
				(width 0.1)
				(type default)
			)
			(layer "F.SilkS")
		)
		(fp_line
			(start 17.45996 -5.148326)
			(end 16.465804 -4.194556)
			(stroke
				(width 0.1)
				(type default)
			)
			(layer "F.SilkS")
		)
		(fp_line
			(start 17.465294 -0.882904)
			(end 17.525746 -0.882904)
			(stroke
				(width 0.1)
				(type default)
			)
			(layer "F.SilkS")
		)
		(fp_line
			(start 17.465294 -0.882904)
			(end 17.525746 -0.882904)
			(stroke
				(width 0.1)
				(type default)
			)
			(layer "F.SilkS")
		)
		(fp_line
			(start 17.465294 -0.882904)
			(end 17.701514 -1.109472)
			(stroke
				(width 0.1)
				(type default)
			)
			(layer "F.SilkS")
		)
		(fp_line
			(start 17.465294 -0.882904)
			(end 17.701514 -1.109472)
			(stroke
				(width 0.1)
				(type default)
			)
			(layer "F.SilkS")
		)
		(fp_line
			(start 17.50441 -5.13334)
			(end 16.521938 -4.190746)
			(stroke
				(width 0.1)
				(type default)
			)
			(layer "F.SilkS")
		)
		(fp_line
			(start 17.50441 -5.13334)
			(end 16.521938 -4.190746)
			(stroke
				(width 0.1)
				(type default)
			)
			(layer "F.SilkS")
		)
		(fp_line
			(start 17.525746 -0.882904)
			(end 17.58569 -0.882904)
			(stroke
				(width 0.1)
				(type default)
			)
			(layer "F.SilkS")
		)
		(fp_line
			(start 17.525746 -0.882904)
			(end 17.58569 -0.882904)
			(stroke
				(width 0.1)
				(type default)
			)
			(layer "F.SilkS")
		)
		(fp_line
			(start 17.525746 -0.882904)
			(end 17.689576 -1.04013)
			(stroke
				(width 0.1)
				(type default)
			)
			(layer "F.SilkS")
		)
		(fp_line
			(start 17.525746 -0.882904)
			(end 17.689576 -1.04013)
			(stroke
				(width 0.1)
				(type default)
			)
			(layer "F.SilkS")
		)
		(fp_line
			(start 17.545558 -5.115052)
			(end 16.5735 -4.182872)
			(stroke
				(width 0.1)
				(type default)
			)
			(layer "F.SilkS")
		)
		(fp_line
			(start 17.545558 -5.115052)
			(end 16.5735 -4.182872)
			(stroke
				(width 0.1)
				(type default)
			)
			(layer "F.SilkS")
		)
		(fp_line
			(start 17.580864 -5.091176)
			(end 16.621252 -4.170426)
			(stroke
				(width 0.1)
				(type default)
			)
			(layer "F.SilkS")
		)
		(fp_line
			(start 17.580864 -5.091176)
			(end 16.621252 -4.170426)
			(stroke
				(width 0.1)
				(type default)
			)
			(layer "F.SilkS")
		)
		(fp_line
			(start 17.58569 -0.882904)
			(end 17.645634 -0.882904)
			(stroke
				(width 0.1)
				(type default)
			)
			(layer "F.SilkS")
		)
		(fp_line
			(start 17.58569 -0.882904)
			(end 17.645634 -0.882904)
			(stroke
				(width 0.1)
				(type default)
			)
			(layer "F.SilkS")
		)
		(fp_line
			(start 17.58569 -0.882904)
			(end 17.677384 -0.970788)
			(stroke
				(width 0.1)
				(type default)
			)
			(layer "F.SilkS")
		)
		(fp_line
			(start 17.58569 -0.882904)
			(end 17.677384 -0.970788)
			(stroke
				(width 0.1)
				(type default)
			)
			(layer "F.SilkS")
		)
		(fp_line
			(start 17.61617 -5.067046)
			(end 16.668242 -4.15798)
			(stroke
				(width 0.1)
				(type default)
			)
			(layer "F.SilkS")
		)
		(fp_line
			(start 17.61617 -5.067046)
			(end 16.668242 -4.15798)
			(stroke
				(width 0.1)
				(type default)
			)
			(layer "F.SilkS")
		)
		(fp_line
			(start 17.645634 -0.882904)
			(end 17.66189 -0.882904)
			(stroke
				(width 0.1)
				(type default)
			)
			(layer "F.SilkS")
		)
		(fp_line
			(start 17.645634 -0.882904)
			(end 17.66189 -0.882904)
			(stroke
				(width 0.1)
				(type default)
			)
			(layer "F.SilkS")
		)
		(fp_line
			(start 17.645634 -0.882904)
			(end 17.664938 -0.901192)
			(stroke
				(width 0.1)
				(type default)
			)
			(layer "F.SilkS")
		)
		(fp_line
			(start 17.645634 -0.882904)
			(end 17.664938 -0.901192)
			(stroke
				(width 0.1)
				(type default)
			)
			(layer "F.SilkS")
		)
		(fp_line
			(start 17.651222 -5.043424)
			(end 16.71066 -4.140962)
			(stroke
				(width 0.1)
				(type default)
			)
			(layer "F.SilkS")
		)
		(fp_line
			(start 17.651222 -5.043424)
			(end 16.71066 -4.140962)
			(stroke
				(width 0.1)
				(type default)
			)
			(layer "F.SilkS")
		)
		(fp_line
			(start 17.66189 -0.882904)
			(end 17.664938 -0.901192)
			(stroke
				(width 0.1)
				(type default)
			)
			(layer "F.SilkS")
		)
		(fp_line
			(start 17.66189 -0.882904)
			(end 17.664938 -0.901192)
			(stroke
				(width 0.1)
				(type default)
			)
			(layer "F.SilkS")
		)
		(fp_line
			(start 17.677384 -0.970788)
			(end 17.664938 -0.901192)
			(stroke
				(width 0.1)
				(type default)
			)
			(layer "F.SilkS")
		)
		(fp_line
			(start 17.677384 -0.970788)
			(end 17.664938 -0.901192)
			(stroke
				(width 0.1)
				(type default)
			)
			(layer "F.SilkS")
		)
		(fp_line
			(start 17.686274 -5.019294)
			(end 16.747998 -4.119118)
			(stroke
				(width 0.1)
				(type default)
			)
			(layer "F.SilkS")
		)
		(fp_line
			(start 17.686274 -5.019294)
			(end 16.747998 -4.119118)
			(stroke
				(width 0.1)
				(type default)
			)
			(layer "F.SilkS")
		)
		(fp_line
			(start 17.689576 -1.04013)
			(end 17.677384 -0.970788)
			(stroke
				(width 0.1)
				(type default)
			)
			(layer "F.SilkS")
		)
		(fp_line
			(start 17.689576 -1.04013)
			(end 17.677384 -0.970788)
			(stroke
				(width 0.1)
				(type default)
			)
			(layer "F.SilkS")
		)
		(fp_line
			(start 17.701514 -1.109472)
			(end 17.689576 -1.04013)
			(stroke
				(width 0.1)
				(type default)
			)
			(layer "F.SilkS")
		)
		(fp_line
			(start 17.701514 -1.109472)
			(end 17.689576 -1.04013)
			(stroke
				(width 0.1)
				(type default)
			)
			(layer "F.SilkS")
		)
		(fp_line
			(start 17.71396 -1.178814)
			(end 17.701514 -1.109472)
			(stroke
				(width 0.1)
				(type default)
			)
			(layer "F.SilkS")
		)
		(fp_line
			(start 17.71396 -1.178814)
			(end 17.701514 -1.109472)
			(stroke
				(width 0.1)
				(type default)
			)
			(layer "F.SilkS")
		)
		(fp_line
			(start 17.721834 -4.995672)
			(end 16.785844 -4.097782)
			(stroke
				(width 0.1)
				(type default)
			)
			(layer "F.SilkS")
		)
		(fp_line
			(start 17.721834 -4.995672)
			(end 16.785844 -4.097782)
			(stroke
				(width 0.1)
				(type default)
			)
			(layer "F.SilkS")
		)
		(fp_line
			(start 17.725898 -1.248156)
			(end 17.71396 -1.178814)
			(stroke
				(width 0.1)
				(type default)
			)
			(layer "F.SilkS")
		)
		(fp_line
			(start 17.725898 -1.248156)
			(end 17.71396 -1.178814)
			(stroke
				(width 0.1)
				(type default)
			)
			(layer "F.SilkS")
		)
		(fp_line
			(start 17.73809 -1.317752)
			(end 17.725898 -1.248156)
			(stroke
				(width 0.1)
				(type default)
			)
			(layer "F.SilkS")
		)
		(fp_line
			(start 17.73809 -1.317752)
			(end 17.725898 -1.248156)
			(stroke
				(width 0.1)
				(type default)
			)
			(layer "F.SilkS")
		)
		(fp_line
			(start 17.750536 -1.387348)
			(end 17.73809 -1.317752)
			(stroke
				(width 0.1)
				(type default)
			)
			(layer "F.SilkS")
		)
		(fp_line
			(start 17.750536 -1.387348)
			(end 17.73809 -1.317752)
			(stroke
				(width 0.1)
				(type default)
			)
			(layer "F.SilkS")
		)
		(fp_line
			(start 17.757394 -4.971796)
			(end 16.818102 -4.071112)
			(stroke
				(width 0.1)
				(type default)
			)
			(layer "F.SilkS")
		)
		(fp_line
			(start 17.757394 -4.971796)
			(end 16.818102 -4.071112)
			(stroke
				(width 0.1)
				(type default)
			)
			(layer "F.SilkS")
		)
		(fp_line
			(start 17.762474 -1.456436)
			(end 17.750536 -1.387348)
			(stroke
				(width 0.1)
				(type default)
			)
			(layer "F.SilkS")
		)
		(fp_line
			(start 17.762474 -1.456436)
			(end 17.750536 -1.387348)
			(stroke
				(width 0.1)
				(type default)
			)
			(layer "F.SilkS")
		)
		(fp_line
			(start 17.774666 -1.525778)
			(end 17.762474 -1.456436)
			(stroke
				(width 0.1)
				(type default)
			)
			(layer "F.SilkS")
		)
		(fp_line
			(start 17.774666 -1.525778)
			(end 17.762474 -1.456436)
			(stroke
				(width 0.1)
				(type default)
			)
			(layer "F.SilkS")
		)
		(fp_line
			(start 17.786858 -1.595374)
			(end 17.774666 -1.525778)
			(stroke
				(width 0.1)
				(type default)
			)
			(layer "F.SilkS")
		)
		(fp_line
			(start 17.786858 -1.595374)
			(end 17.774666 -1.525778)
			(stroke
				(width 0.1)
				(type default)
			)
			(layer "F.SilkS")
		)
		(fp_line
			(start 17.78762 -4.943348)
			(end 16.845788 -4.03987)
			(stroke
				(width 0.1)
				(type default)
			)
			(layer "F.SilkS")
		)
		(fp_line
			(start 17.78762 -4.943348)
			(end 16.845788 -4.03987)
			(stroke
				(width 0.1)
				(type default)
			)
			(layer "F.SilkS")
		)
		(fp_line
			(start 17.79905 -1.664716)
			(end 17.786858 -1.595374)
			(stroke
				(width 0.1)
				(type default)
			)
			(layer "F.SilkS")
		)
		(fp_line
			(start 17.79905 -1.664716)
			(end 17.786858 -1.595374)
			(stroke
				(width 0.1)
				(type default)
			)
			(layer "F.SilkS")
		)
		(fp_line
			(start 17.810988 -1.734058)
			(end 17.79905 -1.664716)
			(stroke
				(width 0.1)
				(type default)
			)
			(layer "F.SilkS")
		)
		(fp_line
			(start 17.810988 -1.734058)
			(end 17.79905 -1.664716)
			(stroke
				(width 0.1)
				(type default)
			)
			(layer "F.SilkS")
		)
		(fp_line
			(start 17.813782 -4.910836)
			(end 16.87322 -4.008882)
			(stroke
				(width 0.1)
				(type default)
			)
			(layer "F.SilkS")
		)
		(fp_line
			(start 17.813782 -4.910836)
			(end 16.87322 -4.008882)
			(stroke
				(width 0.1)
				(type default)
			)
			(layer "F.SilkS")
		)
		(fp_line
			(start 17.823434 -1.8034)
			(end 17.810988 -1.734058)
			(stroke
				(width 0.1)
				(type default)
			)
			(layer "F.SilkS")
		)
		(fp_line
			(start 17.823434 -1.8034)
			(end 17.810988 -1.734058)
			(stroke
				(width 0.1)
				(type default)
			)
			(layer "F.SilkS")
		)
		(fp_line
			(start 17.835626 -1.872742)
			(end 17.823434 -1.8034)
			(stroke
				(width 0.1)
				(type default)
			)
			(layer "F.SilkS")
		)
		(fp_line
			(start 17.835626 -1.872742)
			(end 17.823434 -1.8034)
			(stroke
				(width 0.1)
				(type default)
			)
			(layer "F.SilkS")
		)
		(fp_line
			(start 17.839944 -4.878324)
			(end 16.89735 -3.97383)
			(stroke
				(width 0.1)
				(type default)
			)
			(layer "F.SilkS")
		)
		(fp_line
			(start 17.839944 -4.878324)
			(end 16.89735 -3.97383)
			(stroke
				(width 0.1)
				(type default)
			)
			(layer "F.SilkS")
		)
		(fp_line
			(start 17.847564 -1.942338)
			(end 17.835626 -1.872742)
			(stroke
				(width 0.1)
				(type default)
			)
			(layer "F.SilkS")
		)
		(fp_line
			(start 17.847564 -1.942338)
			(end 17.835626 -1.872742)
			(stroke
				(width 0.1)
				(type default)
			)
			(layer "F.SilkS")
		)
		(fp_line
			(start 17.86001 -2.011426)
			(end 17.847564 -1.942338)
			(stroke
				(width 0.1)
				(type default)
			)
			(layer "F.SilkS")
		)
		(fp_line
			(start 17.86001 -2.011426)
			(end 17.847564 -1.942338)
			(stroke
				(width 0.1)
				(type default)
			)
			(layer "F.SilkS")
		)
		(fp_line
			(start 17.866106 -4.845558)
			(end 16.915384 -3.93319)
			(stroke
				(width 0.1)
				(type default)
			)
			(layer "F.SilkS")
		)
		(fp_line
			(start 17.866106 -4.845558)
			(end 16.915384 -3.93319)
			(stroke
				(width 0.1)
				(type default)
			)
			(layer "F.SilkS")
		)
		(fp_line
			(start 17.871948 -2.081022)
			(end 17.86001 -2.011426)
			(stroke
				(width 0.1)
				(type default)
			)
			(layer "F.SilkS")
		)
		(fp_line
			(start 17.871948 -2.081022)
			(end 17.86001 -2.011426)
			(stroke
				(width 0.1)
				(type default)
			)
			(layer "F.SilkS")
		)
		(fp_line
			(start 17.88414 -2.150364)
			(end 17.871948 -2.081022)
			(stroke
				(width 0.1)
				(type default)
			)
			(layer "F.SilkS")
		)
		(fp_line
			(start 17.88414 -2.150364)
			(end 17.871948 -2.081022)
			(stroke
				(width 0.1)
				(type default)
			)
			(layer "F.SilkS")
		)
		(fp_line
			(start 17.892268 -4.813046)
			(end 16.93291 -3.89255)
			(stroke
				(width 0.1)
				(type default)
			)
			(layer "F.SilkS")
		)
		(fp_line
			(start 17.892268 -4.813046)
			(end 16.93291 -3.89255)
			(stroke
				(width 0.1)
				(type default)
			)
			(layer "F.SilkS")
		)
		(fp_line
			(start 17.896586 -2.21996)
			(end 17.88414 -2.150364)
			(stroke
				(width 0.1)
				(type default)
			)
			(layer "F.SilkS")
		)
		(fp_line
			(start 17.896586 -2.21996)
			(end 17.88414 -2.150364)
			(stroke
				(width 0.1)
				(type default)
			)
			(layer "F.SilkS")
		)
		(fp_line
			(start 17.908524 -2.289048)
			(end 17.896586 -2.21996)
			(stroke
				(width 0.1)
				(type default)
			)
			(layer "F.SilkS")
		)
		(fp_line
			(start 17.908524 -2.289048)
			(end 17.896586 -2.21996)
			(stroke
				(width 0.1)
				(type default)
			)
			(layer "F.SilkS")
		)
		(fp_line
			(start 17.91843 -4.780534)
			(end 16.949674 -3.850894)
			(stroke
				(width 0.1)
				(type default)
			)
			(layer "F.SilkS")
		)
		(fp_line
			(start 17.91843 -4.780534)
			(end 16.949674 -3.850894)
			(stroke
				(width 0.1)
				(type default)
			)
			(layer "F.SilkS")
		)
		(fp_line
			(start 17.920716 -2.35839)
			(end 17.908524 -2.289048)
			(stroke
				(width 0.1)
				(type default)
			)
			(layer "F.SilkS")
		)
		(fp_line
			(start 17.920716 -2.35839)
			(end 17.908524 -2.289048)
			(stroke
				(width 0.1)
				(type default)
			)
			(layer "F.SilkS")
		)
		(fp_line
			(start 17.932908 -2.427732)
			(end 17.920716 -2.35839)
			(stroke
				(width 0.1)
				(type default)
			)
			(layer "F.SilkS")
		)
		(fp_line
			(start 17.932908 -2.427732)
			(end 17.920716 -2.35839)
			(stroke
				(width 0.1)
				(type default)
			)
			(layer "F.SilkS")
		)
		(fp_line
			(start 17.944846 -4.748022)
			(end 16.958056 -3.80111)
			(stroke
				(width 0.1)
				(type default)
			)
			(layer "F.SilkS")
		)
		(fp_line
			(start 17.944846 -4.748022)
			(end 16.958056 -3.80111)
			(stroke
				(width 0.1)
				(type default)
			)
			(layer "F.SilkS")
		)
		(fp_line
			(start 17.9451 -2.497328)
			(end 17.932908 -2.427732)
			(stroke
				(width 0.1)
				(type default)
			)
			(layer "F.SilkS")
		)
		(fp_line
			(start 17.9451 -2.497328)
			(end 17.932908 -2.427732)
			(stroke
				(width 0.1)
				(type default)
			)
			(layer "F.SilkS")
		)
		(fp_line
			(start 17.957038 -2.56667)
			(end 17.9451 -2.497328)
			(stroke
				(width 0.1)
				(type default)
			)
			(layer "F.SilkS")
		)
		(fp_line
			(start 17.957038 -2.56667)
			(end 17.9451 -2.497328)
			(stroke
				(width 0.1)
				(type default)
			)
			(layer "F.SilkS")
		)
		(fp_line
			(start 17.966182 -4.710176)
			(end 16.966438 -3.751326)
			(stroke
				(width 0.1)
				(type default)
			)
			(layer "F.SilkS")
		)
		(fp_line
			(start 17.966182 -4.710176)
			(end 16.966438 -3.751326)
			(stroke
				(width 0.1)
				(type default)
			)
			(layer "F.SilkS")
		)
		(fp_line
			(start 17.969484 -2.636012)
			(end 17.957038 -2.56667)
			(stroke
				(width 0.1)
				(type default)
			)
			(layer "F.SilkS")
		)
		(fp_line
			(start 17.969484 -2.636012)
			(end 17.957038 -2.56667)
			(stroke
				(width 0.1)
				(type default)
			)
			(layer "F.SilkS")
		)
		(fp_line
			(start 17.981676 -2.705608)
			(end 17.969484 -2.636012)
			(stroke
				(width 0.1)
				(type default)
			)
			(layer "F.SilkS")
		)
		(fp_line
			(start 17.981676 -2.705608)
			(end 17.969484 -2.636012)
			(stroke
				(width 0.1)
				(type default)
			)
			(layer "F.SilkS")
		)
		(fp_line
			(start 17.9832 -4.669282)
			(end 16.974566 -3.701542)
			(stroke
				(width 0.1)
				(type default)
			)
			(layer "F.SilkS")
		)
		(fp_line
			(start 17.9832 -4.669282)
			(end 16.974566 -3.701542)
			(stroke
				(width 0.1)
				(type default)
			)
			(layer "F.SilkS")
		)
		(fp_line
			(start 17.993614 -2.77495)
			(end 17.981676 -2.705608)
			(stroke
				(width 0.1)
				(type default)
			)
			(layer "F.SilkS")
		)
		(fp_line
			(start 17.993614 -2.77495)
			(end 17.981676 -2.705608)
			(stroke
				(width 0.1)
				(type default)
			)
			(layer "F.SilkS")
		)
		(fp_line
			(start 18.000472 -4.628388)
			(end 16.97736 -3.646424)
			(stroke
				(width 0.1)
				(type default)
			)
			(layer "F.SilkS")
		)
		(fp_line
			(start 18.000472 -4.628388)
			(end 16.97736 -3.646424)
			(stroke
				(width 0.1)
				(type default)
			)
			(layer "F.SilkS")
		)
		(fp_line
			(start 18.00606 -2.844292)
			(end 17.993614 -2.77495)
			(stroke
				(width 0.1)
				(type default)
			)
			(layer "F.SilkS")
		)
		(fp_line
			(start 18.00606 -2.844292)
			(end 17.993614 -2.77495)
			(stroke
				(width 0.1)
				(type default)
			)
			(layer "F.SilkS")
		)
		(fp_line
			(start 18.017998 -4.58724)
			(end 16.976598 -3.588258)
			(stroke
				(width 0.1)
				(type default)
			)
			(layer "F.SilkS")
		)
		(fp_line
			(start 18.017998 -4.58724)
			(end 16.976598 -3.588258)
			(stroke
				(width 0.1)
				(type default)
			)
			(layer "F.SilkS")
		)
		(fp_line
			(start 18.017998 -2.913634)
			(end 18.00606 -2.844292)
			(stroke
				(width 0.1)
				(type default)
			)
			(layer "F.SilkS")
		)
		(fp_line
			(start 18.017998 -2.913634)
			(end 18.00606 -2.844292)
			(stroke
				(width 0.1)
				(type default)
			)
			(layer "F.SilkS")
		)
		(fp_line
			(start 18.03019 -2.982976)
			(end 18.017998 -2.913634)
			(stroke
				(width 0.1)
				(type default)
			)
			(layer "F.SilkS")
		)
		(fp_line
			(start 18.03019 -2.982976)
			(end 18.017998 -2.913634)
			(stroke
				(width 0.1)
				(type default)
			)
			(layer "F.SilkS")
		)
		(fp_line
			(start 18.035778 -4.546346)
			(end 16.97609 -3.529838)
			(stroke
				(width 0.1)
				(type default)
			)
			(layer "F.SilkS")
		)
		(fp_line
			(start 18.035778 -4.546346)
			(end 16.97609 -3.529838)
			(stroke
				(width 0.1)
				(type default)
			)
			(layer "F.SilkS")
		)
		(fp_line
			(start 18.042636 -3.052572)
			(end 18.03019 -2.982976)
			(stroke
				(width 0.1)
				(type default)
			)
			(layer "F.SilkS")
		)
		(fp_line
			(start 18.042636 -3.052572)
			(end 18.03019 -2.982976)
			(stroke
				(width 0.1)
				(type default)
			)
			(layer "F.SilkS")
		)
		(fp_line
			(start 18.052796 -4.505198)
			(end 16.975582 -3.471672)
			(stroke
				(width 0.1)
				(type default)
			)
			(layer "F.SilkS")
		)
		(fp_line
			(start 18.052796 -4.505198)
			(end 16.975582 -3.471672)
			(stroke
				(width 0.1)
				(type default)
			)
			(layer "F.SilkS")
		)
		(fp_line
			(start 18.054574 -3.121914)
			(end 18.042636 -3.052572)
			(stroke
				(width 0.1)
				(type default)
			)
			(layer "F.SilkS")
		)
		(fp_line
			(start 18.054574 -3.121914)
			(end 18.042636 -3.052572)
			(stroke
				(width 0.1)
				(type default)
			)
			(layer "F.SilkS")
		)
		(fp_line
			(start 18.066766 -3.191002)
			(end 18.054574 -3.121914)
			(stroke
				(width 0.1)
				(type default)
			)
			(layer "F.SilkS")
		)
		(fp_line
			(start 18.066766 -3.191002)
			(end 18.054574 -3.121914)
			(stroke
				(width 0.1)
				(type default)
			)
			(layer "F.SilkS")
		)
		(fp_line
			(start 18.070068 -4.464304)
			(end 16.967708 -3.406648)
			(stroke
				(width 0.1)
				(type default)
			)
			(layer "F.SilkS")
		)
		(fp_line
			(start 18.070068 -4.464304)
			(end 16.967708 -3.406648)
			(stroke
				(width 0.1)
				(type default)
			)
			(layer "F.SilkS")
		)
		(fp_line
			(start 18.079212 -3.260598)
			(end 18.066766 -3.191002)
			(stroke
				(width 0.1)
				(type default)
			)
			(layer "F.SilkS")
		)
		(fp_line
			(start 18.079212 -3.260598)
			(end 18.066766 -3.191002)
			(stroke
				(width 0.1)
				(type default)
			)
			(layer "F.SilkS")
		)
		(fp_line
			(start 18.081752 -4.417314)
			(end 16.959326 -3.340608)
			(stroke
				(width 0.1)
				(type default)
			)
			(layer "F.SilkS")
		)
		(fp_line
			(start 18.081752 -4.417314)
			(end 16.959326 -3.340608)
			(stroke
				(width 0.1)
				(type default)
			)
			(layer "F.SilkS")
		)
		(fp_line
			(start 18.090388 -4.368038)
			(end 16.950436 -3.274568)
			(stroke
				(width 0.1)
				(type default)
			)
			(layer "F.SilkS")
		)
		(fp_line
			(start 18.090388 -4.368038)
			(end 16.950436 -3.274568)
			(stroke
				(width 0.1)
				(type default)
			)
			(layer "F.SilkS")
		)
		(fp_line
			(start 18.099532 -4.318762)
			(end 16.942308 -3.208782)
			(stroke
				(width 0.1)
				(type default)
			)
			(layer "F.SilkS")
		)
		(fp_line
			(start 18.099532 -4.318762)
			(end 16.942308 -3.208782)
			(stroke
				(width 0.1)
				(type default)
			)
			(layer "F.SilkS")
		)
		(fp_line
			(start 18.107914 -4.26974)
			(end 16.930624 -3.139694)
			(stroke
				(width 0.1)
				(type default)
			)
			(layer "F.SilkS")
		)
		(fp_line
			(start 18.107914 -4.26974)
			(end 16.930624 -3.139694)
			(stroke
				(width 0.1)
				(type default)
			)
			(layer "F.SilkS")
		)
		(fp_line
			(start 18.137632 -3.836416)
			(end 16.83258 -2.58445)
			(stroke
				(width 0.1)
				(type default)
			)
			(layer "F.SilkS")
		)
		(fp_line
			(start 18.137632 -3.836416)
			(end 16.83258 -2.58445)
			(stroke
				(width 0.1)
				(type default)
			)
			(layer "F.SilkS")
		)
		(fp_line
			(start 18.736818 -4.109466)
			(end 18.783554 -4.109466)
			(stroke
				(width 0.1)
				(type default)
			)
			(layer "F.SilkS")
		)
		(fp_line
			(start 18.736818 -4.109466)
			(end 18.783554 -4.109466)
			(stroke
				(width 0.1)
				(type default)
			)
			(layer "F.SilkS")
		)
		(fp_line
			(start 18.739612 -4.12496)
			(end 18.736818 -4.109466)
			(stroke
				(width 0.1)
				(type default)
			)
			(layer "F.SilkS")
		)
		(fp_line
			(start 18.739612 -4.12496)
			(end 18.736818 -4.109466)
			(stroke
				(width 0.1)
				(type default)
			)
			(layer "F.SilkS")
		)
		(fp_line
			(start 18.739612 -4.12496)
			(end 20.959318 -6.254496)
			(stroke
				(width 0.1)
				(type default)
			)
			(layer "F.SilkS")
		)
		(fp_line
			(start 18.739612 -4.12496)
			(end 20.959318 -6.254496)
			(stroke
				(width 0.1)
				(type default)
			)
			(layer "F.SilkS")
		)
		(fp_line
			(start 18.75155 -4.194556)
			(end 18.739612 -4.12496)
			(stroke
				(width 0.1)
				(type default)
			)
			(layer "F.SilkS")
		)
		(fp_line
			(start 18.75155 -4.194556)
			(end 18.739612 -4.12496)
			(stroke
				(width 0.1)
				(type default)
			)
			(layer "F.SilkS")
		)
		(fp_line
			(start 18.763996 -4.263898)
			(end 18.75155 -4.194556)
			(stroke
				(width 0.1)
				(type default)
			)
			(layer "F.SilkS")
		)
		(fp_line
			(start 18.763996 -4.263898)
			(end 18.75155 -4.194556)
			(stroke
				(width 0.1)
				(type default)
			)
			(layer "F.SilkS")
		)
		(fp_line
			(start 18.775934 -4.33324)
			(end 18.763996 -4.263898)
			(stroke
				(width 0.1)
				(type default)
			)
			(layer "F.SilkS")
		)
		(fp_line
			(start 18.775934 -4.33324)
			(end 18.763996 -4.263898)
			(stroke
				(width 0.1)
				(type default)
			)
			(layer "F.SilkS")
		)
		(fp_line
			(start 18.775934 -4.33324)
			(end 18.78838 -4.402836)
			(stroke
				(width 0.1)
				(type default)
			)
			(layer "F.SilkS")
		)
		(fp_line
			(start 18.775934 -4.33324)
			(end 18.78838 -4.402836)
			(stroke
				(width 0.1)
				(type default)
			)
			(layer "F.SilkS")
		)
		(fp_line
			(start 18.783554 -4.109466)
			(end 18.843498 -4.109466)
			(stroke
				(width 0.1)
				(type default)
			)
			(layer "F.SilkS")
		)
		(fp_line
			(start 18.783554 -4.109466)
			(end 18.843498 -4.109466)
			(stroke
				(width 0.1)
				(type default)
			)
			(layer "F.SilkS")
		)
		(fp_line
			(start 18.783554 -4.109466)
			(end 20.947126 -6.1849)
			(stroke
				(width 0.1)
				(type default)
			)
			(layer "F.SilkS")
		)
		(fp_line
			(start 18.783554 -4.109466)
			(end 20.947126 -6.1849)
			(stroke
				(width 0.1)
				(type default)
			)
			(layer "F.SilkS")
		)
		(fp_line
			(start 18.78838 -4.402836)
			(end 18.800572 -4.472178)
			(stroke
				(width 0.1)
				(type default)
			)
			(layer "F.SilkS")
		)
		(fp_line
			(start 18.78838 -4.402836)
			(end 18.800572 -4.472178)
			(stroke
				(width 0.1)
				(type default)
			)
			(layer "F.SilkS")
		)
		(fp_line
			(start 18.78838 -4.402836)
			(end 19.58975 -5.171694)
			(stroke
				(width 0.1)
				(type default)
			)
			(layer "F.SilkS")
		)
		(fp_line
			(start 18.78838 -4.402836)
			(end 19.58975 -5.171694)
			(stroke
				(width 0.1)
				(type default)
			)
			(layer "F.SilkS")
		)
		(fp_line
			(start 18.800572 -4.472178)
			(end 18.81251 -4.54152)
			(stroke
				(width 0.1)
				(type default)
			)
			(layer "F.SilkS")
		)
		(fp_line
			(start 18.800572 -4.472178)
			(end 18.81251 -4.54152)
			(stroke
				(width 0.1)
				(type default)
			)
			(layer "F.SilkS")
		)
		(fp_line
			(start 18.800572 -4.472178)
			(end 19.529806 -5.171694)
			(stroke
				(width 0.1)
				(type default)
			)
			(layer "F.SilkS")
		)
		(fp_line
			(start 18.800572 -4.472178)
			(end 19.529806 -5.171694)
			(stroke
				(width 0.1)
				(type default)
			)
			(layer "F.SilkS")
		)
		(fp_line
			(start 18.81251 -4.54152)
			(end 18.824956 -4.610862)
			(stroke
				(width 0.1)
				(type default)
			)
			(layer "F.SilkS")
		)
		(fp_line
			(start 18.81251 -4.54152)
			(end 18.824956 -4.610862)
			(stroke
				(width 0.1)
				(type default)
			)
			(layer "F.SilkS")
		)
		(fp_line
			(start 18.81251 -4.54152)
			(end 19.469608 -5.171694)
			(stroke
				(width 0.1)
				(type default)
			)
			(layer "F.SilkS")
		)
		(fp_line
			(start 18.81251 -4.54152)
			(end 19.469608 -5.171694)
			(stroke
				(width 0.1)
				(type default)
			)
			(layer "F.SilkS")
		)
		(fp_line
			(start 18.824956 -4.610862)
			(end 18.836894 -4.680458)
			(stroke
				(width 0.1)
				(type default)
			)
			(layer "F.SilkS")
		)
		(fp_line
			(start 18.824956 -4.610862)
			(end 18.836894 -4.680458)
			(stroke
				(width 0.1)
				(type default)
			)
			(layer "F.SilkS")
		)
		(fp_line
			(start 18.824956 -4.610862)
			(end 19.409664 -5.171694)
			(stroke
				(width 0.1)
				(type default)
			)
			(layer "F.SilkS")
		)
		(fp_line
			(start 18.824956 -4.610862)
			(end 19.409664 -5.171694)
			(stroke
				(width 0.1)
				(type default)
			)
			(layer "F.SilkS")
		)
		(fp_line
			(start 18.836894 -4.680458)
			(end 18.84934 -4.7498)
			(stroke
				(width 0.1)
				(type default)
			)
			(layer "F.SilkS")
		)
		(fp_line
			(start 18.836894 -4.680458)
			(end 18.84934 -4.7498)
			(stroke
				(width 0.1)
				(type default)
			)
			(layer "F.SilkS")
		)
		(fp_line
			(start 18.836894 -4.680458)
			(end 19.349212 -5.171694)
			(stroke
				(width 0.1)
				(type default)
			)
			(layer "F.SilkS")
		)
		(fp_line
			(start 18.836894 -4.680458)
			(end 19.349212 -5.171694)
			(stroke
				(width 0.1)
				(type default)
			)
			(layer "F.SilkS")
		)
		(fp_line
			(start 18.843498 -4.109466)
			(end 18.90395 -4.109466)
			(stroke
				(width 0.1)
				(type default)
			)
			(layer "F.SilkS")
		)
		(fp_line
			(start 18.843498 -4.109466)
			(end 18.90395 -4.109466)
			(stroke
				(width 0.1)
				(type default)
			)
			(layer "F.SilkS")
		)
		(fp_line
			(start 18.843498 -4.109466)
			(end 20.93468 -6.115558)
			(stroke
				(width 0.1)
				(type default)
			)
			(layer "F.SilkS")
		)
		(fp_line
			(start 18.843498 -4.109466)
			(end 20.93468 -6.115558)
			(stroke
				(width 0.1)
				(type default)
			)
			(layer "F.SilkS")
		)
		(fp_line
			(start 18.84934 -4.7498)
			(end 18.861532 -4.819142)
			(stroke
				(width 0.1)
				(type default)
			)
			(layer "F.SilkS")
		)
		(fp_line
			(start 18.84934 -4.7498)
			(end 18.861532 -4.819142)
			(stroke
				(width 0.1)
				(type default)
			)
			(layer "F.SilkS")
		)
		(fp_line
			(start 18.84934 -4.7498)
			(end 19.289014 -5.171694)
			(stroke
				(width 0.1)
				(type default)
			)
			(layer "F.SilkS")
		)
		(fp_line
			(start 18.84934 -4.7498)
			(end 19.289014 -5.171694)
			(stroke
				(width 0.1)
				(type default)
			)
			(layer "F.SilkS")
		)
		(fp_line
			(start 18.861532 -4.819142)
			(end 18.873978 -4.888484)
			(stroke
				(width 0.1)
				(type default)
			)
			(layer "F.SilkS")
		)
		(fp_line
			(start 18.861532 -4.819142)
			(end 18.873978 -4.888484)
			(stroke
				(width 0.1)
				(type default)
			)
			(layer "F.SilkS")
		)
		(fp_line
			(start 18.861532 -4.819142)
			(end 19.22907 -5.171694)
			(stroke
				(width 0.1)
				(type default)
			)
			(layer "F.SilkS")
		)
		(fp_line
			(start 18.861532 -4.819142)
			(end 19.22907 -5.171694)
			(stroke
				(width 0.1)
				(type default)
			)
			(layer "F.SilkS")
		)
		(fp_line
			(start 18.873978 -4.888484)
			(end 19.168872 -5.171694)
			(stroke
				(width 0.1)
				(type default)
			)
			(layer "F.SilkS")
		)
		(fp_line
			(start 18.873978 -4.888484)
			(end 19.168872 -5.171694)
			(stroke
				(width 0.1)
				(type default)
			)
			(layer "F.SilkS")
		)
		(fp_line
			(start 18.885916 -4.95808)
			(end 18.873978 -4.888484)
			(stroke
				(width 0.1)
				(type default)
			)
			(layer "F.SilkS")
		)
		(fp_line
			(start 18.885916 -4.95808)
			(end 18.873978 -4.888484)
			(stroke
				(width 0.1)
				(type default)
			)
			(layer "F.SilkS")
		)
		(fp_line
			(start 18.898108 -5.027422)
			(end 18.885916 -4.95808)
			(stroke
				(width 0.1)
				(type default)
			)
			(layer "F.SilkS")
		)
		(fp_line
			(start 18.898108 -5.027422)
			(end 18.885916 -4.95808)
			(stroke
				(width 0.1)
				(type default)
			)
			(layer "F.SilkS")
		)
		(fp_line
			(start 18.898108 -5.027422)
			(end 18.9103 -5.097018)
			(stroke
				(width 0.1)
				(type default)
			)
			(layer "F.SilkS")
		)
		(fp_line
			(start 18.898108 -5.027422)
			(end 18.9103 -5.097018)
			(stroke
				(width 0.1)
				(type default)
			)
			(layer "F.SilkS")
		)
		(fp_line
			(start 18.898108 -5.027422)
			(end 19.048476 -5.171694)
			(stroke
				(width 0.1)
				(type default)
			)
			(layer "F.SilkS")
		)
		(fp_line
			(start 18.898108 -5.027422)
			(end 19.048476 -5.171694)
			(stroke
				(width 0.1)
				(type default)
			)
			(layer "F.SilkS")
		)
		(fp_line
			(start 18.90395 -4.109466)
			(end 18.964148 -4.109466)
			(stroke
				(width 0.1)
				(type default)
			)
			(layer "F.SilkS")
		)
		(fp_line
			(start 18.90395 -4.109466)
			(end 18.964148 -4.109466)
			(stroke
				(width 0.1)
				(type default)
			)
			(layer "F.SilkS")
		)
		(fp_line
			(start 18.90395 -4.109466)
			(end 20.922742 -6.04647)
			(stroke
				(width 0.1)
				(type default)
			)
			(layer "F.SilkS")
		)
		(fp_line
			(start 18.90395 -4.109466)
			(end 20.922742 -6.04647)
			(stroke
				(width 0.1)
				(type default)
			)
			(layer "F.SilkS")
		)
		(fp_line
			(start 18.9103 -5.097018)
			(end 18.922492 -5.166106)
			(stroke
				(width 0.1)
				(type default)
			)
			(layer "F.SilkS")
		)
		(fp_line
			(start 18.9103 -5.097018)
			(end 18.922492 -5.166106)
			(stroke
				(width 0.1)
				(type default)
			)
			(layer "F.SilkS")
		)
		(fp_line
			(start 18.9103 -5.097018)
			(end 18.988278 -5.171694)
			(stroke
				(width 0.1)
				(type default)
			)
			(layer "F.SilkS")
		)
		(fp_line
			(start 18.9103 -5.097018)
			(end 18.988278 -5.171694)
			(stroke
				(width 0.1)
				(type default)
			)
			(layer "F.SilkS")
		)
		(fp_line
			(start 18.922492 -5.166106)
			(end 18.923508 -5.171694)
			(stroke
				(width 0.1)
				(type default)
			)
			(layer "F.SilkS")
		)
		(fp_line
			(start 18.922492 -5.166106)
			(end 18.923508 -5.171694)
			(stroke
				(width 0.1)
				(type default)
			)
			(layer "F.SilkS")
		)
		(fp_line
			(start 18.922492 -5.166106)
			(end 18.928334 -5.171694)
			(stroke
				(width 0.1)
				(type default)
			)
			(layer "F.SilkS")
		)
		(fp_line
			(start 18.922492 -5.166106)
			(end 18.928334 -5.171694)
			(stroke
				(width 0.1)
				(type default)
			)
			(layer "F.SilkS")
		)
		(fp_line
			(start 18.923508 -5.171694)
			(end 18.928334 -5.171694)
			(stroke
				(width 0.1)
				(type default)
			)
			(layer "F.SilkS")
		)
		(fp_line
			(start 18.923508 -5.171694)
			(end 18.928334 -5.171694)
			(stroke
				(width 0.1)
				(type default)
			)
			(layer "F.SilkS")
		)
		(fp_line
			(start 18.964148 -4.109466)
			(end 19.024092 -4.109466)
			(stroke
				(width 0.1)
				(type default)
			)
			(layer "F.SilkS")
		)
		(fp_line
			(start 18.964148 -4.109466)
			(end 19.024092 -4.109466)
			(stroke
				(width 0.1)
				(type default)
			)
			(layer "F.SilkS")
		)
		(fp_line
			(start 18.964148 -4.109466)
			(end 20.91055 -5.976874)
			(stroke
				(width 0.1)
				(type default)
			)
			(layer "F.SilkS")
		)
		(fp_line
			(start 18.964148 -4.109466)
			(end 20.91055 -5.976874)
			(stroke
				(width 0.1)
				(type default)
			)
			(layer "F.SilkS")
		)
		(fp_line
			(start 18.988278 -5.171694)
			(end 18.928334 -5.171694)
			(stroke
				(width 0.1)
				(type default)
			)
			(layer "F.SilkS")
		)
		(fp_line
			(start 18.988278 -5.171694)
			(end 18.928334 -5.171694)
			(stroke
				(width 0.1)
				(type default)
			)
			(layer "F.SilkS")
		)
		(fp_line
			(start 19.024092 -4.109466)
			(end 19.08429 -4.109466)
			(stroke
				(width 0.1)
				(type default)
			)
			(layer "F.SilkS")
		)
		(fp_line
			(start 19.024092 -4.109466)
			(end 19.08429 -4.109466)
			(stroke
				(width 0.1)
				(type default)
			)
			(layer "F.SilkS")
		)
		(fp_line
			(start 19.024092 -4.109466)
			(end 20.898104 -5.907278)
			(stroke
				(width 0.1)
				(type default)
			)
			(layer "F.SilkS")
		)
		(fp_line
			(start 19.024092 -4.109466)
			(end 20.898104 -5.907278)
			(stroke
				(width 0.1)
				(type default)
			)
			(layer "F.SilkS")
		)
		(fp_line
			(start 19.048476 -5.171694)
			(end 18.988278 -5.171694)
			(stroke
				(width 0.1)
				(type default)
			)
			(layer "F.SilkS")
		)
		(fp_line
			(start 19.048476 -5.171694)
			(end 18.988278 -5.171694)
			(stroke
				(width 0.1)
				(type default)
			)
			(layer "F.SilkS")
		)
		(fp_line
			(start 19.048476 -5.171694)
			(end 19.10842 -5.171694)
			(stroke
				(width 0.1)
				(type default)
			)
			(layer "F.SilkS")
		)
		(fp_line
			(start 19.048476 -5.171694)
			(end 19.10842 -5.171694)
			(stroke
				(width 0.1)
				(type default)
			)
			(layer "F.SilkS")
		)
		(fp_line
			(start 19.074638 -1.79197)
			(end 20.399248 -3.062478)
			(stroke
				(width 0.1)
				(type default)
			)
			(layer "F.SilkS")
		)
		(fp_line
			(start 19.074638 -1.79197)
			(end 20.399248 -3.062478)
			(stroke
				(width 0.1)
				(type default)
			)
			(layer "F.SilkS")
		)
		(fp_line
			(start 19.077178 -1.851914)
			(end 20.41144 -3.13182)
			(stroke
				(width 0.1)
				(type default)
			)
			(layer "F.SilkS")
		)
		(fp_line
			(start 19.077178 -1.851914)
			(end 20.41144 -3.13182)
			(stroke
				(width 0.1)
				(type default)
			)
			(layer "F.SilkS")
		)
		(fp_line
			(start 19.078448 -1.737868)
			(end 20.38731 -2.99339)
			(stroke
				(width 0.1)
				(type default)
			)
			(layer "F.SilkS")
		)
		(fp_line
			(start 19.078448 -1.737868)
			(end 20.38731 -2.99339)
			(stroke
				(width 0.1)
				(type default)
			)
			(layer "F.SilkS")
		)
		(fp_line
			(start 19.082258 -1.683512)
			(end 20.374864 -2.923794)
			(stroke
				(width 0.1)
				(type default)
			)
			(layer "F.SilkS")
		)
		(fp_line
			(start 19.082258 -1.683512)
			(end 20.374864 -2.923794)
			(stroke
				(width 0.1)
				(type default)
			)
			(layer "F.SilkS")
		)
		(fp_line
			(start 19.083274 -1.915668)
			(end 20.423886 -3.201416)
			(stroke
				(width 0.1)
				(type default)
			)
			(layer "F.SilkS")
		)
		(fp_line
			(start 19.083274 -1.915668)
			(end 20.423886 -3.201416)
			(stroke
				(width 0.1)
				(type default)
			)
			(layer "F.SilkS")
		)
		(fp_line
			(start 19.08429 -4.109466)
			(end 19.144234 -4.109466)
			(stroke
				(width 0.1)
				(type default)
			)
			(layer "F.SilkS")
		)
		(fp_line
			(start 19.08429 -4.109466)
			(end 19.144234 -4.109466)
			(stroke
				(width 0.1)
				(type default)
			)
			(layer "F.SilkS")
		)
		(fp_line
			(start 19.08429 -4.109466)
			(end 20.886166 -5.837936)
			(stroke
				(width 0.1)
				(type default)
			)
			(layer "F.SilkS")
		)
		(fp_line
			(start 19.08429 -4.109466)
			(end 20.886166 -5.837936)
			(stroke
				(width 0.1)
				(type default)
			)
			(layer "F.SilkS")
		)
		(fp_line
			(start 19.086068 -1.62941)
			(end 20.362926 -2.854198)
			(stroke
				(width 0.1)
				(type default)
			)
			(layer "F.SilkS")
		)
		(fp_line
			(start 19.086068 -1.62941)
			(end 20.362926 -2.854198)
			(stroke
				(width 0.1)
				(type default)
			)
			(layer "F.SilkS")
		)
		(fp_line
			(start 19.089624 -1.575308)
			(end 20.35048 -2.784856)
			(stroke
				(width 0.1)
				(type default)
			)
			(layer "F.SilkS")
		)
		(fp_line
			(start 19.089624 -1.575308)
			(end 20.35048 -2.784856)
			(stroke
				(width 0.1)
				(type default)
			)
			(layer "F.SilkS")
		)
		(fp_line
			(start 19.089878 -1.979676)
			(end 20.435824 -3.270758)
			(stroke
				(width 0.1)
				(type default)
			)
			(layer "F.SilkS")
		)
		(fp_line
			(start 19.089878 -1.979676)
			(end 20.435824 -3.270758)
			(stroke
				(width 0.1)
				(type default)
			)
			(layer "F.SilkS")
		)
		(fp_line
			(start 19.095974 -2.043176)
			(end 20.44827 -3.340354)
			(stroke
				(width 0.1)
				(type default)
			)
			(layer "F.SilkS")
		)
		(fp_line
			(start 19.095974 -2.043176)
			(end 20.44827 -3.340354)
			(stroke
				(width 0.1)
				(type default)
			)
			(layer "F.SilkS")
		)
		(fp_line
			(start 19.100292 -1.528064)
			(end 20.338288 -2.715768)
			(stroke
				(width 0.1)
				(type default)
			)
			(layer "F.SilkS")
		)
		(fp_line
			(start 19.100292 -1.528064)
			(end 20.338288 -2.715768)
			(stroke
				(width 0.1)
				(type default)
			)
			(layer "F.SilkS")
		)
		(fp_line
			(start 19.10461 -2.108962)
			(end 20.460462 -3.409442)
			(stroke
				(width 0.1)
				(type default)
			)
			(layer "F.SilkS")
		)
		(fp_line
			(start 19.10461 -2.108962)
			(end 20.460462 -3.409442)
			(stroke
				(width 0.1)
				(type default)
			)
			(layer "F.SilkS")
		)
		(fp_line
			(start 19.10842 -5.171694)
			(end 18.885916 -4.95808)
			(stroke
				(width 0.1)
				(type default)
			)
			(layer "F.SilkS")
		)
		(fp_line
			(start 19.10842 -5.171694)
			(end 18.885916 -4.95808)
			(stroke
				(width 0.1)
				(type default)
			)
			(layer "F.SilkS")
		)
		(fp_line
			(start 19.10842 -5.171694)
			(end 19.168872 -5.171694)
			(stroke
				(width 0.1)
				(type default)
			)
			(layer "F.SilkS")
		)
		(fp_line
			(start 19.10842 -5.171694)
			(end 19.168872 -5.171694)
			(stroke
				(width 0.1)
				(type default)
			)
			(layer "F.SilkS")
		)
		(fp_line
			(start 19.112738 -1.48209)
			(end 20.32635 -2.646172)
			(stroke
				(width 0.1)
				(type default)
			)
			(layer "F.SilkS")
		)
		(fp_line
			(start 19.112738 -1.48209)
			(end 20.32635 -2.646172)
			(stroke
				(width 0.1)
				(type default)
			)
			(layer "F.SilkS")
		)
		(fp_line
			(start 19.116802 -2.178304)
			(end 19.10461 -2.108962)
			(stroke
				(width 0.1)
				(type default)
			)
			(layer "F.SilkS")
		)
		(fp_line
			(start 19.116802 -2.178304)
			(end 19.10461 -2.108962)
			(stroke
				(width 0.1)
				(type default)
			)
			(layer "F.SilkS")
		)
		(fp_line
			(start 19.116802 -2.178304)
			(end 20.4724 -3.479038)
			(stroke
				(width 0.1)
				(type default)
			)
			(layer "F.SilkS")
		)
		(fp_line
			(start 19.116802 -2.178304)
			(end 20.4724 -3.479038)
			(stroke
				(width 0.1)
				(type default)
			)
			(layer "F.SilkS")
		)
		(fp_line
			(start 19.12493 -1.436116)
			(end 20.313904 -2.576576)
			(stroke
				(width 0.1)
				(type default)
			)
			(layer "F.SilkS")
		)
		(fp_line
			(start 19.12493 -1.436116)
			(end 20.313904 -2.576576)
			(stroke
				(width 0.1)
				(type default)
			)
			(layer "F.SilkS")
		)
		(fp_line
			(start 19.12874 -2.2479)
			(end 19.116802 -2.178304)
			(stroke
				(width 0.1)
				(type default)
			)
			(layer "F.SilkS")
		)
		(fp_line
			(start 19.12874 -2.2479)
			(end 19.116802 -2.178304)
			(stroke
				(width 0.1)
				(type default)
			)
			(layer "F.SilkS")
		)
		(fp_line
			(start 19.12874 -2.2479)
			(end 19.141186 -2.317242)
			(stroke
				(width 0.1)
				(type default)
			)
			(layer "F.SilkS")
		)
		(fp_line
			(start 19.12874 -2.2479)
			(end 19.141186 -2.317242)
			(stroke
				(width 0.1)
				(type default)
			)
			(layer "F.SilkS")
		)
		(fp_line
			(start 19.12874 -2.2479)
			(end 20.484846 -3.548634)
			(stroke
				(width 0.1)
				(type default)
			)
			(layer "F.SilkS")
		)
		(fp_line
			(start 19.12874 -2.2479)
			(end 20.484846 -3.548634)
			(stroke
				(width 0.1)
				(type default)
			)
			(layer "F.SilkS")
		)
		(fp_line
			(start 19.137376 -1.390396)
			(end 20.301966 -2.507234)
			(stroke
				(width 0.1)
				(type default)
			)
			(layer "F.SilkS")
		)
		(fp_line
			(start 19.137376 -1.390396)
			(end 20.301966 -2.507234)
			(stroke
				(width 0.1)
				(type default)
			)
			(layer "F.SilkS")
		)
		(fp_line
			(start 19.144234 -4.109466)
			(end 19.204686 -4.109466)
			(stroke
				(width 0.1)
				(type default)
			)
			(layer "F.SilkS")
		)
		(fp_line
			(start 19.144234 -4.109466)
			(end 19.204686 -4.109466)
			(stroke
				(width 0.1)
				(type default)
			)
			(layer "F.SilkS")
		)
		(fp_line
			(start 19.144234 -4.109466)
			(end 20.874228 -5.768594)
			(stroke
				(width 0.1)
				(type default)
			)
			(layer "F.SilkS")
		)
		(fp_line
			(start 19.144234 -4.109466)
			(end 20.874228 -5.768594)
			(stroke
				(width 0.1)
				(type default)
			)
			(layer "F.SilkS")
		)
		(fp_line
			(start 19.149822 -1.344676)
			(end 20.28952 -2.437892)
			(stroke
				(width 0.1)
				(type default)
			)
			(layer "F.SilkS")
		)
		(fp_line
			(start 19.149822 -1.344676)
			(end 20.28952 -2.437892)
			(stroke
				(width 0.1)
				(type default)
			)
			(layer "F.SilkS")
		)
		(fp_line
			(start 19.153378 -2.386584)
			(end 19.141186 -2.317242)
			(stroke
				(width 0.1)
				(type default)
			)
			(layer "F.SilkS")
		)
		(fp_line
			(start 19.153378 -2.386584)
			(end 19.141186 -2.317242)
			(stroke
				(width 0.1)
				(type default)
			)
			(layer "F.SilkS")
		)
		(fp_line
			(start 19.153378 -2.386584)
			(end 20.50923 -3.687064)
			(stroke
				(width 0.1)
				(type default)
			)
			(layer "F.SilkS")
		)
		(fp_line
			(start 19.153378 -2.386584)
			(end 20.50923 -3.687064)
			(stroke
				(width 0.1)
				(type default)
			)
			(layer "F.SilkS")
		)
		(fp_line
			(start 19.165316 -2.455926)
			(end 19.153378 -2.386584)
			(stroke
				(width 0.1)
				(type default)
			)
			(layer "F.SilkS")
		)
		(fp_line
			(start 19.165316 -2.455926)
			(end 19.153378 -2.386584)
			(stroke
				(width 0.1)
				(type default)
			)
			(layer "F.SilkS")
		)
		(fp_line
			(start 19.165316 -2.455926)
			(end 20.521422 -3.75666)
			(stroke
				(width 0.1)
				(type default)
			)
			(layer "F.SilkS")
		)
		(fp_line
			(start 19.165316 -2.455926)
			(end 20.521422 -3.75666)
			(stroke
				(width 0.1)
				(type default)
			)
			(layer "F.SilkS")
		)
		(fp_line
			(start 19.170142 -1.306322)
			(end 20.278344 -2.369312)
			(stroke
				(width 0.1)
				(type default)
			)
			(layer "F.SilkS")
		)
		(fp_line
			(start 19.170142 -1.306322)
			(end 20.278344 -2.369312)
			(stroke
				(width 0.1)
				(type default)
			)
			(layer "F.SilkS")
		)
		(fp_line
			(start 19.177762 -2.525522)
			(end 19.165316 -2.455926)
			(stroke
				(width 0.1)
				(type default)
			)
			(layer "F.SilkS")
		)
		(fp_line
			(start 19.177762 -2.525522)
			(end 19.165316 -2.455926)
			(stroke
				(width 0.1)
				(type default)
			)
			(layer "F.SilkS")
		)
		(fp_line
			(start 19.177762 -2.525522)
			(end 20.533614 -3.826256)
			(stroke
				(width 0.1)
				(type default)
			)
			(layer "F.SilkS")
		)
		(fp_line
			(start 19.177762 -2.525522)
			(end 20.533614 -3.826256)
			(stroke
				(width 0.1)
				(type default)
			)
			(layer "F.SilkS")
		)
		(fp_line
			(start 19.1897 -2.594864)
			(end 19.177762 -2.525522)
			(stroke
				(width 0.1)
				(type default)
			)
			(layer "F.SilkS")
		)
		(fp_line
			(start 19.1897 -2.594864)
			(end 19.177762 -2.525522)
			(stroke
				(width 0.1)
				(type default)
			)
			(layer "F.SilkS")
		)
		(fp_line
			(start 19.1897 -2.594864)
			(end 20.545806 -3.895344)
			(stroke
				(width 0.1)
				(type default)
			)
			(layer "F.SilkS")
		)
		(fp_line
			(start 19.1897 -2.594864)
			(end 20.545806 -3.895344)
			(stroke
				(width 0.1)
				(type default)
			)
			(layer "F.SilkS")
		)
		(fp_line
			(start 19.190462 -1.267968)
			(end 20.270216 -2.303526)
			(stroke
				(width 0.1)
				(type default)
			)
			(layer "F.SilkS")
		)
		(fp_line
			(start 19.190462 -1.267968)
			(end 20.270216 -2.303526)
			(stroke
				(width 0.1)
				(type default)
			)
			(layer "F.SilkS")
		)
		(fp_line
			(start 19.201892 -2.663952)
			(end 19.1897 -2.594864)
			(stroke
				(width 0.1)
				(type default)
			)
			(layer "F.SilkS")
		)
		(fp_line
			(start 19.201892 -2.663952)
			(end 19.1897 -2.594864)
			(stroke
				(width 0.1)
				(type default)
			)
			(layer "F.SilkS")
		)
		(fp_line
			(start 19.201892 -2.663952)
			(end 20.557744 -3.96494)
			(stroke
				(width 0.1)
				(type default)
			)
			(layer "F.SilkS")
		)
		(fp_line
			(start 19.201892 -2.663952)
			(end 20.557744 -3.96494)
			(stroke
				(width 0.1)
				(type default)
			)
			(layer "F.SilkS")
		)
		(fp_line
			(start 19.204686 -4.109466)
			(end 19.264884 -4.109466)
			(stroke
				(width 0.1)
				(type default)
			)
			(layer "F.SilkS")
		)
		(fp_line
			(start 19.204686 -4.109466)
			(end 19.264884 -4.109466)
			(stroke
				(width 0.1)
				(type default)
			)
			(layer "F.SilkS")
		)
		(fp_line
			(start 19.204686 -4.109466)
			(end 20.861782 -5.699252)
			(stroke
				(width 0.1)
				(type default)
			)
			(layer "F.SilkS")
		)
		(fp_line
			(start 19.204686 -4.109466)
			(end 20.861782 -5.699252)
			(stroke
				(width 0.1)
				(type default)
			)
			(layer "F.SilkS")
		)
		(fp_line
			(start 19.210782 -1.229868)
			(end 20.26285 -2.239264)
			(stroke
				(width 0.1)
				(type default)
			)
			(layer "F.SilkS")
		)
		(fp_line
			(start 19.210782 -1.229868)
			(end 20.26285 -2.239264)
			(stroke
				(width 0.1)
				(type default)
			)
			(layer "F.SilkS")
		)
		(fp_line
			(start 19.21383 -2.733548)
			(end 19.201892 -2.663952)
			(stroke
				(width 0.1)
				(type default)
			)
			(layer "F.SilkS")
		)
		(fp_line
			(start 19.21383 -2.733548)
			(end 19.201892 -2.663952)
			(stroke
				(width 0.1)
				(type default)
			)
			(layer "F.SilkS")
		)
		(fp_line
			(start 19.21383 -2.733548)
			(end 20.57019 -4.034282)
			(stroke
				(width 0.1)
				(type default)
			)
			(layer "F.SilkS")
		)
		(fp_line
			(start 19.21383 -2.733548)
			(end 20.57019 -4.034282)
			(stroke
				(width 0.1)
				(type default)
			)
			(layer "F.SilkS")
		)
		(fp_line
			(start 19.226276 -2.80289)
			(end 19.21383 -2.733548)
			(stroke
				(width 0.1)
				(type default)
			)
			(layer "F.SilkS")
		)
		(fp_line
			(start 19.226276 -2.80289)
			(end 19.21383 -2.733548)
			(stroke
				(width 0.1)
				(type default)
			)
			(layer "F.SilkS")
		)
		(fp_line
			(start 19.226276 -2.80289)
			(end 20.582382 -4.103878)
			(stroke
				(width 0.1)
				(type default)
			)
			(layer "F.SilkS")
		)
		(fp_line
			(start 19.226276 -2.80289)
			(end 20.582382 -4.103878)
			(stroke
				(width 0.1)
				(type default)
			)
			(layer "F.SilkS")
		)
		(fp_line
			(start 19.22907 -5.171694)
			(end 19.168872 -5.171694)
			(stroke
				(width 0.1)
				(type default)
			)
			(layer "F.SilkS")
		)
		(fp_line
			(start 19.22907 -5.171694)
			(end 19.168872 -5.171694)
			(stroke
				(width 0.1)
				(type default)
			)
			(layer "F.SilkS")
		)
		(fp_line
			(start 19.230848 -1.191514)
			(end 20.263358 -2.181606)
			(stroke
				(width 0.1)
				(type default)
			)
			(layer "F.SilkS")
		)
		(fp_line
			(start 19.230848 -1.191514)
			(end 20.263358 -2.181606)
			(stroke
				(width 0.1)
				(type default)
			)
			(layer "F.SilkS")
		)
		(fp_line
			(start 19.238468 -2.872232)
			(end 19.226276 -2.80289)
			(stroke
				(width 0.1)
				(type default)
			)
			(layer "F.SilkS")
		)
		(fp_line
			(start 19.238468 -2.872232)
			(end 19.226276 -2.80289)
			(stroke
				(width 0.1)
				(type default)
			)
			(layer "F.SilkS")
		)
		(fp_line
			(start 19.238468 -2.872232)
			(end 21.635466 -5.171694)
			(stroke
				(width 0.1)
				(type default)
			)
			(layer "F.SilkS")
		)
		(fp_line
			(start 19.238468 -2.872232)
			(end 21.635466 -5.171694)
			(stroke
				(width 0.1)
				(type default)
			)
			(layer "F.SilkS")
		)
		(fp_line
			(start 19.250406 -2.941574)
			(end 19.238468 -2.872232)
			(stroke
				(width 0.1)
				(type default)
			)
			(layer "F.SilkS")
		)
		(fp_line
			(start 19.250406 -2.941574)
			(end 19.238468 -2.872232)
			(stroke
				(width 0.1)
				(type default)
			)
			(layer "F.SilkS")
		)
		(fp_line
			(start 19.25193 -1.153922)
			(end 20.265136 -2.125726)
			(stroke
				(width 0.1)
				(type default)
			)
			(layer "F.SilkS")
		)
		(fp_line
			(start 19.25193 -1.153922)
			(end 20.265136 -2.125726)
			(stroke
				(width 0.1)
				(type default)
			)
			(layer "F.SilkS")
		)
		(fp_line
			(start 19.262852 -3.01117)
			(end 19.250406 -2.941574)
			(stroke
				(width 0.1)
				(type default)
			)
			(layer "F.SilkS")
		)
		(fp_line
			(start 19.262852 -3.01117)
			(end 19.250406 -2.941574)
			(stroke
				(width 0.1)
				(type default)
			)
			(layer "F.SilkS")
		)
		(fp_line
			(start 19.264884 -4.109466)
			(end 19.324828 -4.109466)
			(stroke
				(width 0.1)
				(type default)
			)
			(layer "F.SilkS")
		)
		(fp_line
			(start 19.264884 -4.109466)
			(end 19.324828 -4.109466)
			(stroke
				(width 0.1)
				(type default)
			)
			(layer "F.SilkS")
		)
		(fp_line
			(start 19.264884 -4.109466)
			(end 20.84959 -5.629656)
			(stroke
				(width 0.1)
				(type default)
			)
			(layer "F.SilkS")
		)
		(fp_line
			(start 19.264884 -4.109466)
			(end 20.84959 -5.629656)
			(stroke
				(width 0.1)
				(type default)
			)
			(layer "F.SilkS")
		)
		(fp_line
			(start 19.27479 -3.080512)
			(end 19.262852 -3.01117)
			(stroke
				(width 0.1)
				(type default)
			)
			(layer "F.SilkS")
		)
		(fp_line
			(start 19.27479 -3.080512)
			(end 19.262852 -3.01117)
			(stroke
				(width 0.1)
				(type default)
			)
			(layer "F.SilkS")
		)
		(fp_line
			(start 19.279616 -1.122934)
			(end 20.274534 -2.077212)
			(stroke
				(width 0.1)
				(type default)
			)
			(layer "F.SilkS")
		)
		(fp_line
			(start 19.279616 -1.122934)
			(end 20.274534 -2.077212)
			(stroke
				(width 0.1)
				(type default)
			)
			(layer "F.SilkS")
		)
		(fp_line
			(start 19.286982 -3.149854)
			(end 19.27479 -3.080512)
			(stroke
				(width 0.1)
				(type default)
			)
			(layer "F.SilkS")
		)
		(fp_line
			(start 19.286982 -3.149854)
			(end 19.27479 -3.080512)
			(stroke
				(width 0.1)
				(type default)
			)
			(layer "F.SilkS")
		)
		(fp_line
			(start 19.289014 -5.171694)
			(end 19.22907 -5.171694)
			(stroke
				(width 0.1)
				(type default)
			)
			(layer "F.SilkS")
		)
		(fp_line
			(start 19.289014 -5.171694)
			(end 19.22907 -5.171694)
			(stroke
				(width 0.1)
				(type default)
			)
			(layer "F.SilkS")
		)
		(fp_line
			(start 19.299428 -3.218942)
			(end 19.286982 -3.149854)
			(stroke
				(width 0.1)
				(type default)
			)
			(layer "F.SilkS")
		)
		(fp_line
			(start 19.299428 -3.218942)
			(end 19.286982 -3.149854)
			(stroke
				(width 0.1)
				(type default)
			)
			(layer "F.SilkS")
		)
		(fp_line
			(start 19.307556 -1.091946)
			(end 20.287488 -2.031746)
			(stroke
				(width 0.1)
				(type default)
			)
			(layer "F.SilkS")
		)
		(fp_line
			(start 19.307556 -1.091946)
			(end 20.287488 -2.031746)
			(stroke
				(width 0.1)
				(type default)
			)
			(layer "F.SilkS")
		)
		(fp_line
			(start 19.311366 -3.288538)
			(end 19.299428 -3.218942)
			(stroke
				(width 0.1)
				(type default)
			)
			(layer "F.SilkS")
		)
		(fp_line
			(start 19.311366 -3.288538)
			(end 19.299428 -3.218942)
			(stroke
				(width 0.1)
				(type default)
			)
			(layer "F.SilkS")
		)
		(fp_line
			(start 19.323558 -3.358134)
			(end 19.311366 -3.288538)
			(stroke
				(width 0.1)
				(type default)
			)
			(layer "F.SilkS")
		)
		(fp_line
			(start 19.323558 -3.358134)
			(end 19.311366 -3.288538)
			(stroke
				(width 0.1)
				(type default)
			)
			(layer "F.SilkS")
		)
		(fp_line
			(start 19.324828 -4.109466)
			(end 19.385026 -4.109466)
			(stroke
				(width 0.1)
				(type default)
			)
			(layer "F.SilkS")
		)
		(fp_line
			(start 19.324828 -4.109466)
			(end 19.385026 -4.109466)
			(stroke
				(width 0.1)
				(type default)
			)
			(layer "F.SilkS")
		)
		(fp_line
			(start 19.324828 -4.109466)
			(end 20.837144 -5.560314)
			(stroke
				(width 0.1)
				(type default)
			)
			(layer "F.SilkS")
		)
		(fp_line
			(start 19.324828 -4.109466)
			(end 20.837144 -5.560314)
			(stroke
				(width 0.1)
				(type default)
			)
			(layer "F.SilkS")
		)
		(fp_line
			(start 19.335496 -1.061212)
			(end 20.307046 -1.992884)
			(stroke
				(width 0.1)
				(type default)
			)
			(layer "F.SilkS")
		)
		(fp_line
			(start 19.335496 -1.061212)
			(end 20.307046 -1.992884)
			(stroke
				(width 0.1)
				(type default)
			)
			(layer "F.SilkS")
		)
		(fp_line
			(start 19.33575 -3.427476)
			(end 19.323558 -3.358134)
			(stroke
				(width 0.1)
				(type default)
			)
			(layer "F.SilkS")
		)
		(fp_line
			(start 19.33575 -3.427476)
			(end 19.323558 -3.358134)
			(stroke
				(width 0.1)
				(type default)
			)
			(layer "F.SilkS")
		)
		(fp_line
			(start 19.347942 -3.496564)
			(end 19.33575 -3.427476)
			(stroke
				(width 0.1)
				(type default)
			)
			(layer "F.SilkS")
		)
		(fp_line
			(start 19.347942 -3.496564)
			(end 19.33575 -3.427476)
			(stroke
				(width 0.1)
				(type default)
			)
			(layer "F.SilkS")
		)
		(fp_line
			(start 19.349212 -5.171694)
			(end 19.289014 -5.171694)
			(stroke
				(width 0.1)
				(type default)
			)
			(layer "F.SilkS")
		)
		(fp_line
			(start 19.349212 -5.171694)
			(end 19.289014 -5.171694)
			(stroke
				(width 0.1)
				(type default)
			)
			(layer "F.SilkS")
		)
		(fp_line
			(start 19.35988 -3.56616)
			(end 19.347942 -3.496564)
			(stroke
				(width 0.1)
				(type default)
			)
			(layer "F.SilkS")
		)
		(fp_line
			(start 19.35988 -3.56616)
			(end 19.347942 -3.496564)
			(stroke
				(width 0.1)
				(type default)
			)
			(layer "F.SilkS")
		)
		(fp_line
			(start 19.363436 -1.030224)
			(end 20.332446 -1.959356)
			(stroke
				(width 0.1)
				(type default)
			)
			(layer "F.SilkS")
		)
		(fp_line
			(start 19.363436 -1.030224)
			(end 20.332446 -1.959356)
			(stroke
				(width 0.1)
				(type default)
			)
			(layer "F.SilkS")
		)
		(fp_line
			(start 19.372326 -3.635502)
			(end 19.35988 -3.56616)
			(stroke
				(width 0.1)
				(type default)
			)
			(layer "F.SilkS")
		)
		(fp_line
			(start 19.372326 -3.635502)
			(end 19.35988 -3.56616)
			(stroke
				(width 0.1)
				(type default)
			)
			(layer "F.SilkS")
		)
		(fp_line
			(start 19.384518 -3.704844)
			(end 19.372326 -3.635502)
			(stroke
				(width 0.1)
				(type default)
			)
			(layer "F.SilkS")
		)
		(fp_line
			(start 19.384518 -3.704844)
			(end 19.372326 -3.635502)
			(stroke
				(width 0.1)
				(type default)
			)
			(layer "F.SilkS")
		)
		(fp_line
			(start 19.385026 -4.109466)
			(end 19.445478 -4.109466)
			(stroke
				(width 0.1)
				(type default)
			)
			(layer "F.SilkS")
		)
		(fp_line
			(start 19.385026 -4.109466)
			(end 19.445478 -4.109466)
			(stroke
				(width 0.1)
				(type default)
			)
			(layer "F.SilkS")
		)
		(fp_line
			(start 19.385026 -4.109466)
			(end 20.825206 -5.490972)
			(stroke
				(width 0.1)
				(type default)
			)
			(layer "F.SilkS")
		)
		(fp_line
			(start 19.385026 -4.109466)
			(end 20.825206 -5.490972)
			(stroke
				(width 0.1)
				(type default)
			)
			(layer "F.SilkS")
		)
		(fp_line
			(start 19.392646 -1.000252)
			(end 20.362164 -1.9304)
			(stroke
				(width 0.1)
				(type default)
			)
			(layer "F.SilkS")
		)
		(fp_line
			(start 19.392646 -1.000252)
			(end 20.362164 -1.9304)
			(stroke
				(width 0.1)
				(type default)
			)
			(layer "F.SilkS")
		)
		(fp_line
			(start 19.396456 -3.774186)
			(end 19.384518 -3.704844)
			(stroke
				(width 0.1)
				(type default)
			)
			(layer "F.SilkS")
		)
		(fp_line
			(start 19.396456 -3.774186)
			(end 19.384518 -3.704844)
			(stroke
				(width 0.1)
				(type default)
			)
			(layer "F.SilkS")
		)
		(fp_line
			(start 19.408902 -3.843528)
			(end 19.396456 -3.774186)
			(stroke
				(width 0.1)
				(type default)
			)
			(layer "F.SilkS")
		)
		(fp_line
			(start 19.408902 -3.843528)
			(end 19.396456 -3.774186)
			(stroke
				(width 0.1)
				(type default)
			)
			(layer "F.SilkS")
		)
		(fp_line
			(start 19.409664 -5.171694)
			(end 19.349212 -5.171694)
			(stroke
				(width 0.1)
				(type default)
			)
			(layer "F.SilkS")
		)
		(fp_line
			(start 19.409664 -5.171694)
			(end 19.349212 -5.171694)
			(stroke
				(width 0.1)
				(type default)
			)
			(layer "F.SilkS")
		)
		(fp_line
			(start 19.42084 -3.913124)
			(end 19.408902 -3.843528)
			(stroke
				(width 0.1)
				(type default)
			)
			(layer "F.SilkS")
		)
		(fp_line
			(start 19.42084 -3.913124)
			(end 19.408902 -3.843528)
			(stroke
				(width 0.1)
				(type default)
			)
			(layer "F.SilkS")
		)
		(fp_line
			(start 19.42084 -3.913124)
			(end 20.776184 -5.21335)
			(stroke
				(width 0.1)
				(type default)
			)
			(layer "F.SilkS")
		)
		(fp_line
			(start 19.42084 -3.913124)
			(end 20.776184 -5.21335)
			(stroke
				(width 0.1)
				(type default)
			)
			(layer "F.SilkS")
		)
		(fp_line
			(start 19.42846 -0.976884)
			(end 20.400772 -1.909572)
			(stroke
				(width 0.1)
				(type default)
			)
			(layer "F.SilkS")
		)
		(fp_line
			(start 19.42846 -0.976884)
			(end 20.400772 -1.909572)
			(stroke
				(width 0.1)
				(type default)
			)
			(layer "F.SilkS")
		)
		(fp_line
			(start 19.433032 -3.982466)
			(end 19.42084 -3.913124)
			(stroke
				(width 0.1)
				(type default)
			)
			(layer "F.SilkS")
		)
		(fp_line
			(start 19.433032 -3.982466)
			(end 19.42084 -3.913124)
			(stroke
				(width 0.1)
				(type default)
			)
			(layer "F.SilkS")
		)
		(fp_line
			(start 19.445478 -4.109466)
			(end 19.455384 -4.109466)
			(stroke
				(width 0.1)
				(type default)
			)
			(layer "F.SilkS")
		)
		(fp_line
			(start 19.445478 -4.109466)
			(end 19.455384 -4.109466)
			(stroke
				(width 0.1)
				(type default)
			)
			(layer "F.SilkS")
		)
		(fp_line
			(start 19.445478 -4.109466)
			(end 20.81276 -5.421376)
			(stroke
				(width 0.1)
				(type default)
			)
			(layer "F.SilkS")
		)
		(fp_line
			(start 19.445478 -4.109466)
			(end 20.81276 -5.421376)
			(stroke
				(width 0.1)
				(type default)
			)
			(layer "F.SilkS")
		)
		(fp_line
			(start 19.445478 -4.051554)
			(end 19.433032 -3.982466)
			(stroke
				(width 0.1)
				(type default)
			)
			(layer "F.SilkS")
		)
		(fp_line
			(start 19.445478 -4.051554)
			(end 19.433032 -3.982466)
			(stroke
				(width 0.1)
				(type default)
			)
			(layer "F.SilkS")
		)
		(fp_line
			(start 19.455384 -4.109466)
			(end 19.445478 -4.051554)
			(stroke
				(width 0.1)
				(type default)
			)
			(layer "F.SilkS")
		)
		(fp_line
			(start 19.455384 -4.109466)
			(end 19.445478 -4.051554)
			(stroke
				(width 0.1)
				(type default)
			)
			(layer "F.SilkS")
		)
		(fp_line
			(start 19.46402 -0.953516)
			(end 20.442428 -1.892046)
			(stroke
				(width 0.1)
				(type default)
			)
			(layer "F.SilkS")
		)
		(fp_line
			(start 19.46402 -0.953516)
			(end 20.442428 -1.892046)
			(stroke
				(width 0.1)
				(type default)
			)
			(layer "F.SilkS")
		)
		(fp_line
			(start 19.469608 -5.171694)
			(end 19.409664 -5.171694)
			(stroke
				(width 0.1)
				(type default)
			)
			(layer "F.SilkS")
		)
		(fp_line
			(start 19.469608 -5.171694)
			(end 19.409664 -5.171694)
			(stroke
				(width 0.1)
				(type default)
			)
			(layer "F.SilkS")
		)
		(fp_line
			(start 19.500088 -0.930148)
			(end 20.491704 -1.881378)
			(stroke
				(width 0.1)
				(type default)
			)
			(layer "F.SilkS")
		)
		(fp_line
			(start 19.500088 -0.930148)
			(end 20.491704 -1.881378)
			(stroke
				(width 0.1)
				(type default)
			)
			(layer "F.SilkS")
		)
		(fp_line
			(start 19.529806 -5.171694)
			(end 19.469608 -5.171694)
			(stroke
				(width 0.1)
				(type default)
			)
			(layer "F.SilkS")
		)
		(fp_line
			(start 19.529806 -5.171694)
			(end 19.469608 -5.171694)
			(stroke
				(width 0.1)
				(type default)
			)
			(layer "F.SilkS")
		)
		(fp_line
			(start 19.536156 -0.906526)
			(end 20.545044 -1.874774)
			(stroke
				(width 0.1)
				(type default)
			)
			(layer "F.SilkS")
		)
		(fp_line
			(start 19.536156 -0.906526)
			(end 20.545044 -1.874774)
			(stroke
				(width 0.1)
				(type default)
			)
			(layer "F.SilkS")
		)
		(fp_line
			(start 19.574002 -0.88519)
			(end 20.60194 -1.871726)
			(stroke
				(width 0.1)
				(type default)
			)
			(layer "F.SilkS")
		)
		(fp_line
			(start 19.574002 -0.88519)
			(end 20.60194 -1.871726)
			(stroke
				(width 0.1)
				(type default)
			)
			(layer "F.SilkS")
		)
		(fp_line
			(start 19.58975 -5.171694)
			(end 19.529806 -5.171694)
			(stroke
				(width 0.1)
				(type default)
			)
			(layer "F.SilkS")
		)
		(fp_line
			(start 19.58975 -5.171694)
			(end 19.529806 -5.171694)
			(stroke
				(width 0.1)
				(type default)
			)
			(layer "F.SilkS")
		)
		(fp_line
			(start 19.58975 -5.171694)
			(end 19.641566 -5.171694)
			(stroke
				(width 0.1)
				(type default)
			)
			(layer "F.SilkS")
		)
		(fp_line
			(start 19.58975 -5.171694)
			(end 19.641566 -5.171694)
			(stroke
				(width 0.1)
				(type default)
			)
			(layer "F.SilkS")
		)
		(fp_line
			(start 19.617944 -0.870458)
			(end 20.669504 -1.878838)
			(stroke
				(width 0.1)
				(type default)
			)
			(layer "F.SilkS")
		)
		(fp_line
			(start 19.617944 -0.870458)
			(end 20.669504 -1.878838)
			(stroke
				(width 0.1)
				(type default)
			)
			(layer "F.SilkS")
		)
		(fp_line
			(start 19.641566 -5.171694)
			(end 19.651726 -5.23113)
			(stroke
				(width 0.1)
				(type default)
			)
			(layer "F.SilkS")
		)
		(fp_line
			(start 19.641566 -5.171694)
			(end 19.651726 -5.23113)
			(stroke
				(width 0.1)
				(type default)
			)
			(layer "F.SilkS")
		)
		(fp_line
			(start 19.662902 -0.855218)
			(end 20.738084 -1.886966)
			(stroke
				(width 0.1)
				(type default)
			)
			(layer "F.SilkS")
		)
		(fp_line
			(start 19.662902 -0.855218)
			(end 20.738084 -1.886966)
			(stroke
				(width 0.1)
				(type default)
			)
			(layer "F.SilkS")
		)
		(fp_line
			(start 19.664172 -5.300472)
			(end 19.651726 -5.23113)
			(stroke
				(width 0.1)
				(type default)
			)
			(layer "F.SilkS")
		)
		(fp_line
			(start 19.664172 -5.300472)
			(end 19.651726 -5.23113)
			(stroke
				(width 0.1)
				(type default)
			)
			(layer "F.SilkS")
		)
		(fp_line
			(start 19.676364 -5.370068)
			(end 19.664172 -5.300472)
			(stroke
				(width 0.1)
				(type default)
			)
			(layer "F.SilkS")
		)
		(fp_line
			(start 19.676364 -5.370068)
			(end 19.664172 -5.300472)
			(stroke
				(width 0.1)
				(type default)
			)
			(layer "F.SilkS")
		)
		(fp_line
			(start 19.688302 -5.439156)
			(end 19.676364 -5.370068)
			(stroke
				(width 0.1)
				(type default)
			)
			(layer "F.SilkS")
		)
		(fp_line
			(start 19.688302 -5.439156)
			(end 19.676364 -5.370068)
			(stroke
				(width 0.1)
				(type default)
			)
			(layer "F.SilkS")
		)
		(fp_line
			(start 19.700748 -5.508752)
			(end 19.688302 -5.439156)
			(stroke
				(width 0.1)
				(type default)
			)
			(layer "F.SilkS")
		)
		(fp_line
			(start 19.700748 -5.508752)
			(end 19.688302 -5.439156)
			(stroke
				(width 0.1)
				(type default)
			)
			(layer "F.SilkS")
		)
		(fp_line
			(start 19.707352 -0.840486)
			(end 20.828 -1.915414)
			(stroke
				(width 0.1)
				(type default)
			)
			(layer "F.SilkS")
		)
		(fp_line
			(start 19.707352 -0.840486)
			(end 20.828 -1.915414)
			(stroke
				(width 0.1)
				(type default)
			)
			(layer "F.SilkS")
		)
		(fp_line
			(start 19.712686 -5.578094)
			(end 19.700748 -5.508752)
			(stroke
				(width 0.1)
				(type default)
			)
			(layer "F.SilkS")
		)
		(fp_line
			(start 19.712686 -5.578094)
			(end 19.700748 -5.508752)
			(stroke
				(width 0.1)
				(type default)
			)
			(layer "F.SilkS")
		)
		(fp_line
			(start 19.725132 -5.647436)
			(end 19.712686 -5.578094)
			(stroke
				(width 0.1)
				(type default)
			)
			(layer "F.SilkS")
		)
		(fp_line
			(start 19.725132 -5.647436)
			(end 19.712686 -5.578094)
			(stroke
				(width 0.1)
				(type default)
			)
			(layer "F.SilkS")
		)
		(fp_line
			(start 19.737324 -5.716778)
			(end 19.725132 -5.647436)
			(stroke
				(width 0.1)
				(type default)
			)
			(layer "F.SilkS")
		)
		(fp_line
			(start 19.737324 -5.716778)
			(end 19.725132 -5.647436)
			(stroke
				(width 0.1)
				(type default)
			)
			(layer "F.SilkS")
		)
		(fp_line
			(start 19.749262 -5.786374)
			(end 19.737324 -5.716778)
			(stroke
				(width 0.1)
				(type default)
			)
			(layer "F.SilkS")
		)
		(fp_line
			(start 19.749262 -5.786374)
			(end 19.737324 -5.716778)
			(stroke
				(width 0.1)
				(type default)
			)
			(layer "F.SilkS")
		)
		(fp_line
			(start 19.751802 -0.825246)
			(end 20.932902 -1.95834)
			(stroke
				(width 0.1)
				(type default)
			)
			(layer "F.SilkS")
		)
		(fp_line
			(start 19.751802 -0.825246)
			(end 20.932902 -1.95834)
			(stroke
				(width 0.1)
				(type default)
			)
			(layer "F.SilkS")
		)
		(fp_line
			(start 19.761708 -5.85597)
			(end 19.749262 -5.786374)
			(stroke
				(width 0.1)
				(type default)
			)
			(layer "F.SilkS")
		)
		(fp_line
			(start 19.761708 -5.85597)
			(end 19.749262 -5.786374)
			(stroke
				(width 0.1)
				(type default)
			)
			(layer "F.SilkS")
		)
		(fp_line
			(start 19.773646 -5.925058)
			(end 19.761708 -5.85597)
			(stroke
				(width 0.1)
				(type default)
			)
			(layer "F.SilkS")
		)
		(fp_line
			(start 19.773646 -5.925058)
			(end 19.761708 -5.85597)
			(stroke
				(width 0.1)
				(type default)
			)
			(layer "F.SilkS")
		)
		(fp_line
			(start 19.785838 -5.9944)
			(end 19.773646 -5.925058)
			(stroke
				(width 0.1)
				(type default)
			)
			(layer "F.SilkS")
		)
		(fp_line
			(start 19.785838 -5.9944)
			(end 19.773646 -5.925058)
			(stroke
				(width 0.1)
				(type default)
			)
			(layer "F.SilkS")
		)
		(fp_line
			(start 19.798284 -6.063996)
			(end 19.785838 -5.9944)
			(stroke
				(width 0.1)
				(type default)
			)
			(layer "F.SilkS")
		)
		(fp_line
			(start 19.798284 -6.063996)
			(end 19.785838 -5.9944)
			(stroke
				(width 0.1)
				(type default)
			)
			(layer "F.SilkS")
		)
		(fp_line
			(start 19.798284 -6.063996)
			(end 19.810222 -6.133338)
			(stroke
				(width 0.1)
				(type default)
			)
			(layer "F.SilkS")
		)
		(fp_line
			(start 19.798284 -6.063996)
			(end 19.810222 -6.133338)
			(stroke
				(width 0.1)
				(type default)
			)
			(layer "F.SilkS")
		)
		(fp_line
			(start 19.801078 -0.815086)
			(end 21.08327 -2.044954)
			(stroke
				(width 0.1)
				(type default)
			)
			(layer "F.SilkS")
		)
		(fp_line
			(start 19.801078 -0.815086)
			(end 21.08327 -2.044954)
			(stroke
				(width 0.1)
				(type default)
			)
			(layer "F.SilkS")
		)
		(fp_line
			(start 19.810222 -6.133338)
			(end 19.822668 -6.20268)
			(stroke
				(width 0.1)
				(type default)
			)
			(layer "F.SilkS")
		)
		(fp_line
			(start 19.810222 -6.133338)
			(end 19.822668 -6.20268)
			(stroke
				(width 0.1)
				(type default)
			)
			(layer "F.SilkS")
		)
		(fp_line
			(start 19.822668 -6.20268)
			(end 19.834606 -6.272022)
			(stroke
				(width 0.1)
				(type default)
			)
			(layer "F.SilkS")
		)
		(fp_line
			(start 19.822668 -6.20268)
			(end 19.834606 -6.272022)
			(stroke
				(width 0.1)
				(type default)
			)
			(layer "F.SilkS")
		)
		(fp_line
			(start 19.835114 -6.274308)
			(end 19.834606 -6.272022)
			(stroke
				(width 0.1)
				(type default)
			)
			(layer "F.SilkS")
		)
		(fp_line
			(start 19.835114 -6.274308)
			(end 19.834606 -6.272022)
			(stroke
				(width 0.1)
				(type default)
			)
			(layer "F.SilkS")
		)
		(fp_line
			(start 19.838924 -6.276086)
			(end 19.834606 -6.272022)
			(stroke
				(width 0.1)
				(type default)
			)
			(layer "F.SilkS")
		)
		(fp_line
			(start 19.838924 -6.276086)
			(end 19.834606 -6.272022)
			(stroke
				(width 0.1)
				(type default)
			)
			(layer "F.SilkS")
		)
		(fp_line
			(start 19.838924 -6.276086)
			(end 19.835114 -6.274308)
			(stroke
				(width 0.1)
				(type default)
			)
			(layer "F.SilkS")
		)
		(fp_line
			(start 19.838924 -6.276086)
			(end 19.835114 -6.274308)
			(stroke
				(width 0.1)
				(type default)
			)
			(layer "F.SilkS")
		)
		(fp_line
			(start 19.855434 -0.809498)
			(end 21.299932 -2.195068)
			(stroke
				(width 0.1)
				(type default)
			)
			(layer "F.SilkS")
		)
		(fp_line
			(start 19.855434 -0.809498)
			(end 21.299932 -2.195068)
			(stroke
				(width 0.1)
				(type default)
			)
			(layer "F.SilkS")
		)
		(fp_line
			(start 19.910044 -0.80391)
			(end 21.273516 -2.11201)
			(stroke
				(width 0.1)
				(type default)
			)
			(layer "F.SilkS")
		)
		(fp_line
			(start 19.910044 -0.80391)
			(end 21.273516 -2.11201)
			(stroke
				(width 0.1)
				(type default)
			)
			(layer "F.SilkS")
		)
		(fp_line
			(start 19.95424 -6.329172)
			(end 19.822668 -6.20268)
			(stroke
				(width 0.1)
				(type default)
			)
			(layer "F.SilkS")
		)
		(fp_line
			(start 19.95424 -6.329172)
			(end 19.822668 -6.20268)
			(stroke
				(width 0.1)
				(type default)
			)
			(layer "F.SilkS")
		)
		(fp_line
			(start 19.95424 -6.329172)
			(end 19.838924 -6.276086)
			(stroke
				(width 0.1)
				(type default)
			)
			(layer "F.SilkS")
		)
		(fp_line
			(start 19.95424 -6.329172)
			(end 19.838924 -6.276086)
			(stroke
				(width 0.1)
				(type default)
			)
			(layer "F.SilkS")
		)
		(fp_line
			(start 19.964654 -0.798576)
			(end 21.2471 -2.028952)
			(stroke
				(width 0.1)
				(type default)
			)
			(layer "F.SilkS")
		)
		(fp_line
			(start 19.964654 -0.798576)
			(end 21.2471 -2.028952)
			(stroke
				(width 0.1)
				(type default)
			)
			(layer "F.SilkS")
		)
		(fp_line
			(start 20.01901 -0.792988)
			(end 21.220684 -1.946148)
			(stroke
				(width 0.1)
				(type default)
			)
			(layer "F.SilkS")
		)
		(fp_line
			(start 20.01901 -0.792988)
			(end 21.220684 -1.946148)
			(stroke
				(width 0.1)
				(type default)
			)
			(layer "F.SilkS")
		)
		(fp_line
			(start 20.069302 -6.382004)
			(end 19.810222 -6.133338)
			(stroke
				(width 0.1)
				(type default)
			)
			(layer "F.SilkS")
		)
		(fp_line
			(start 20.069302 -6.382004)
			(end 19.810222 -6.133338)
			(stroke
				(width 0.1)
				(type default)
			)
			(layer "F.SilkS")
		)
		(fp_line
			(start 20.069302 -6.382004)
			(end 19.95424 -6.329172)
			(stroke
				(width 0.1)
				(type default)
			)
			(layer "F.SilkS")
		)
		(fp_line
			(start 20.069302 -6.382004)
			(end 19.95424 -6.329172)
			(stroke
				(width 0.1)
				(type default)
			)
			(layer "F.SilkS")
		)
		(fp_line
			(start 20.084542 -0.798576)
			(end 21.194268 -1.862836)
			(stroke
				(width 0.1)
				(type default)
			)
			(layer "F.SilkS")
		)
		(fp_line
			(start 20.084542 -0.798576)
			(end 21.194268 -1.862836)
			(stroke
				(width 0.1)
				(type default)
			)
			(layer "F.SilkS")
		)
		(fp_line
			(start 20.14982 -0.803402)
			(end 21.167852 -1.779778)
			(stroke
				(width 0.1)
				(type default)
			)
			(layer "F.SilkS")
		)
		(fp_line
			(start 20.14982 -0.803402)
			(end 21.167852 -1.779778)
			(stroke
				(width 0.1)
				(type default)
			)
			(layer "F.SilkS")
		)
		(fp_line
			(start 20.185126 -6.43509)
			(end 19.798284 -6.063996)
			(stroke
				(width 0.1)
				(type default)
			)
			(layer "F.SilkS")
		)
		(fp_line
			(start 20.185126 -6.43509)
			(end 19.798284 -6.063996)
			(stroke
				(width 0.1)
				(type default)
			)
			(layer "F.SilkS")
		)
		(fp_line
			(start 20.185126 -6.43509)
			(end 20.069302 -6.382004)
			(stroke
				(width 0.1)
				(type default)
			)
			(layer "F.SilkS")
		)
		(fp_line
			(start 20.185126 -6.43509)
			(end 20.069302 -6.382004)
			(stroke
				(width 0.1)
				(type default)
			)
			(layer "F.SilkS")
		)
		(fp_line
			(start 20.215352 -0.808228)
			(end 21.141436 -1.69672)
			(stroke
				(width 0.1)
				(type default)
			)
			(layer "F.SilkS")
		)
		(fp_line
			(start 20.215352 -0.808228)
			(end 21.141436 -1.69672)
			(stroke
				(width 0.1)
				(type default)
			)
			(layer "F.SilkS")
		)
		(fp_line
			(start 20.280884 -0.813562)
			(end 21.115274 -1.613916)
			(stroke
				(width 0.1)
				(type default)
			)
			(layer "F.SilkS")
		)
		(fp_line
			(start 20.280884 -0.813562)
			(end 21.115274 -1.613916)
			(stroke
				(width 0.1)
				(type default)
			)
			(layer "F.SilkS")
		)
		(fp_line
			(start 20.30095 -6.488176)
			(end 19.785838 -5.9944)
			(stroke
				(width 0.1)
				(type default)
			)
			(layer "F.SilkS")
		)
		(fp_line
			(start 20.30095 -6.488176)
			(end 19.785838 -5.9944)
			(stroke
				(width 0.1)
				(type default)
			)
			(layer "F.SilkS")
		)
		(fp_line
			(start 20.30095 -6.488176)
			(end 20.185126 -6.43509)
			(stroke
				(width 0.1)
				(type default)
			)
			(layer "F.SilkS")
		)
		(fp_line
			(start 20.30095 -6.488176)
			(end 20.185126 -6.43509)
			(stroke
				(width 0.1)
				(type default)
			)
			(layer "F.SilkS")
		)
		(fp_line
			(start 20.301966 -2.507234)
			(end 20.28952 -2.437892)
			(stroke
				(width 0.1)
				(type default)
			)
			(layer "F.SilkS")
		)
		(fp_line
			(start 20.301966 -2.507234)
			(end 20.28952 -2.437892)
			(stroke
				(width 0.1)
				(type default)
			)
			(layer "F.SilkS")
		)
		(fp_line
			(start 20.313904 -2.576576)
			(end 20.301966 -2.507234)
			(stroke
				(width 0.1)
				(type default)
			)
			(layer "F.SilkS")
		)
		(fp_line
			(start 20.313904 -2.576576)
			(end 20.301966 -2.507234)
			(stroke
				(width 0.1)
				(type default)
			)
			(layer "F.SilkS")
		)
		(fp_line
			(start 20.32635 -2.646172)
			(end 20.313904 -2.576576)
			(stroke
				(width 0.1)
				(type default)
			)
			(layer "F.SilkS")
		)
		(fp_line
			(start 20.32635 -2.646172)
			(end 20.313904 -2.576576)
			(stroke
				(width 0.1)
				(type default)
			)
			(layer "F.SilkS")
		)
		(fp_line
			(start 20.32635 -2.646172)
			(end 20.338288 -2.715768)
			(stroke
				(width 0.1)
				(type default)
			)
			(layer "F.SilkS")
		)
		(fp_line
			(start 20.32635 -2.646172)
			(end 20.338288 -2.715768)
			(stroke
				(width 0.1)
				(type default)
			)
			(layer "F.SilkS")
		)
		(fp_line
			(start 20.338288 -2.715768)
			(end 20.35048 -2.784856)
			(stroke
				(width 0.1)
				(type default)
			)
			(layer "F.SilkS")
		)
		(fp_line
			(start 20.338288 -2.715768)
			(end 20.35048 -2.784856)
			(stroke
				(width 0.1)
				(type default)
			)
			(layer "F.SilkS")
		)
		(fp_line
			(start 20.35048 -2.784856)
			(end 20.362926 -2.854198)
			(stroke
				(width 0.1)
				(type default)
			)
			(layer "F.SilkS")
		)
		(fp_line
			(start 20.35048 -2.784856)
			(end 20.362926 -2.854198)
			(stroke
				(width 0.1)
				(type default)
			)
			(layer "F.SilkS")
		)
		(fp_line
			(start 20.359116 -0.830834)
			(end 21.088858 -1.530604)
			(stroke
				(width 0.1)
				(type default)
			)
			(layer "F.SilkS")
		)
		(fp_line
			(start 20.359116 -0.830834)
			(end 21.088858 -1.530604)
			(stroke
				(width 0.1)
				(type default)
			)
			(layer "F.SilkS")
		)
		(fp_line
			(start 20.362926 -2.854198)
			(end 20.374864 -2.923794)
			(stroke
				(width 0.1)
				(type default)
			)
			(layer "F.SilkS")
		)
		(fp_line
			(start 20.362926 -2.854198)
			(end 20.374864 -2.923794)
			(stroke
				(width 0.1)
				(type default)
			)
			(layer "F.SilkS")
		)
		(fp_line
			(start 20.374864 -2.923794)
			(end 20.38731 -2.99339)
			(stroke
				(width 0.1)
				(type default)
			)
			(layer "F.SilkS")
		)
		(fp_line
			(start 20.374864 -2.923794)
			(end 20.38731 -2.99339)
			(stroke
				(width 0.1)
				(type default)
			)
			(layer "F.SilkS")
		)
		(fp_line
			(start 20.38731 -2.99339)
			(end 20.399248 -3.062478)
			(stroke
				(width 0.1)
				(type default)
			)
			(layer "F.SilkS")
		)
		(fp_line
			(start 20.38731 -2.99339)
			(end 20.399248 -3.062478)
			(stroke
				(width 0.1)
				(type default)
			)
			(layer "F.SilkS")
		)
		(fp_line
			(start 20.399248 -3.062478)
			(end 20.41144 -3.13182)
			(stroke
				(width 0.1)
				(type default)
			)
			(layer "F.SilkS")
		)
		(fp_line
			(start 20.399248 -3.062478)
			(end 20.41144 -3.13182)
			(stroke
				(width 0.1)
				(type default)
			)
			(layer "F.SilkS")
		)
		(fp_line
			(start 20.41144 -3.13182)
			(end 20.423886 -3.201416)
			(stroke
				(width 0.1)
				(type default)
			)
			(layer "F.SilkS")
		)
		(fp_line
			(start 20.41144 -3.13182)
			(end 20.423886 -3.201416)
			(stroke
				(width 0.1)
				(type default)
			)
			(layer "F.SilkS")
		)
		(fp_line
			(start 20.416012 -6.541262)
			(end 19.773646 -5.925058)
			(stroke
				(width 0.1)
				(type default)
			)
			(layer "F.SilkS")
		)
		(fp_line
			(start 20.416012 -6.541262)
			(end 19.773646 -5.925058)
			(stroke
				(width 0.1)
				(type default)
			)
			(layer "F.SilkS")
		)
		(fp_line
			(start 20.416012 -6.541262)
			(end 20.30095 -6.488176)
			(stroke
				(width 0.1)
				(type default)
			)
			(layer "F.SilkS")
		)
		(fp_line
			(start 20.416012 -6.541262)
			(end 20.30095 -6.488176)
			(stroke
				(width 0.1)
				(type default)
			)
			(layer "F.SilkS")
		)
		(fp_line
			(start 20.423886 -3.201416)
			(end 20.435824 -3.270758)
			(stroke
				(width 0.1)
				(type default)
			)
			(layer "F.SilkS")
		)
		(fp_line
			(start 20.423886 -3.201416)
			(end 20.435824 -3.270758)
			(stroke
				(width 0.1)
				(type default)
			)
			(layer "F.SilkS")
		)
		(fp_line
			(start 20.435824 -3.270758)
			(end 20.44827 -3.340354)
			(stroke
				(width 0.1)
				(type default)
			)
			(layer "F.SilkS")
		)
		(fp_line
			(start 20.435824 -3.270758)
			(end 20.44827 -3.340354)
			(stroke
				(width 0.1)
				(type default)
			)
			(layer "F.SilkS")
		)
		(fp_line
			(start 20.437602 -0.848106)
			(end 21.062188 -1.447546)
			(stroke
				(width 0.1)
				(type default)
			)
			(layer "F.SilkS")
		)
		(fp_line
			(start 20.437602 -0.848106)
			(end 21.062188 -1.447546)
			(stroke
				(width 0.1)
				(type default)
			)
			(layer "F.SilkS")
		)
		(fp_line
			(start 20.44827 -3.340354)
			(end 20.460462 -3.409442)
			(stroke
				(width 0.1)
				(type default)
			)
			(layer "F.SilkS")
		)
		(fp_line
			(start 20.44827 -3.340354)
			(end 20.460462 -3.409442)
			(stroke
				(width 0.1)
				(type default)
			)
			(layer "F.SilkS")
		)
		(fp_line
			(start 20.460462 -3.409442)
			(end 20.4724 -3.479038)
			(stroke
				(width 0.1)
				(type default)
			)
			(layer "F.SilkS")
		)
		(fp_line
			(start 20.460462 -3.409442)
			(end 20.4724 -3.479038)
			(stroke
				(width 0.1)
				(type default)
			)
			(layer "F.SilkS")
		)
		(fp_line
			(start 20.484846 -3.548634)
			(end 20.4724 -3.479038)
			(stroke
				(width 0.1)
				(type default)
			)
			(layer "F.SilkS")
		)
		(fp_line
			(start 20.484846 -3.548634)
			(end 20.4724 -3.479038)
			(stroke
				(width 0.1)
				(type default)
			)
			(layer "F.SilkS")
		)
		(fp_line
			(start 20.496784 -3.617976)
			(end 19.141186 -2.317242)
			(stroke
				(width 0.1)
				(type default)
			)
			(layer "F.SilkS")
		)
		(fp_line
			(start 20.496784 -3.617976)
			(end 19.141186 -2.317242)
			(stroke
				(width 0.1)
				(type default)
			)
			(layer "F.SilkS")
		)
		(fp_line
			(start 20.496784 -3.617976)
			(end 20.484846 -3.548634)
			(stroke
				(width 0.1)
				(type default)
			)
			(layer "F.SilkS")
		)
		(fp_line
			(start 20.496784 -3.617976)
			(end 20.484846 -3.548634)
			(stroke
				(width 0.1)
				(type default)
			)
			(layer "F.SilkS")
		)
		(fp_line
			(start 20.496784 -3.617976)
			(end 20.50923 -3.687064)
			(stroke
				(width 0.1)
				(type default)
			)
			(layer "F.SilkS")
		)
		(fp_line
			(start 20.496784 -3.617976)
			(end 20.50923 -3.687064)
			(stroke
				(width 0.1)
				(type default)
			)
			(layer "F.SilkS")
		)
		(fp_line
			(start 20.50923 -3.687064)
			(end 20.521422 -3.75666)
			(stroke
				(width 0.1)
				(type default)
			)
			(layer "F.SilkS")
		)
		(fp_line
			(start 20.50923 -3.687064)
			(end 20.521422 -3.75666)
			(stroke
				(width 0.1)
				(type default)
			)
			(layer "F.SilkS")
		)
		(fp_line
			(start 20.515834 -0.865632)
			(end 21.035772 -1.364742)
			(stroke
				(width 0.1)
				(type default)
			)
			(layer "F.SilkS")
		)
		(fp_line
			(start 20.515834 -0.865632)
			(end 21.035772 -1.364742)
			(stroke
				(width 0.1)
				(type default)
			)
			(layer "F.SilkS")
		)
		(fp_line
			(start 20.521422 -3.75666)
			(end 20.533614 -3.826256)
			(stroke
				(width 0.1)
				(type default)
			)
			(layer "F.SilkS")
		)
		(fp_line
			(start 20.521422 -3.75666)
			(end 20.533614 -3.826256)
			(stroke
				(width 0.1)
				(type default)
			)
			(layer "F.SilkS")
		)
		(fp_line
			(start 20.531328 -6.594348)
			(end 19.761708 -5.85597)
			(stroke
				(width 0.1)
				(type default)
			)
			(layer "F.SilkS")
		)
		(fp_line
			(start 20.531328 -6.594348)
			(end 19.761708 -5.85597)
			(stroke
				(width 0.1)
				(type default)
			)
			(layer "F.SilkS")
		)
		(fp_line
			(start 20.531328 -6.594348)
			(end 20.416012 -6.541262)
			(stroke
				(width 0.1)
				(type default)
			)
			(layer "F.SilkS")
		)
		(fp_line
			(start 20.531328 -6.594348)
			(end 20.416012 -6.541262)
			(stroke
				(width 0.1)
				(type default)
			)
			(layer "F.SilkS")
		)
		(fp_line
			(start 20.533614 -3.826256)
			(end 20.545806 -3.895344)
			(stroke
				(width 0.1)
				(type default)
			)
			(layer "F.SilkS")
		)
		(fp_line
			(start 20.533614 -3.826256)
			(end 20.545806 -3.895344)
			(stroke
				(width 0.1)
				(type default)
			)
			(layer "F.SilkS")
		)
		(fp_line
			(start 20.545806 -3.895344)
			(end 20.557744 -3.96494)
			(stroke
				(width 0.1)
				(type default)
			)
			(layer "F.SilkS")
		)
		(fp_line
			(start 20.545806 -3.895344)
			(end 20.557744 -3.96494)
			(stroke
				(width 0.1)
				(type default)
			)
			(layer "F.SilkS")
		)
		(fp_line
			(start 20.557744 -3.96494)
			(end 20.57019 -4.034282)
			(stroke
				(width 0.1)
				(type default)
			)
			(layer "F.SilkS")
		)
		(fp_line
			(start 20.557744 -3.96494)
			(end 20.57019 -4.034282)
			(stroke
				(width 0.1)
				(type default)
			)
			(layer "F.SilkS")
		)
		(fp_line
			(start 20.57019 -4.034282)
			(end 20.582382 -4.103878)
			(stroke
				(width 0.1)
				(type default)
			)
			(layer "F.SilkS")
		)
		(fp_line
			(start 20.57019 -4.034282)
			(end 20.582382 -4.103878)
			(stroke
				(width 0.1)
				(type default)
			)
			(layer "F.SilkS")
		)
		(fp_line
			(start 20.582382 -4.103878)
			(end 20.583398 -4.109466)
			(stroke
				(width 0.1)
				(type default)
			)
			(layer "F.SilkS")
		)
		(fp_line
			(start 20.582382 -4.103878)
			(end 20.583398 -4.109466)
			(stroke
				(width 0.1)
				(type default)
			)
			(layer "F.SilkS")
		)
		(fp_line
			(start 20.582382 -4.103878)
			(end 20.588224 -4.109466)
			(stroke
				(width 0.1)
				(type default)
			)
			(layer "F.SilkS")
		)
		(fp_line
			(start 20.582382 -4.103878)
			(end 20.588224 -4.109466)
			(stroke
				(width 0.1)
				(type default)
			)
			(layer "F.SilkS")
		)
		(fp_line
			(start 20.583398 -4.109466)
			(end 20.588224 -4.109466)
			(stroke
				(width 0.1)
				(type default)
			)
			(layer "F.SilkS")
		)
		(fp_line
			(start 20.583398 -4.109466)
			(end 20.588224 -4.109466)
			(stroke
				(width 0.1)
				(type default)
			)
			(layer "F.SilkS")
		)
		(fp_line
			(start 20.610322 -0.898652)
			(end 21.00961 -1.281684)
			(stroke
				(width 0.1)
				(type default)
			)
			(layer "F.SilkS")
		)
		(fp_line
			(start 20.610322 -0.898652)
			(end 21.00961 -1.281684)
			(stroke
				(width 0.1)
				(type default)
			)
			(layer "F.SilkS")
		)
		(fp_line
			(start 20.647152 -6.647434)
			(end 19.749262 -5.786374)
			(stroke
				(width 0.1)
				(type default)
			)
			(layer "F.SilkS")
		)
		(fp_line
			(start 20.647152 -6.647434)
			(end 19.749262 -5.786374)
			(stroke
				(width 0.1)
				(type default)
			)
			(layer "F.SilkS")
		)
		(fp_line
			(start 20.647152 -6.647434)
			(end 20.531328 -6.594348)
			(stroke
				(width 0.1)
				(type default)
			)
			(layer "F.SilkS")
		)
		(fp_line
			(start 20.647152 -6.647434)
			(end 20.531328 -6.594348)
			(stroke
				(width 0.1)
				(type default)
			)
			(layer "F.SilkS")
		)
		(fp_line
			(start 20.648422 -4.109466)
			(end 20.588224 -4.109466)
			(stroke
				(width 0.1)
				(type default)
			)
			(layer "F.SilkS")
		)
		(fp_line
			(start 20.648422 -4.109466)
			(end 20.588224 -4.109466)
			(stroke
				(width 0.1)
				(type default)
			)
			(layer "F.SilkS")
		)
		(fp_line
			(start 20.708366 -0.934974)
			(end 20.98294 -1.198626)
			(stroke
				(width 0.1)
				(type default)
			)
			(layer "F.SilkS")
		)
		(fp_line
			(start 20.708366 -0.934974)
			(end 20.98294 -1.198626)
			(stroke
				(width 0.1)
				(type default)
			)
			(layer "F.SilkS")
		)
		(fp_line
			(start 20.70862 -4.109466)
			(end 20.648422 -4.109466)
			(stroke
				(width 0.1)
				(type default)
			)
			(layer "F.SilkS")
		)
		(fp_line
			(start 20.70862 -4.109466)
			(end 20.648422 -4.109466)
			(stroke
				(width 0.1)
				(type default)
			)
			(layer "F.SilkS")
		)
		(fp_line
			(start 20.762722 -6.70052)
			(end 19.737324 -5.716778)
			(stroke
				(width 0.1)
				(type default)
			)
			(layer "F.SilkS")
		)
		(fp_line
			(start 20.762722 -6.70052)
			(end 19.737324 -5.716778)
			(stroke
				(width 0.1)
				(type default)
			)
			(layer "F.SilkS")
		)
		(fp_line
			(start 20.762722 -6.70052)
			(end 20.647152 -6.647434)
			(stroke
				(width 0.1)
				(type default)
			)
			(layer "F.SilkS")
		)
		(fp_line
			(start 20.762722 -6.70052)
			(end 20.647152 -6.647434)
			(stroke
				(width 0.1)
				(type default)
			)
			(layer "F.SilkS")
		)
		(fp_line
			(start 20.768564 -4.109466)
			(end 20.70862 -4.109466)
			(stroke
				(width 0.1)
				(type default)
			)
			(layer "F.SilkS")
		)
		(fp_line
			(start 20.768564 -4.109466)
			(end 20.70862 -4.109466)
			(stroke
				(width 0.1)
				(type default)
			)
			(layer "F.SilkS")
		)
		(fp_line
			(start 20.769072 -5.171694)
			(end 20.793202 -5.171694)
			(stroke
				(width 0.1)
				(type default)
			)
			(layer "F.SilkS")
		)
		(fp_line
			(start 20.769072 -5.171694)
			(end 20.793202 -5.171694)
			(stroke
				(width 0.1)
				(type default)
			)
			(layer "F.SilkS")
		)
		(fp_line
			(start 20.776184 -5.21335)
			(end 20.769072 -5.171694)
			(stroke
				(width 0.1)
				(type default)
			)
			(layer "F.SilkS")
		)
		(fp_line
			(start 20.776184 -5.21335)
			(end 20.769072 -5.171694)
			(stroke
				(width 0.1)
				(type default)
			)
			(layer "F.SilkS")
		)
		(fp_line
			(start 20.776184 -5.21335)
			(end 20.78863 -5.282692)
			(stroke
				(width 0.1)
				(type default)
			)
			(layer "F.SilkS")
		)
		(fp_line
			(start 20.776184 -5.21335)
			(end 20.78863 -5.282692)
			(stroke
				(width 0.1)
				(type default)
			)
			(layer "F.SilkS")
		)
		(fp_line
			(start 20.78863 -5.282692)
			(end 19.433032 -3.982466)
			(stroke
				(width 0.1)
				(type default)
			)
			(layer "F.SilkS")
		)
		(fp_line
			(start 20.78863 -5.282692)
			(end 19.433032 -3.982466)
			(stroke
				(width 0.1)
				(type default)
			)
			(layer "F.SilkS")
		)
		(fp_line
			(start 20.78863 -5.282692)
			(end 20.800822 -5.352034)
			(stroke
				(width 0.1)
				(type default)
			)
			(layer "F.SilkS")
		)
		(fp_line
			(start 20.78863 -5.282692)
			(end 20.800822 -5.352034)
			(stroke
				(width 0.1)
				(type default)
			)
			(layer "F.SilkS")
		)
		(fp_line
			(start 20.793202 -5.171694)
			(end 19.408902 -3.843528)
			(stroke
				(width 0.1)
				(type default)
			)
			(layer "F.SilkS")
		)
		(fp_line
			(start 20.793202 -5.171694)
			(end 19.408902 -3.843528)
			(stroke
				(width 0.1)
				(type default)
			)
			(layer "F.SilkS")
		)
		(fp_line
			(start 20.800822 -5.352034)
			(end 19.445478 -4.051554)
			(stroke
				(width 0.1)
				(type default)
			)
			(layer "F.SilkS")
		)
		(fp_line
			(start 20.800822 -5.352034)
			(end 19.445478 -4.051554)
			(stroke
				(width 0.1)
				(type default)
			)
			(layer "F.SilkS")
		)
		(fp_line
			(start 20.800822 -5.352034)
			(end 20.81276 -5.421376)
			(stroke
				(width 0.1)
				(type default)
			)
			(layer "F.SilkS")
		)
		(fp_line
			(start 20.800822 -5.352034)
			(end 20.81276 -5.421376)
			(stroke
				(width 0.1)
				(type default)
			)
			(layer "F.SilkS")
		)
		(fp_line
			(start 20.81276 -5.421376)
			(end 20.825206 -5.490972)
			(stroke
				(width 0.1)
				(type default)
			)
			(layer "F.SilkS")
		)
		(fp_line
			(start 20.81276 -5.421376)
			(end 20.825206 -5.490972)
			(stroke
				(width 0.1)
				(type default)
			)
			(layer "F.SilkS")
		)
		(fp_line
			(start 20.825206 -5.490972)
			(end 20.837144 -5.560314)
			(stroke
				(width 0.1)
				(type default)
			)
			(layer "F.SilkS")
		)
		(fp_line
			(start 20.825206 -5.490972)
			(end 20.837144 -5.560314)
			(stroke
				(width 0.1)
				(type default)
			)
			(layer "F.SilkS")
		)
		(fp_line
			(start 20.829016 -4.109466)
			(end 20.768564 -4.109466)
			(stroke
				(width 0.1)
				(type default)
			)
			(layer "F.SilkS")
		)
		(fp_line
			(start 20.829016 -4.109466)
			(end 20.768564 -4.109466)
			(stroke
				(width 0.1)
				(type default)
			)
			(layer "F.SilkS")
		)
		(fp_line
			(start 20.831302 -0.995426)
			(end 20.956524 -1.115314)
			(stroke
				(width 0.1)
				(type default)
			)
			(layer "F.SilkS")
		)
		(fp_line
			(start 20.831302 -0.995426)
			(end 20.956524 -1.115314)
			(stroke
				(width 0.1)
				(type default)
			)
			(layer "F.SilkS")
		)
		(fp_line
			(start 20.837144 -5.560314)
			(end 20.84959 -5.629656)
			(stroke
				(width 0.1)
				(type default)
			)
			(layer "F.SilkS")
		)
		(fp_line
			(start 20.837144 -5.560314)
			(end 20.84959 -5.629656)
			(stroke
				(width 0.1)
				(type default)
			)
			(layer "F.SilkS")
		)
		(fp_line
			(start 20.84959 -5.629656)
			(end 20.861782 -5.699252)
			(stroke
				(width 0.1)
				(type default)
			)
			(layer "F.SilkS")
		)
		(fp_line
			(start 20.84959 -5.629656)
			(end 20.861782 -5.699252)
			(stroke
				(width 0.1)
				(type default)
			)
			(layer "F.SilkS")
		)
		(fp_line
			(start 20.8534 -5.171694)
			(end 19.396456 -3.774186)
			(stroke
				(width 0.1)
				(type default)
			)
			(layer "F.SilkS")
		)
		(fp_line
			(start 20.8534 -5.171694)
			(end 19.396456 -3.774186)
			(stroke
				(width 0.1)
				(type default)
			)
			(layer "F.SilkS")
		)
		(fp_line
			(start 20.8534 -5.171694)
			(end 20.793202 -5.171694)
			(stroke
				(width 0.1)
				(type default)
			)
			(layer "F.SilkS")
		)
		(fp_line
			(start 20.8534 -5.171694)
			(end 20.793202 -5.171694)
			(stroke
				(width 0.1)
				(type default)
			)
			(layer "F.SilkS")
		)
		(fp_line
			(start 20.861782 -5.699252)
			(end 20.874228 -5.768594)
			(stroke
				(width 0.1)
				(type default)
			)
			(layer "F.SilkS")
		)
		(fp_line
			(start 20.861782 -5.699252)
			(end 20.874228 -5.768594)
			(stroke
				(width 0.1)
				(type default)
			)
			(layer "F.SilkS")
		)
		(fp_line
			(start 20.874228 -5.768594)
			(end 20.886166 -5.837936)
			(stroke
				(width 0.1)
				(type default)
			)
			(layer "F.SilkS")
		)
		(fp_line
			(start 20.874228 -5.768594)
			(end 20.886166 -5.837936)
			(stroke
				(width 0.1)
				(type default)
			)
			(layer "F.SilkS")
		)
		(fp_line
			(start 20.877784 -6.753606)
			(end 19.725132 -5.647436)
			(stroke
				(width 0.1)
				(type default)
			)
			(layer "F.SilkS")
		)
		(fp_line
			(start 20.877784 -6.753606)
			(end 19.725132 -5.647436)
			(stroke
				(width 0.1)
				(type default)
			)
			(layer "F.SilkS")
		)
		(fp_line
			(start 20.877784 -6.753606)
			(end 20.762722 -6.70052)
			(stroke
				(width 0.1)
				(type default)
			)
			(layer "F.SilkS")
		)
		(fp_line
			(start 20.877784 -6.753606)
			(end 20.762722 -6.70052)
			(stroke
				(width 0.1)
				(type default)
			)
			(layer "F.SilkS")
		)
		(fp_line
			(start 20.886166 -5.837936)
			(end 20.898104 -5.907278)
			(stroke
				(width 0.1)
				(type default)
			)
			(layer "F.SilkS")
		)
		(fp_line
			(start 20.886166 -5.837936)
			(end 20.898104 -5.907278)
			(stroke
				(width 0.1)
				(type default)
			)
			(layer "F.SilkS")
		)
		(fp_line
			(start 20.889214 -4.109466)
			(end 20.829016 -4.109466)
			(stroke
				(width 0.1)
				(type default)
			)
			(layer "F.SilkS")
		)
		(fp_line
			(start 20.889214 -4.109466)
			(end 20.829016 -4.109466)
			(stroke
				(width 0.1)
				(type default)
			)
			(layer "F.SilkS")
		)
		(fp_line
			(start 20.898104 -5.907278)
			(end 20.91055 -5.976874)
			(stroke
				(width 0.1)
				(type default)
			)
			(layer "F.SilkS")
		)
		(fp_line
			(start 20.898104 -5.907278)
			(end 20.91055 -5.976874)
			(stroke
				(width 0.1)
				(type default)
			)
			(layer "F.SilkS")
		)
		(fp_line
			(start 20.91055 -5.976874)
			(end 20.922742 -6.04647)
			(stroke
				(width 0.1)
				(type default)
			)
			(layer "F.SilkS")
		)
		(fp_line
			(start 20.91055 -5.976874)
			(end 20.922742 -6.04647)
			(stroke
				(width 0.1)
				(type default)
			)
			(layer "F.SilkS")
		)
		(fp_line
			(start 20.913344 -5.171694)
			(end 19.384518 -3.704844)
			(stroke
				(width 0.1)
				(type default)
			)
			(layer "F.SilkS")
		)
		(fp_line
			(start 20.913344 -5.171694)
			(end 19.384518 -3.704844)
			(stroke
				(width 0.1)
				(type default)
			)
			(layer "F.SilkS")
		)
		(fp_line
			(start 20.913344 -5.171694)
			(end 20.8534 -5.171694)
			(stroke
				(width 0.1)
				(type default)
			)
			(layer "F.SilkS")
		)
		(fp_line
			(start 20.913344 -5.171694)
			(end 20.8534 -5.171694)
			(stroke
				(width 0.1)
				(type default)
			)
			(layer "F.SilkS")
		)
		(fp_line
			(start 20.922742 -6.04647)
			(end 20.93468 -6.115558)
			(stroke
				(width 0.1)
				(type default)
			)
			(layer "F.SilkS")
		)
		(fp_line
			(start 20.922742 -6.04647)
			(end 20.93468 -6.115558)
			(stroke
				(width 0.1)
				(type default)
			)
			(layer "F.SilkS")
		)
		(fp_line
			(start 20.93468 -6.115558)
			(end 20.947126 -6.1849)
			(stroke
				(width 0.1)
				(type default)
			)
			(layer "F.SilkS")
		)
		(fp_line
			(start 20.93468 -6.115558)
			(end 20.947126 -6.1849)
			(stroke
				(width 0.1)
				(type default)
			)
			(layer "F.SilkS")
		)
		(fp_line
			(start 20.947126 -6.1849)
			(end 20.959318 -6.254496)
			(stroke
				(width 0.1)
				(type default)
			)
			(layer "F.SilkS")
		)
		(fp_line
			(start 20.947126 -6.1849)
			(end 20.959318 -6.254496)
			(stroke
				(width 0.1)
				(type default)
			)
			(layer "F.SilkS")
		)
		(fp_line
			(start 20.949666 -4.109466)
			(end 20.889214 -4.109466)
			(stroke
				(width 0.1)
				(type default)
			)
			(layer "F.SilkS")
		)
		(fp_line
			(start 20.949666 -4.109466)
			(end 20.889214 -4.109466)
			(stroke
				(width 0.1)
				(type default)
			)
			(layer "F.SilkS")
		)
		(fp_line
			(start 20.959318 -6.254496)
			(end 20.97151 -6.324092)
			(stroke
				(width 0.1)
				(type default)
			)
			(layer "F.SilkS")
		)
		(fp_line
			(start 20.959318 -6.254496)
			(end 20.97151 -6.324092)
			(stroke
				(width 0.1)
				(type default)
			)
			(layer "F.SilkS")
		)
		(fp_line
			(start 20.97151 -6.324092)
			(end 18.75155 -4.194556)
			(stroke
				(width 0.1)
				(type default)
			)
			(layer "F.SilkS")
		)
		(fp_line
			(start 20.97151 -6.324092)
			(end 18.75155 -4.194556)
			(stroke
				(width 0.1)
				(type default)
			)
			(layer "F.SilkS")
		)
		(fp_line
			(start 20.97151 -6.324092)
			(end 20.983702 -6.393434)
			(stroke
				(width 0.1)
				(type default)
			)
			(layer "F.SilkS")
		)
		(fp_line
			(start 20.97151 -6.324092)
			(end 20.983702 -6.393434)
			(stroke
				(width 0.1)
				(type default)
			)
			(layer "F.SilkS")
		)
		(fp_line
			(start 20.973542 -5.171694)
			(end 19.372326 -3.635502)
			(stroke
				(width 0.1)
				(type default)
			)
			(layer "F.SilkS")
		)
		(fp_line
			(start 20.973542 -5.171694)
			(end 19.372326 -3.635502)
			(stroke
				(width 0.1)
				(type default)
			)
			(layer "F.SilkS")
		)
		(fp_line
			(start 20.973542 -5.171694)
			(end 20.913344 -5.171694)
			(stroke
				(width 0.1)
				(type default)
			)
			(layer "F.SilkS")
		)
		(fp_line
			(start 20.973542 -5.171694)
			(end 20.913344 -5.171694)
			(stroke
				(width 0.1)
				(type default)
			)
			(layer "F.SilkS")
		)
		(fp_line
			(start 20.98294 -1.198626)
			(end 20.956524 -1.115314)
			(stroke
				(width 0.1)
				(type default)
			)
			(layer "F.SilkS")
		)
		(fp_line
			(start 20.98294 -1.198626)
			(end 20.956524 -1.115314)
			(stroke
				(width 0.1)
				(type default)
			)
			(layer "F.SilkS")
		)
		(fp_line
			(start 20.983702 -6.393434)
			(end 18.763996 -4.263898)
			(stroke
				(width 0.1)
				(type default)
			)
			(layer "F.SilkS")
		)
		(fp_line
			(start 20.983702 -6.393434)
			(end 18.763996 -4.263898)
			(stroke
				(width 0.1)
				(type default)
			)
			(layer "F.SilkS")
		)
		(fp_line
			(start 20.983702 -6.393434)
			(end 20.996148 -6.462522)
			(stroke
				(width 0.1)
				(type default)
			)
			(layer "F.SilkS")
		)
		(fp_line
			(start 20.983702 -6.393434)
			(end 20.996148 -6.462522)
			(stroke
				(width 0.1)
				(type default)
			)
			(layer "F.SilkS")
		)
		(fp_line
			(start 20.993354 -6.806438)
			(end 19.712686 -5.578094)
			(stroke
				(width 0.1)
				(type default)
			)
			(layer "F.SilkS")
		)
		(fp_line
			(start 20.993354 -6.806438)
			(end 19.712686 -5.578094)
			(stroke
				(width 0.1)
				(type default)
			)
			(layer "F.SilkS")
		)
		(fp_line
			(start 20.993354 -6.806438)
			(end 20.877784 -6.753606)
			(stroke
				(width 0.1)
				(type default)
			)
			(layer "F.SilkS")
		)
		(fp_line
			(start 20.993354 -6.806438)
			(end 20.877784 -6.753606)
			(stroke
				(width 0.1)
				(type default)
			)
			(layer "F.SilkS")
		)
		(fp_line
			(start 20.996148 -6.462522)
			(end 18.775934 -4.33324)
			(stroke
				(width 0.1)
				(type default)
			)
			(layer "F.SilkS")
		)
		(fp_line
			(start 20.996148 -6.462522)
			(end 18.775934 -4.33324)
			(stroke
				(width 0.1)
				(type default)
			)
			(layer "F.SilkS")
		)
		(fp_line
			(start 20.996148 -6.462522)
			(end 21.008086 -6.532118)
			(stroke
				(width 0.1)
				(type default)
			)
			(layer "F.SilkS")
		)
		(fp_line
			(start 20.996148 -6.462522)
			(end 21.008086 -6.532118)
			(stroke
				(width 0.1)
				(type default)
			)
			(layer "F.SilkS")
		)
		(fp_line
			(start 21.008086 -6.532118)
			(end 19.651726 -5.23113)
			(stroke
				(width 0.1)
				(type default)
			)
			(layer "F.SilkS")
		)
		(fp_line
			(start 21.008086 -6.532118)
			(end 19.651726 -5.23113)
			(stroke
				(width 0.1)
				(type default)
			)
			(layer "F.SilkS")
		)
		(fp_line
			(start 21.008086 -6.532118)
			(end 21.020278 -6.60146)
			(stroke
				(width 0.1)
				(type default)
			)
			(layer "F.SilkS")
		)
		(fp_line
			(start 21.008086 -6.532118)
			(end 21.020278 -6.60146)
			(stroke
				(width 0.1)
				(type default)
			)
			(layer "F.SilkS")
		)
		(fp_line
			(start 21.00961 -4.109466)
			(end 20.949666 -4.109466)
			(stroke
				(width 0.1)
				(type default)
			)
			(layer "F.SilkS")
		)
		(fp_line
			(start 21.00961 -4.109466)
			(end 20.949666 -4.109466)
			(stroke
				(width 0.1)
				(type default)
			)
			(layer "F.SilkS")
		)
		(fp_line
			(start 21.00961 -4.109466)
			(end 21.069554 -4.109466)
			(stroke
				(width 0.1)
				(type default)
			)
			(layer "F.SilkS")
		)
		(fp_line
			(start 21.00961 -4.109466)
			(end 21.069554 -4.109466)
			(stroke
				(width 0.1)
				(type default)
			)
			(layer "F.SilkS")
		)
		(fp_line
			(start 21.00961 -1.281684)
			(end 20.98294 -1.198626)
			(stroke
				(width 0.1)
				(type default)
			)
			(layer "F.SilkS")
		)
		(fp_line
			(start 21.00961 -1.281684)
			(end 20.98294 -1.198626)
			(stroke
				(width 0.1)
				(type default)
			)
			(layer "F.SilkS")
		)
		(fp_line
			(start 21.020278 -6.60146)
			(end 19.664172 -5.300472)
			(stroke
				(width 0.1)
				(type default)
			)
			(layer "F.SilkS")
		)
		(fp_line
			(start 21.020278 -6.60146)
			(end 19.664172 -5.300472)
			(stroke
				(width 0.1)
				(type default)
			)
			(layer "F.SilkS")
		)
		(fp_line
			(start 21.020278 -6.60146)
			(end 21.03247 -6.671056)
			(stroke
				(width 0.1)
				(type default)
			)
			(layer "F.SilkS")
		)
		(fp_line
			(start 21.020278 -6.60146)
			(end 21.03247 -6.671056)
			(stroke
				(width 0.1)
				(type default)
			)
			(layer "F.SilkS")
		)
		(fp_line
			(start 21.03247 -6.671056)
			(end 19.676364 -5.370068)
			(stroke
				(width 0.1)
				(type default)
			)
			(layer "F.SilkS")
		)
		(fp_line
			(start 21.03247 -6.671056)
			(end 19.676364 -5.370068)
			(stroke
				(width 0.1)
				(type default)
			)
			(layer "F.SilkS")
		)
		(fp_line
			(start 21.03247 -6.671056)
			(end 21.044662 -6.740144)
			(stroke
				(width 0.1)
				(type default)
			)
			(layer "F.SilkS")
		)
		(fp_line
			(start 21.03247 -6.671056)
			(end 21.044662 -6.740144)
			(stroke
				(width 0.1)
				(type default)
			)
			(layer "F.SilkS")
		)
		(fp_line
			(start 21.033994 -5.171694)
			(end 19.35988 -3.56616)
			(stroke
				(width 0.1)
				(type default)
			)
			(layer "F.SilkS")
		)
		(fp_line
			(start 21.033994 -5.171694)
			(end 19.35988 -3.56616)
			(stroke
				(width 0.1)
				(type default)
			)
			(layer "F.SilkS")
		)
		(fp_line
			(start 21.033994 -5.171694)
			(end 20.973542 -5.171694)
			(stroke
				(width 0.1)
				(type default)
			)
			(layer "F.SilkS")
		)
		(fp_line
			(start 21.033994 -5.171694)
			(end 20.973542 -5.171694)
			(stroke
				(width 0.1)
				(type default)
			)
			(layer "F.SilkS")
		)
		(fp_line
			(start 21.035772 -1.364742)
			(end 21.00961 -1.281684)
			(stroke
				(width 0.1)
				(type default)
			)
			(layer "F.SilkS")
		)
		(fp_line
			(start 21.035772 -1.364742)
			(end 21.00961 -1.281684)
			(stroke
				(width 0.1)
				(type default)
			)
			(layer "F.SilkS")
		)
		(fp_line
			(start 21.044662 -6.740144)
			(end 19.688302 -5.439156)
			(stroke
				(width 0.1)
				(type default)
			)
			(layer "F.SilkS")
		)
		(fp_line
			(start 21.044662 -6.740144)
			(end 19.688302 -5.439156)
			(stroke
				(width 0.1)
				(type default)
			)
			(layer "F.SilkS")
		)
		(fp_line
			(start 21.044662 -6.740144)
			(end 21.057108 -6.80974)
			(stroke
				(width 0.1)
				(type default)
			)
			(layer "F.SilkS")
		)
		(fp_line
			(start 21.044662 -6.740144)
			(end 21.057108 -6.80974)
			(stroke
				(width 0.1)
				(type default)
			)
			(layer "F.SilkS")
		)
		(fp_line
			(start 21.057108 -6.80974)
			(end 19.700748 -5.508752)
			(stroke
				(width 0.1)
				(type default)
			)
			(layer "F.SilkS")
		)
		(fp_line
			(start 21.057108 -6.80974)
			(end 19.700748 -5.508752)
			(stroke
				(width 0.1)
				(type default)
			)
			(layer "F.SilkS")
		)
		(fp_line
			(start 21.057108 -6.80974)
			(end 21.061934 -6.838188)
			(stroke
				(width 0.1)
				(type default)
			)
			(layer "F.SilkS")
		)
		(fp_line
			(start 21.057108 -6.80974)
			(end 21.061934 -6.838188)
			(stroke
				(width 0.1)
				(type default)
			)
			(layer "F.SilkS")
		)
		(fp_line
			(start 21.061934 -6.838188)
			(end 20.993354 -6.806438)
			(stroke
				(width 0.1)
				(type default)
			)
			(layer "F.SilkS")
		)
		(fp_line
			(start 21.061934 -6.838188)
			(end 20.993354 -6.806438)
			(stroke
				(width 0.1)
				(type default)
			)
			(layer "F.SilkS")
		)
		(fp_line
			(start 21.062188 -1.447546)
			(end 21.035772 -1.364742)
			(stroke
				(width 0.1)
				(type default)
			)
			(layer "F.SilkS")
		)
		(fp_line
			(start 21.062188 -1.447546)
			(end 21.035772 -1.364742)
			(stroke
				(width 0.1)
				(type default)
			)
			(layer "F.SilkS")
		)
		(fp_line
			(start 21.069554 -4.109466)
			(end 21.129752 -4.109466)
			(stroke
				(width 0.1)
				(type default)
			)
			(layer "F.SilkS")
		)
		(fp_line
			(start 21.069554 -4.109466)
			(end 21.129752 -4.109466)
			(stroke
				(width 0.1)
				(type default)
			)
			(layer "F.SilkS")
		)
		(fp_line
			(start 21.088858 -1.530604)
			(end 21.062188 -1.447546)
			(stroke
				(width 0.1)
				(type default)
			)
			(layer "F.SilkS")
		)
		(fp_line
			(start 21.088858 -1.530604)
			(end 21.062188 -1.447546)
			(stroke
				(width 0.1)
				(type default)
			)
			(layer "F.SilkS")
		)
		(fp_line
			(start 21.093938 -5.171694)
			(end 19.347942 -3.496564)
			(stroke
				(width 0.1)
				(type default)
			)
			(layer "F.SilkS")
		)
		(fp_line
			(start 21.093938 -5.171694)
			(end 19.347942 -3.496564)
			(stroke
				(width 0.1)
				(type default)
			)
			(layer "F.SilkS")
		)
		(fp_line
			(start 21.093938 -5.171694)
			(end 21.033994 -5.171694)
			(stroke
				(width 0.1)
				(type default)
			)
			(layer "F.SilkS")
		)
		(fp_line
			(start 21.093938 -5.171694)
			(end 21.033994 -5.171694)
			(stroke
				(width 0.1)
				(type default)
			)
			(layer "F.SilkS")
		)
		(fp_line
			(start 21.115274 -1.613916)
			(end 21.088858 -1.530604)
			(stroke
				(width 0.1)
				(type default)
			)
			(layer "F.SilkS")
		)
		(fp_line
			(start 21.115274 -1.613916)
			(end 21.088858 -1.530604)
			(stroke
				(width 0.1)
				(type default)
			)
			(layer "F.SilkS")
		)
		(fp_line
			(start 21.129752 -4.109466)
			(end 21.18995 -4.109466)
			(stroke
				(width 0.1)
				(type default)
			)
			(layer "F.SilkS")
		)
		(fp_line
			(start 21.129752 -4.109466)
			(end 21.18995 -4.109466)
			(stroke
				(width 0.1)
				(type default)
			)
			(layer "F.SilkS")
		)
		(fp_line
			(start 21.141436 -1.69672)
			(end 21.115274 -1.613916)
			(stroke
				(width 0.1)
				(type default)
			)
			(layer "F.SilkS")
		)
		(fp_line
			(start 21.141436 -1.69672)
			(end 21.115274 -1.613916)
			(stroke
				(width 0.1)
				(type default)
			)
			(layer "F.SilkS")
		)
		(fp_line
			(start 21.154136 -5.171694)
			(end 19.33575 -3.427476)
			(stroke
				(width 0.1)
				(type default)
			)
			(layer "F.SilkS")
		)
		(fp_line
			(start 21.154136 -5.171694)
			(end 19.33575 -3.427476)
			(stroke
				(width 0.1)
				(type default)
			)
			(layer "F.SilkS")
		)
		(fp_line
			(start 21.154136 -5.171694)
			(end 21.093938 -5.171694)
			(stroke
				(width 0.1)
				(type default)
			)
			(layer "F.SilkS")
		)
		(fp_line
			(start 21.154136 -5.171694)
			(end 21.093938 -5.171694)
			(stroke
				(width 0.1)
				(type default)
			)
			(layer "F.SilkS")
		)
		(fp_line
			(start 21.167852 -1.779778)
			(end 21.141436 -1.69672)
			(stroke
				(width 0.1)
				(type default)
			)
			(layer "F.SilkS")
		)
		(fp_line
			(start 21.167852 -1.779778)
			(end 21.141436 -1.69672)
			(stroke
				(width 0.1)
				(type default)
			)
			(layer "F.SilkS")
		)
		(fp_line
			(start 21.18995 -4.109466)
			(end 21.250402 -4.109466)
			(stroke
				(width 0.1)
				(type default)
			)
			(layer "F.SilkS")
		)
		(fp_line
			(start 21.18995 -4.109466)
			(end 21.250402 -4.109466)
			(stroke
				(width 0.1)
				(type default)
			)
			(layer "F.SilkS")
		)
		(fp_line
			(start 21.194268 -1.862836)
			(end 21.167852 -1.779778)
			(stroke
				(width 0.1)
				(type default)
			)
			(layer "F.SilkS")
		)
		(fp_line
			(start 21.194268 -1.862836)
			(end 21.167852 -1.779778)
			(stroke
				(width 0.1)
				(type default)
			)
			(layer "F.SilkS")
		)
		(fp_line
			(start 21.21408 -5.171694)
			(end 19.323558 -3.358134)
			(stroke
				(width 0.1)
				(type default)
			)
			(layer "F.SilkS")
		)
		(fp_line
			(start 21.21408 -5.171694)
			(end 19.323558 -3.358134)
			(stroke
				(width 0.1)
				(type default)
			)
			(layer "F.SilkS")
		)
		(fp_line
			(start 21.21408 -5.171694)
			(end 21.154136 -5.171694)
			(stroke
				(width 0.1)
				(type default)
			)
			(layer "F.SilkS")
		)
		(fp_line
			(start 21.21408 -5.171694)
			(end 21.154136 -5.171694)
			(stroke
				(width 0.1)
				(type default)
			)
			(layer "F.SilkS")
		)
		(fp_line
			(start 21.220684 -1.946148)
			(end 21.194268 -1.862836)
			(stroke
				(width 0.1)
				(type default)
			)
			(layer "F.SilkS")
		)
		(fp_line
			(start 21.220684 -1.946148)
			(end 21.194268 -1.862836)
			(stroke
				(width 0.1)
				(type default)
			)
			(layer "F.SilkS")
		)
		(fp_line
			(start 21.2471 -2.028952)
			(end 21.220684 -1.946148)
			(stroke
				(width 0.1)
				(type default)
			)
			(layer "F.SilkS")
		)
		(fp_line
			(start 21.2471 -2.028952)
			(end 21.220684 -1.946148)
			(stroke
				(width 0.1)
				(type default)
			)
			(layer "F.SilkS")
		)
		(fp_line
			(start 21.250402 -4.109466)
			(end 21.310346 -4.109466)
			(stroke
				(width 0.1)
				(type default)
			)
			(layer "F.SilkS")
		)
		(fp_line
			(start 21.250402 -4.109466)
			(end 21.310346 -4.109466)
			(stroke
				(width 0.1)
				(type default)
			)
			(layer "F.SilkS")
		)
		(fp_line
			(start 21.273516 -2.11201)
			(end 21.2471 -2.028952)
			(stroke
				(width 0.1)
				(type default)
			)
			(layer "F.SilkS")
		)
		(fp_line
			(start 21.273516 -2.11201)
			(end 21.2471 -2.028952)
			(stroke
				(width 0.1)
				(type default)
			)
			(layer "F.SilkS")
		)
		(fp_line
			(start 21.274532 -5.171694)
			(end 19.311366 -3.288538)
			(stroke
				(width 0.1)
				(type default)
			)
			(layer "F.SilkS")
		)
		(fp_line
			(start 21.274532 -5.171694)
			(end 19.311366 -3.288538)
			(stroke
				(width 0.1)
				(type default)
			)
			(layer "F.SilkS")
		)
		(fp_line
			(start 21.274532 -5.171694)
			(end 21.21408 -5.171694)
			(stroke
				(width 0.1)
				(type default)
			)
			(layer "F.SilkS")
		)
		(fp_line
			(start 21.274532 -5.171694)
			(end 21.21408 -5.171694)
			(stroke
				(width 0.1)
				(type default)
			)
			(layer "F.SilkS")
		)
		(fp_line
			(start 21.299932 -2.195068)
			(end 21.273516 -2.11201)
			(stroke
				(width 0.1)
				(type default)
			)
			(layer "F.SilkS")
		)
		(fp_line
			(start 21.299932 -2.195068)
			(end 21.273516 -2.11201)
			(stroke
				(width 0.1)
				(type default)
			)
			(layer "F.SilkS")
		)
		(fp_line
			(start 21.310346 -4.109466)
			(end 21.370544 -4.109466)
			(stroke
				(width 0.1)
				(type default)
			)
			(layer "F.SilkS")
		)
		(fp_line
			(start 21.310346 -4.109466)
			(end 21.370544 -4.109466)
			(stroke
				(width 0.1)
				(type default)
			)
			(layer "F.SilkS")
		)
		(fp_line
			(start 21.33473 -5.171694)
			(end 19.299428 -3.218942)
			(stroke
				(width 0.1)
				(type default)
			)
			(layer "F.SilkS")
		)
		(fp_line
			(start 21.33473 -5.171694)
			(end 19.299428 -3.218942)
			(stroke
				(width 0.1)
				(type default)
			)
			(layer "F.SilkS")
		)
		(fp_line
			(start 21.33473 -5.171694)
			(end 21.274532 -5.171694)
			(stroke
				(width 0.1)
				(type default)
			)
			(layer "F.SilkS")
		)
		(fp_line
			(start 21.33473 -5.171694)
			(end 21.274532 -5.171694)
			(stroke
				(width 0.1)
				(type default)
			)
			(layer "F.SilkS")
		)
		(fp_line
			(start 21.370544 -4.109466)
			(end 21.430742 -4.109466)
			(stroke
				(width 0.1)
				(type default)
			)
			(layer "F.SilkS")
		)
		(fp_line
			(start 21.370544 -4.109466)
			(end 21.430742 -4.109466)
			(stroke
				(width 0.1)
				(type default)
			)
			(layer "F.SilkS")
		)
		(fp_line
			(start 21.394674 -5.171694)
			(end 19.286982 -3.149854)
			(stroke
				(width 0.1)
				(type default)
			)
			(layer "F.SilkS")
		)
		(fp_line
			(start 21.394674 -5.171694)
			(end 19.286982 -3.149854)
			(stroke
				(width 0.1)
				(type default)
			)
			(layer "F.SilkS")
		)
		(fp_line
			(start 21.394674 -5.171694)
			(end 21.33473 -5.171694)
			(stroke
				(width 0.1)
				(type default)
			)
			(layer "F.SilkS")
		)
		(fp_line
			(start 21.394674 -5.171694)
			(end 21.33473 -5.171694)
			(stroke
				(width 0.1)
				(type default)
			)
			(layer "F.SilkS")
		)
		(fp_line
			(start 21.430742 -4.109466)
			(end 21.490686 -4.109466)
			(stroke
				(width 0.1)
				(type default)
			)
			(layer "F.SilkS")
		)
		(fp_line
			(start 21.430742 -4.109466)
			(end 21.490686 -4.109466)
			(stroke
				(width 0.1)
				(type default)
			)
			(layer "F.SilkS")
		)
		(fp_line
			(start 21.454872 -5.171694)
			(end 19.27479 -3.080512)
			(stroke
				(width 0.1)
				(type default)
			)
			(layer "F.SilkS")
		)
		(fp_line
			(start 21.454872 -5.171694)
			(end 19.27479 -3.080512)
			(stroke
				(width 0.1)
				(type default)
			)
			(layer "F.SilkS")
		)
		(fp_line
			(start 21.454872 -5.171694)
			(end 21.394674 -5.171694)
			(stroke
				(width 0.1)
				(type default)
			)
			(layer "F.SilkS")
		)
		(fp_line
			(start 21.454872 -5.171694)
			(end 21.394674 -5.171694)
			(stroke
				(width 0.1)
				(type default)
			)
			(layer "F.SilkS")
		)
		(fp_line
			(start 21.490686 -4.109466)
			(end 21.55063 -4.109466)
			(stroke
				(width 0.1)
				(type default)
			)
			(layer "F.SilkS")
		)
		(fp_line
			(start 21.490686 -4.109466)
			(end 21.55063 -4.109466)
			(stroke
				(width 0.1)
				(type default)
			)
			(layer "F.SilkS")
		)
		(fp_line
			(start 21.515324 -5.171694)
			(end 19.262852 -3.01117)
			(stroke
				(width 0.1)
				(type default)
			)
			(layer "F.SilkS")
		)
		(fp_line
			(start 21.515324 -5.171694)
			(end 19.262852 -3.01117)
			(stroke
				(width 0.1)
				(type default)
			)
			(layer "F.SilkS")
		)
		(fp_line
			(start 21.515324 -5.171694)
			(end 21.454872 -5.171694)
			(stroke
				(width 0.1)
				(type default)
			)
			(layer "F.SilkS")
		)
		(fp_line
			(start 21.515324 -5.171694)
			(end 21.454872 -5.171694)
			(stroke
				(width 0.1)
				(type default)
			)
			(layer "F.SilkS")
		)
		(fp_line
			(start 21.55063 -4.109466)
			(end 21.611082 -4.109466)
			(stroke
				(width 0.1)
				(type default)
			)
			(layer "F.SilkS")
		)
		(fp_line
			(start 21.55063 -4.109466)
			(end 21.611082 -4.109466)
			(stroke
				(width 0.1)
				(type default)
			)
			(layer "F.SilkS")
		)
		(fp_line
			(start 21.575522 -5.171694)
			(end 19.250406 -2.941574)
			(stroke
				(width 0.1)
				(type default)
			)
			(layer "F.SilkS")
		)
		(fp_line
			(start 21.575522 -5.171694)
			(end 19.250406 -2.941574)
			(stroke
				(width 0.1)
				(type default)
			)
			(layer "F.SilkS")
		)
		(fp_line
			(start 21.575522 -5.171694)
			(end 21.515324 -5.171694)
			(stroke
				(width 0.1)
				(type default)
			)
			(layer "F.SilkS")
		)
		(fp_line
			(start 21.575522 -5.171694)
			(end 21.515324 -5.171694)
			(stroke
				(width 0.1)
				(type default)
			)
			(layer "F.SilkS")
		)
		(fp_line
			(start 21.612352 -4.109466)
			(end 21.611082 -4.109466)
			(stroke
				(width 0.1)
				(type default)
			)
			(layer "F.SilkS")
		)
		(fp_line
			(start 21.612352 -4.109466)
			(end 21.611082 -4.109466)
			(stroke
				(width 0.1)
				(type default)
			)
			(layer "F.SilkS")
		)
		(fp_line
			(start 21.61286 -4.11099)
			(end 21.611082 -4.109466)
			(stroke
				(width 0.1)
				(type default)
			)
			(layer "F.SilkS")
		)
		(fp_line
			(start 21.61286 -4.11099)
			(end 21.611082 -4.109466)
			(stroke
				(width 0.1)
				(type default)
			)
			(layer "F.SilkS")
		)
		(fp_line
			(start 21.61286 -4.11099)
			(end 21.612352 -4.109466)
			(stroke
				(width 0.1)
				(type default)
			)
			(layer "F.SilkS")
		)
		(fp_line
			(start 21.61286 -4.11099)
			(end 21.612352 -4.109466)
			(stroke
				(width 0.1)
				(type default)
			)
			(layer "F.SilkS")
		)
		(fp_line
			(start 21.61286 -4.11099)
			(end 21.624798 -4.180586)
			(stroke
				(width 0.1)
				(type default)
			)
			(layer "F.SilkS")
		)
		(fp_line
			(start 21.61286 -4.11099)
			(end 21.624798 -4.180586)
			(stroke
				(width 0.1)
				(type default)
			)
			(layer "F.SilkS")
		)
		(fp_line
			(start 21.624798 -4.180586)
			(end 21.55063 -4.109466)
			(stroke
				(width 0.1)
				(type default)
			)
			(layer "F.SilkS")
		)
		(fp_line
			(start 21.624798 -4.180586)
			(end 21.55063 -4.109466)
			(stroke
				(width 0.1)
				(type default)
			)
			(layer "F.SilkS")
		)
		(fp_line
			(start 21.624798 -4.180586)
			(end 21.636736 -4.249674)
			(stroke
				(width 0.1)
				(type default)
			)
			(layer "F.SilkS")
		)
		(fp_line
			(start 21.624798 -4.180586)
			(end 21.636736 -4.249674)
			(stroke
				(width 0.1)
				(type default)
			)
			(layer "F.SilkS")
		)
		(fp_line
			(start 21.635466 -5.171694)
			(end 21.575522 -5.171694)
			(stroke
				(width 0.1)
				(type default)
			)
			(layer "F.SilkS")
		)
		(fp_line
			(start 21.635466 -5.171694)
			(end 21.575522 -5.171694)
			(stroke
				(width 0.1)
				(type default)
			)
			(layer "F.SilkS")
		)
		(fp_line
			(start 21.636736 -4.249674)
			(end 21.490686 -4.109466)
			(stroke
				(width 0.1)
				(type default)
			)
			(layer "F.SilkS")
		)
		(fp_line
			(start 21.636736 -4.249674)
			(end 21.490686 -4.109466)
			(stroke
				(width 0.1)
				(type default)
			)
			(layer "F.SilkS")
		)
		(fp_line
			(start 21.636736 -4.249674)
			(end 21.649182 -4.319016)
			(stroke
				(width 0.1)
				(type default)
			)
			(layer "F.SilkS")
		)
		(fp_line
			(start 21.636736 -4.249674)
			(end 21.649182 -4.319016)
			(stroke
				(width 0.1)
				(type default)
			)
			(layer "F.SilkS")
		)
		(fp_line
			(start 21.649182 -4.319016)
			(end 21.430742 -4.109466)
			(stroke
				(width 0.1)
				(type default)
			)
			(layer "F.SilkS")
		)
		(fp_line
			(start 21.649182 -4.319016)
			(end 21.430742 -4.109466)
			(stroke
				(width 0.1)
				(type default)
			)
			(layer "F.SilkS")
		)
		(fp_line
			(start 21.649182 -4.319016)
			(end 21.661374 -4.388358)
			(stroke
				(width 0.1)
				(type default)
			)
			(layer "F.SilkS")
		)
		(fp_line
			(start 21.649182 -4.319016)
			(end 21.661374 -4.388358)
			(stroke
				(width 0.1)
				(type default)
			)
			(layer "F.SilkS")
		)
		(fp_line
			(start 21.661374 -4.388358)
			(end 21.370544 -4.109466)
			(stroke
				(width 0.1)
				(type default)
			)
			(layer "F.SilkS")
		)
		(fp_line
			(start 21.661374 -4.388358)
			(end 21.370544 -4.109466)
			(stroke
				(width 0.1)
				(type default)
			)
			(layer "F.SilkS")
		)
		(fp_line
			(start 21.661374 -4.388358)
			(end 21.673312 -4.457954)
			(stroke
				(width 0.1)
				(type default)
			)
			(layer "F.SilkS")
		)
		(fp_line
			(start 21.661374 -4.388358)
			(end 21.673312 -4.457954)
			(stroke
				(width 0.1)
				(type default)
			)
			(layer "F.SilkS")
		)
		(fp_line
			(start 21.673312 -4.457954)
			(end 21.310346 -4.109466)
			(stroke
				(width 0.1)
				(type default)
			)
			(layer "F.SilkS")
		)
		(fp_line
			(start 21.673312 -4.457954)
			(end 21.310346 -4.109466)
			(stroke
				(width 0.1)
				(type default)
			)
			(layer "F.SilkS")
		)
		(fp_line
			(start 21.673312 -4.457954)
			(end 21.685504 -4.527296)
			(stroke
				(width 0.1)
				(type default)
			)
			(layer "F.SilkS")
		)
		(fp_line
			(start 21.673312 -4.457954)
			(end 21.685504 -4.527296)
			(stroke
				(width 0.1)
				(type default)
			)
			(layer "F.SilkS")
		)
		(fp_line
			(start 21.685504 -4.527296)
			(end 21.250402 -4.109466)
			(stroke
				(width 0.1)
				(type default)
			)
			(layer "F.SilkS")
		)
		(fp_line
			(start 21.685504 -4.527296)
			(end 21.250402 -4.109466)
			(stroke
				(width 0.1)
				(type default)
			)
			(layer "F.SilkS")
		)
		(fp_line
			(start 21.685504 -4.527296)
			(end 21.69795 -4.596638)
			(stroke
				(width 0.1)
				(type default)
			)
			(layer "F.SilkS")
		)
		(fp_line
			(start 21.685504 -4.527296)
			(end 21.69795 -4.596638)
			(stroke
				(width 0.1)
				(type default)
			)
			(layer "F.SilkS")
		)
		(fp_line
			(start 21.69541 -5.171694)
			(end 20.588224 -4.109466)
			(stroke
				(width 0.1)
				(type default)
			)
			(layer "F.SilkS")
		)
		(fp_line
			(start 21.69541 -5.171694)
			(end 20.588224 -4.109466)
			(stroke
				(width 0.1)
				(type default)
			)
			(layer "F.SilkS")
		)
		(fp_line
			(start 21.69541 -5.171694)
			(end 21.635466 -5.171694)
			(stroke
				(width 0.1)
				(type default)
			)
			(layer "F.SilkS")
		)
		(fp_line
			(start 21.69541 -5.171694)
			(end 21.635466 -5.171694)
			(stroke
				(width 0.1)
				(type default)
			)
			(layer "F.SilkS")
		)
		(fp_line
			(start 21.69795 -4.596638)
			(end 21.18995 -4.109466)
			(stroke
				(width 0.1)
				(type default)
			)
			(layer "F.SilkS")
		)
		(fp_line
			(start 21.69795 -4.596638)
			(end 21.18995 -4.109466)
			(stroke
				(width 0.1)
				(type default)
			)
			(layer "F.SilkS")
		)
		(fp_line
			(start 21.69795 -4.596638)
			(end 21.709888 -4.66598)
			(stroke
				(width 0.1)
				(type default)
			)
			(layer "F.SilkS")
		)
		(fp_line
			(start 21.69795 -4.596638)
			(end 21.709888 -4.66598)
			(stroke
				(width 0.1)
				(type default)
			)
			(layer "F.SilkS")
		)
		(fp_line
			(start 21.709888 -4.66598)
			(end 21.129752 -4.109466)
			(stroke
				(width 0.1)
				(type default)
			)
			(layer "F.SilkS")
		)
		(fp_line
			(start 21.709888 -4.66598)
			(end 21.129752 -4.109466)
			(stroke
				(width 0.1)
				(type default)
			)
			(layer "F.SilkS")
		)
		(fp_line
			(start 21.709888 -4.66598)
			(end 21.721826 -4.735576)
			(stroke
				(width 0.1)
				(type default)
			)
			(layer "F.SilkS")
		)
		(fp_line
			(start 21.709888 -4.66598)
			(end 21.721826 -4.735576)
			(stroke
				(width 0.1)
				(type default)
			)
			(layer "F.SilkS")
		)
		(fp_line
			(start 21.721826 -4.735576)
			(end 21.069554 -4.109466)
			(stroke
				(width 0.1)
				(type default)
			)
			(layer "F.SilkS")
		)
		(fp_line
			(start 21.721826 -4.735576)
			(end 21.069554 -4.109466)
			(stroke
				(width 0.1)
				(type default)
			)
			(layer "F.SilkS")
		)
		(fp_line
			(start 21.721826 -4.735576)
			(end 21.734018 -4.804664)
			(stroke
				(width 0.1)
				(type default)
			)
			(layer "F.SilkS")
		)
		(fp_line
			(start 21.721826 -4.735576)
			(end 21.734018 -4.804664)
			(stroke
				(width 0.1)
				(type default)
			)
			(layer "F.SilkS")
		)
		(fp_line
			(start 21.734018 -4.804664)
			(end 21.00961 -4.109466)
			(stroke
				(width 0.1)
				(type default)
			)
			(layer "F.SilkS")
		)
		(fp_line
			(start 21.734018 -4.804664)
			(end 21.00961 -4.109466)
			(stroke
				(width 0.1)
				(type default)
			)
			(layer "F.SilkS")
		)
		(fp_line
			(start 21.734018 -4.804664)
			(end 21.746464 -4.874006)
			(stroke
				(width 0.1)
				(type default)
			)
			(layer "F.SilkS")
		)
		(fp_line
			(start 21.734018 -4.804664)
			(end 21.746464 -4.874006)
			(stroke
				(width 0.1)
				(type default)
			)
			(layer "F.SilkS")
		)
		(fp_line
			(start 21.746464 -4.874006)
			(end 20.949666 -4.109466)
			(stroke
				(width 0.1)
				(type default)
			)
			(layer "F.SilkS")
		)
		(fp_line
			(start 21.746464 -4.874006)
			(end 20.949666 -4.109466)
			(stroke
				(width 0.1)
				(type default)
			)
			(layer "F.SilkS")
		)
		(fp_line
			(start 21.746464 -4.874006)
			(end 21.758402 -4.943348)
			(stroke
				(width 0.1)
				(type default)
			)
			(layer "F.SilkS")
		)
		(fp_line
			(start 21.746464 -4.874006)
			(end 21.758402 -4.943348)
			(stroke
				(width 0.1)
				(type default)
			)
			(layer "F.SilkS")
		)
		(fp_line
			(start 21.755608 -5.171694)
			(end 20.648422 -4.109466)
			(stroke
				(width 0.1)
				(type default)
			)
			(layer "F.SilkS")
		)
		(fp_line
			(start 21.755608 -5.171694)
			(end 20.648422 -4.109466)
			(stroke
				(width 0.1)
				(type default)
			)
			(layer "F.SilkS")
		)
		(fp_line
			(start 21.755608 -5.171694)
			(end 21.69541 -5.171694)
			(stroke
				(width 0.1)
				(type default)
			)
			(layer "F.SilkS")
		)
		(fp_line
			(start 21.755608 -5.171694)
			(end 21.69541 -5.171694)
			(stroke
				(width 0.1)
				(type default)
			)
			(layer "F.SilkS")
		)
		(fp_line
			(start 21.758402 -4.943348)
			(end 20.889214 -4.109466)
			(stroke
				(width 0.1)
				(type default)
			)
			(layer "F.SilkS")
		)
		(fp_line
			(start 21.758402 -4.943348)
			(end 20.889214 -4.109466)
			(stroke
				(width 0.1)
				(type default)
			)
			(layer "F.SilkS")
		)
		(fp_line
			(start 21.758402 -4.943348)
			(end 21.770594 -5.012944)
			(stroke
				(width 0.1)
				(type default)
			)
			(layer "F.SilkS")
		)
		(fp_line
			(start 21.758402 -4.943348)
			(end 21.770594 -5.012944)
			(stroke
				(width 0.1)
				(type default)
			)
			(layer "F.SilkS")
		)
		(fp_line
			(start 21.770594 -5.012944)
			(end 20.829016 -4.109466)
			(stroke
				(width 0.1)
				(type default)
			)
			(layer "F.SilkS")
		)
		(fp_line
			(start 21.770594 -5.012944)
			(end 20.829016 -4.109466)
			(stroke
				(width 0.1)
				(type default)
			)
			(layer "F.SilkS")
		)
		(fp_line
			(start 21.770594 -5.012944)
			(end 21.78304 -5.082032)
			(stroke
				(width 0.1)
				(type default)
			)
			(layer "F.SilkS")
		)
		(fp_line
			(start 21.770594 -5.012944)
			(end 21.78304 -5.082032)
			(stroke
				(width 0.1)
				(type default)
			)
			(layer "F.SilkS")
		)
		(fp_line
			(start 21.78304 -5.082032)
			(end 20.768564 -4.109466)
			(stroke
				(width 0.1)
				(type default)
			)
			(layer "F.SilkS")
		)
		(fp_line
			(start 21.78304 -5.082032)
			(end 20.768564 -4.109466)
			(stroke
				(width 0.1)
				(type default)
			)
			(layer "F.SilkS")
		)
		(fp_line
			(start 21.78304 -5.082032)
			(end 21.794978 -5.151374)
			(stroke
				(width 0.1)
				(type default)
			)
			(layer "F.SilkS")
		)
		(fp_line
			(start 21.78304 -5.082032)
			(end 21.794978 -5.151374)
			(stroke
				(width 0.1)
				(type default)
			)
			(layer "F.SilkS")
		)
		(fp_line
			(start 21.794978 -5.151374)
			(end 20.70862 -4.109466)
			(stroke
				(width 0.1)
				(type default)
			)
			(layer "F.SilkS")
		)
		(fp_line
			(start 21.794978 -5.151374)
			(end 20.70862 -4.109466)
			(stroke
				(width 0.1)
				(type default)
			)
			(layer "F.SilkS")
		)
		(fp_line
			(start 21.794978 -5.151374)
			(end 21.798534 -5.171694)
			(stroke
				(width 0.1)
				(type default)
			)
			(layer "F.SilkS")
		)
		(fp_line
			(start 21.794978 -5.151374)
			(end 21.798534 -5.171694)
			(stroke
				(width 0.1)
				(type default)
			)
			(layer "F.SilkS")
		)
		(fp_line
			(start 21.798534 -5.171694)
			(end 21.755608 -5.171694)
			(stroke
				(width 0.1)
				(type default)
			)
			(layer "F.SilkS")
		)
		(fp_line
			(start 21.798534 -5.171694)
			(end 21.755608 -5.171694)
			(stroke
				(width 0.1)
				(type default)
			)
			(layer "F.SilkS")
		)
		(fp_line
			(start 21.838158 -2.018792)
			(end 23.619206 -3.727196)
			(stroke
				(width 0.1)
				(type default)
			)
			(layer "F.SilkS")
		)
		(fp_line
			(start 21.838158 -2.018792)
			(end 23.619206 -3.727196)
			(stroke
				(width 0.1)
				(type default)
			)
			(layer "F.SilkS")
		)
		(fp_line
			(start 21.839428 -2.07772)
			(end 23.55469 -3.723386)
			(stroke
				(width 0.1)
				(type default)
			)
			(layer "F.SilkS")
		)
		(fp_line
			(start 21.839428 -2.07772)
			(end 23.55469 -3.723386)
			(stroke
				(width 0.1)
				(type default)
			)
			(layer "F.SilkS")
		)
		(fp_line
			(start 21.841206 -2.137156)
			(end 23.489666 -3.71856)
			(stroke
				(width 0.1)
				(type default)
			)
			(layer "F.SilkS")
		)
		(fp_line
			(start 21.841206 -2.137156)
			(end 23.489666 -3.71856)
			(stroke
				(width 0.1)
				(type default)
			)
			(layer "F.SilkS")
		)
		(fp_line
			(start 21.841206 -1.90627)
			(end 23.747984 -3.735324)
			(stroke
				(width 0.1)
				(type default)
			)
			(layer "F.SilkS")
		)
		(fp_line
			(start 21.841206 -1.90627)
			(end 23.747984 -3.735324)
			(stroke
				(width 0.1)
				(type default)
			)
			(layer "F.SilkS")
		)
		(fp_line
			(start 21.846032 -1.853184)
			(end 23.811992 -3.739388)
			(stroke
				(width 0.1)
				(type default)
			)
			(layer "F.SilkS")
		)
		(fp_line
			(start 21.846032 -1.853184)
			(end 23.811992 -3.739388)
			(stroke
				(width 0.1)
				(type default)
			)
			(layer "F.SilkS")
		)
		(fp_line
			(start 21.849334 -2.202942)
			(end 23.414228 -3.703828)
			(stroke
				(width 0.1)
				(type default)
			)
			(layer "F.SilkS")
		)
		(fp_line
			(start 21.849334 -2.202942)
			(end 23.414228 -3.703828)
			(stroke
				(width 0.1)
				(type default)
			)
			(layer "F.SilkS")
		)
		(fp_line
			(start 21.850858 -1.799844)
			(end 23.874222 -3.740912)
			(stroke
				(width 0.1)
				(type default)
			)
			(layer "F.SilkS")
		)
		(fp_line
			(start 21.850858 -1.799844)
			(end 23.874222 -3.740912)
			(stroke
				(width 0.1)
				(type default)
			)
			(layer "F.SilkS")
		)
		(fp_line
			(start 21.85797 -2.268728)
			(end 23.338282 -3.688842)
			(stroke
				(width 0.1)
				(type default)
			)
			(layer "F.SilkS")
		)
		(fp_line
			(start 21.85797 -2.268728)
			(end 23.338282 -3.688842)
			(stroke
				(width 0.1)
				(type default)
			)
			(layer "F.SilkS")
		)
		(fp_line
			(start 21.86051 -1.75133)
			(end 23.930864 -3.737864)
			(stroke
				(width 0.1)
				(type default)
			)
			(layer "F.SilkS")
		)
		(fp_line
			(start 21.86051 -1.75133)
			(end 23.930864 -3.737864)
			(stroke
				(width 0.1)
				(type default)
			)
			(layer "F.SilkS")
		)
		(fp_line
			(start 21.869146 -2.337308)
			(end 23.26259 -3.673856)
			(stroke
				(width 0.1)
				(type default)
			)
			(layer "F.SilkS")
		)
		(fp_line
			(start 21.869146 -2.337308)
			(end 23.26259 -3.673856)
			(stroke
				(width 0.1)
				(type default)
			)
			(layer "F.SilkS")
		)
		(fp_line
			(start 21.870416 -1.703578)
			(end 23.98776 -3.734816)
			(stroke
				(width 0.1)
				(type default)
			)
			(layer "F.SilkS")
		)
		(fp_line
			(start 21.870416 -1.703578)
			(end 23.98776 -3.734816)
			(stroke
				(width 0.1)
				(type default)
			)
			(layer "F.SilkS")
		)
		(fp_line
			(start 21.88083 -1.655826)
			(end 24.04491 -3.731768)
			(stroke
				(width 0.1)
				(type default)
			)
			(layer "F.SilkS")
		)
		(fp_line
			(start 21.88083 -1.655826)
			(end 24.04491 -3.731768)
			(stroke
				(width 0.1)
				(type default)
			)
			(layer "F.SilkS")
		)
		(fp_line
			(start 21.89099 -2.416048)
			(end 23.187152 -3.659124)
			(stroke
				(width 0.1)
				(type default)
			)
			(layer "F.SilkS")
		)
		(fp_line
			(start 21.89099 -2.416048)
			(end 23.187152 -3.659124)
			(stroke
				(width 0.1)
				(type default)
			)
			(layer "F.SilkS")
		)
		(fp_line
			(start 21.894546 -1.611376)
			(end 24.101806 -3.728974)
			(stroke
				(width 0.1)
				(type default)
			)
			(layer "F.SilkS")
		)
		(fp_line
			(start 21.894546 -1.611376)
			(end 24.101806 -3.728974)
			(stroke
				(width 0.1)
				(type default)
			)
			(layer "F.SilkS")
		)
		(fp_line
			(start 21.909786 -1.568196)
			(end 24.154892 -3.721862)
			(stroke
				(width 0.1)
				(type default)
			)
			(layer "F.SilkS")
		)
		(fp_line
			(start 21.909786 -1.568196)
			(end 24.154892 -3.721862)
			(stroke
				(width 0.1)
				(type default)
			)
			(layer "F.SilkS")
		)
		(fp_line
			(start 21.913088 -2.494788)
			(end 23.10003 -3.63347)
			(stroke
				(width 0.1)
				(type default)
			)
			(layer "F.SilkS")
		)
		(fp_line
			(start 21.913088 -2.494788)
			(end 23.10003 -3.63347)
			(stroke
				(width 0.1)
				(type default)
			)
			(layer "F.SilkS")
		)
		(fp_line
			(start 21.924772 -1.525016)
			(end 24.205946 -3.712972)
			(stroke
				(width 0.1)
				(type default)
			)
			(layer "F.SilkS")
		)
		(fp_line
			(start 21.924772 -1.525016)
			(end 24.205946 -3.712972)
			(stroke
				(width 0.1)
				(type default)
			)
			(layer "F.SilkS")
		)
		(fp_line
			(start 21.93544 -2.573782)
			(end 23.00478 -3.599942)
			(stroke
				(width 0.1)
				(type default)
			)
			(layer "F.SilkS")
		)
		(fp_line
			(start 21.93544 -2.573782)
			(end 23.00478 -3.599942)
			(stroke
				(width 0.1)
				(type default)
			)
			(layer "F.SilkS")
		)
		(fp_line
			(start 21.942806 -1.484376)
			(end 23.220934 -2.710688)
			(stroke
				(width 0.1)
				(type default)
			)
			(layer "F.SilkS")
		)
		(fp_line
			(start 21.942806 -1.484376)
			(end 23.220934 -2.710688)
			(stroke
				(width 0.1)
				(type default)
			)
			(layer "F.SilkS")
		)
		(fp_line
			(start 21.957538 -2.652776)
			(end 22.909784 -3.56616)
			(stroke
				(width 0.1)
				(type default)
			)
			(layer "F.SilkS")
		)
		(fp_line
			(start 21.957538 -2.652776)
			(end 22.909784 -3.56616)
			(stroke
				(width 0.1)
				(type default)
			)
			(layer "F.SilkS")
		)
		(fp_line
			(start 21.962364 -1.445514)
			(end 23.052786 -2.491486)
			(stroke
				(width 0.1)
				(type default)
			)
			(layer "F.SilkS")
		)
		(fp_line
			(start 21.962364 -1.445514)
			(end 23.052786 -2.491486)
			(stroke
				(width 0.1)
				(type default)
			)
			(layer "F.SilkS")
		)
		(fp_line
			(start 21.981922 -1.406652)
			(end 23.020782 -2.403094)
			(stroke
				(width 0.1)
				(type default)
			)
			(layer "F.SilkS")
		)
		(fp_line
			(start 21.981922 -1.406652)
			(end 23.020782 -2.403094)
			(stroke
				(width 0.1)
				(type default)
			)
			(layer "F.SilkS")
		)
		(fp_line
			(start 22.003004 -1.36906)
			(end 22.99081 -2.31648)
			(stroke
				(width 0.1)
				(type default)
			)
			(layer "F.SilkS")
		)
		(fp_line
			(start 22.003004 -1.36906)
			(end 22.99081 -2.31648)
			(stroke
				(width 0.1)
				(type default)
			)
			(layer "F.SilkS")
		)
		(fp_line
			(start 22.017228 -2.767838)
			(end 22.802342 -3.521202)
			(stroke
				(width 0.1)
				(type default)
			)
			(layer "F.SilkS")
		)
		(fp_line
			(start 22.017228 -2.767838)
			(end 22.802342 -3.521202)
			(stroke
				(width 0.1)
				(type default)
			)
			(layer "F.SilkS")
		)
		(fp_line
			(start 22.02688 -1.334262)
			(end 22.984206 -2.252726)
			(stroke
				(width 0.1)
				(type default)
			)
			(layer "F.SilkS")
		)
		(fp_line
			(start 22.02688 -1.334262)
			(end 22.984206 -2.252726)
			(stroke
				(width 0.1)
				(type default)
			)
			(layer "F.SilkS")
		)
		(fp_line
			(start 22.05101 -1.299464)
			(end 22.981158 -2.19202)
			(stroke
				(width 0.1)
				(type default)
			)
			(layer "F.SilkS")
		)
		(fp_line
			(start 22.05101 -1.299464)
			(end 22.981158 -2.19202)
			(stroke
				(width 0.1)
				(type default)
			)
			(layer "F.SilkS")
		)
		(fp_line
			(start 22.07514 -1.265174)
			(end 22.985222 -2.137918)
			(stroke
				(width 0.1)
				(type default)
			)
			(layer "F.SilkS")
		)
		(fp_line
			(start 22.07514 -1.265174)
			(end 22.985222 -2.137918)
			(stroke
				(width 0.1)
				(type default)
			)
			(layer "F.SilkS")
		)
		(fp_line
			(start 22.077934 -2.883408)
			(end 22.662896 -3.444748)
			(stroke
				(width 0.1)
				(type default)
			)
			(layer "F.SilkS")
		)
		(fp_line
			(start 22.077934 -2.883408)
			(end 22.662896 -3.444748)
			(stroke
				(width 0.1)
				(type default)
			)
			(layer "F.SilkS")
		)
		(fp_line
			(start 22.10308 -1.233932)
			(end 22.992588 -2.087372)
			(stroke
				(width 0.1)
				(type default)
			)
			(layer "F.SilkS")
		)
		(fp_line
			(start 22.10308 -1.233932)
			(end 22.992588 -2.087372)
			(stroke
				(width 0.1)
				(type default)
			)
			(layer "F.SilkS")
		)
		(fp_line
			(start 22.130512 -1.202944)
			(end 23.005542 -2.042414)
			(stroke
				(width 0.1)
				(type default)
			)
			(layer "F.SilkS")
		)
		(fp_line
			(start 22.130512 -1.202944)
			(end 23.005542 -2.042414)
			(stroke
				(width 0.1)
				(type default)
			)
			(layer "F.SilkS")
		)
		(fp_line
			(start 22.158452 -1.171956)
			(end 23.020782 -1.99898)
			(stroke
				(width 0.1)
				(type default)
			)
			(layer "F.SilkS")
		)
		(fp_line
			(start 22.158452 -1.171956)
			(end 23.020782 -1.99898)
			(stroke
				(width 0.1)
				(type default)
			)
			(layer "F.SilkS")
		)
		(fp_line
			(start 22.18944 -1.143762)
			(end 23.042372 -1.96215)
			(stroke
				(width 0.1)
				(type default)
			)
			(layer "F.SilkS")
		)
		(fp_line
			(start 22.18944 -1.143762)
			(end 23.042372 -1.96215)
			(stroke
				(width 0.1)
				(type default)
			)
			(layer "F.SilkS")
		)
		(fp_line
			(start 22.22119 -1.11633)
			(end 23.06447 -1.925828)
			(stroke
				(width 0.1)
				(type default)
			)
			(layer "F.SilkS")
		)
		(fp_line
			(start 22.22119 -1.11633)
			(end 23.06447 -1.925828)
			(stroke
				(width 0.1)
				(type default)
			)
			(layer "F.SilkS")
		)
		(fp_line
			(start 22.252432 -1.089152)
			(end 23.094188 -1.896364)
			(stroke
				(width 0.1)
				(type default)
			)
			(layer "F.SilkS")
		)
		(fp_line
			(start 22.252432 -1.089152)
			(end 23.094188 -1.896364)
			(stroke
				(width 0.1)
				(type default)
			)
			(layer "F.SilkS")
		)
		(fp_line
			(start 22.286214 -1.063752)
			(end 23.124414 -1.867916)
			(stroke
				(width 0.1)
				(type default)
			)
			(layer "F.SilkS")
		)
		(fp_line
			(start 22.286214 -1.063752)
			(end 23.124414 -1.867916)
			(stroke
				(width 0.1)
				(type default)
			)
			(layer "F.SilkS")
		)
		(fp_line
			(start 22.321774 -1.039622)
			(end 23.158196 -1.842262)
			(stroke
				(width 0.1)
				(type default)
			)
			(layer "F.SilkS")
		)
		(fp_line
			(start 22.321774 -1.039622)
			(end 23.158196 -1.842262)
			(stroke
				(width 0.1)
				(type default)
			)
			(layer "F.SilkS")
		)
		(fp_line
			(start 22.356572 -1.015746)
			(end 23.197058 -1.821942)
			(stroke
				(width 0.1)
				(type default)
			)
			(layer "F.SilkS")
		)
		(fp_line
			(start 22.356572 -1.015746)
			(end 23.197058 -1.821942)
			(stroke
				(width 0.1)
				(type default)
			)
			(layer "F.SilkS")
		)
		(fp_line
			(start 22.393402 -0.993394)
			(end 23.235666 -1.801622)
			(stroke
				(width 0.1)
				(type default)
			)
			(layer "F.SilkS")
		)
		(fp_line
			(start 22.393402 -0.993394)
			(end 23.235666 -1.801622)
			(stroke
				(width 0.1)
				(type default)
			)
			(layer "F.SilkS")
		)
		(fp_line
			(start 22.43201 -0.97282)
			(end 23.280878 -1.786636)
			(stroke
				(width 0.1)
				(type default)
			)
			(layer "F.SilkS")
		)
		(fp_line
			(start 22.43201 -0.97282)
			(end 23.280878 -1.786636)
			(stroke
				(width 0.1)
				(type default)
			)
			(layer "F.SilkS")
		)
		(fp_line
			(start 22.470872 -0.952246)
			(end 23.328122 -1.774444)
			(stroke
				(width 0.1)
				(type default)
			)
			(layer "F.SilkS")
		)
		(fp_line
			(start 22.470872 -0.952246)
			(end 23.328122 -1.774444)
			(stroke
				(width 0.1)
				(type default)
			)
			(layer "F.SilkS")
		)
		(fp_line
			(start 22.510496 -0.932688)
			(end 23.375366 -1.761998)
			(stroke
				(width 0.1)
				(type default)
			)
			(layer "F.SilkS")
		)
		(fp_line
			(start 22.510496 -0.932688)
			(end 23.375366 -1.761998)
			(stroke
				(width 0.1)
				(type default)
			)
			(layer "F.SilkS")
		)
		(fp_line
			(start 22.552914 -0.91567)
			(end 23.430484 -1.757172)
			(stroke
				(width 0.1)
				(type default)
			)
			(layer "F.SilkS")
		)
		(fp_line
			(start 22.552914 -0.91567)
			(end 23.430484 -1.757172)
			(stroke
				(width 0.1)
				(type default)
			)
			(layer "F.SilkS")
		)
		(fp_line
			(start 22.595332 -0.898398)
			(end 23.48611 -1.752854)
			(stroke
				(width 0.1)
				(type default)
			)
			(layer "F.SilkS")
		)
		(fp_line
			(start 22.595332 -0.898398)
			(end 23.48611 -1.752854)
			(stroke
				(width 0.1)
				(type default)
			)
			(layer "F.SilkS")
		)
		(fp_line
			(start 22.638258 -0.881888)
			(end 23.54199 -1.74879)
			(stroke
				(width 0.1)
				(type default)
			)
			(layer "F.SilkS")
		)
		(fp_line
			(start 22.638258 -0.881888)
			(end 23.54199 -1.74879)
			(stroke
				(width 0.1)
				(type default)
			)
			(layer "F.SilkS")
		)
		(fp_line
			(start 22.651212 -4.81838)
			(end 22.66696 -4.776216)
			(stroke
				(width 0.1)
				(type default)
			)
			(layer "F.SilkS")
		)
		(fp_line
			(start 22.651212 -4.81838)
			(end 22.66696 -4.776216)
			(stroke
				(width 0.1)
				(type default)
			)
			(layer "F.SilkS")
		)
		(fp_line
			(start 22.651212 -4.81838)
			(end 22.676358 -4.842764)
			(stroke
				(width 0.1)
				(type default)
			)
			(layer "F.SilkS")
		)
		(fp_line
			(start 22.651212 -4.81838)
			(end 22.676358 -4.842764)
			(stroke
				(width 0.1)
				(type default)
			)
			(layer "F.SilkS")
		)
		(fp_line
			(start 22.66696 -4.776216)
			(end 22.682708 -4.733798)
			(stroke
				(width 0.1)
				(type default)
			)
			(layer "F.SilkS")
		)
		(fp_line
			(start 22.66696 -4.776216)
			(end 22.682708 -4.733798)
			(stroke
				(width 0.1)
				(type default)
			)
			(layer "F.SilkS")
		)
		(fp_line
			(start 22.66696 -4.776216)
			(end 22.802088 -4.905756)
			(stroke
				(width 0.1)
				(type default)
			)
			(layer "F.SilkS")
		)
		(fp_line
			(start 22.66696 -4.776216)
			(end 22.802088 -4.905756)
			(stroke
				(width 0.1)
				(type default)
			)
			(layer "F.SilkS")
		)
		(fp_line
			(start 22.682708 -4.733798)
			(end 22.698964 -4.69138)
			(stroke
				(width 0.1)
				(type default)
			)
			(layer "F.SilkS")
		)
		(fp_line
			(start 22.682708 -4.733798)
			(end 22.698964 -4.69138)
			(stroke
				(width 0.1)
				(type default)
			)
			(layer "F.SilkS")
		)
		(fp_line
			(start 22.682708 -4.733798)
			(end 22.919436 -4.960874)
			(stroke
				(width 0.1)
				(type default)
			)
			(layer "F.SilkS")
		)
		(fp_line
			(start 22.682708 -4.733798)
			(end 22.919436 -4.960874)
			(stroke
				(width 0.1)
				(type default)
			)
			(layer "F.SilkS")
		)
		(fp_line
			(start 22.684232 -0.868172)
			(end 23.610316 -1.756664)
			(stroke
				(width 0.1)
				(type default)
			)
			(layer "F.SilkS")
		)
		(fp_line
			(start 22.684232 -0.868172)
			(end 23.610316 -1.756664)
			(stroke
				(width 0.1)
				(type default)
			)
			(layer "F.SilkS")
		)
		(fp_line
			(start 22.698964 -4.69138)
			(end 22.714712 -4.648962)
			(stroke
				(width 0.1)
				(type default)
			)
			(layer "F.SilkS")
		)
		(fp_line
			(start 22.698964 -4.69138)
			(end 22.714712 -4.648962)
			(stroke
				(width 0.1)
				(type default)
			)
			(layer "F.SilkS")
		)
		(fp_line
			(start 22.698964 -4.69138)
			(end 23.03272 -5.01142)
			(stroke
				(width 0.1)
				(type default)
			)
			(layer "F.SilkS")
		)
		(fp_line
			(start 22.698964 -4.69138)
			(end 23.03272 -5.01142)
			(stroke
				(width 0.1)
				(type default)
			)
			(layer "F.SilkS")
		)
		(fp_line
			(start 22.714712 -4.648962)
			(end 22.730714 -4.606544)
			(stroke
				(width 0.1)
				(type default)
			)
			(layer "F.SilkS")
		)
		(fp_line
			(start 22.714712 -4.648962)
			(end 22.730714 -4.606544)
			(stroke
				(width 0.1)
				(type default)
			)
			(layer "F.SilkS")
		)
		(fp_line
			(start 22.714712 -4.648962)
			(end 23.13432 -5.051298)
			(stroke
				(width 0.1)
				(type default)
			)
			(layer "F.SilkS")
		)
		(fp_line
			(start 22.714712 -4.648962)
			(end 23.13432 -5.051298)
			(stroke
				(width 0.1)
				(type default)
			)
			(layer "F.SilkS")
		)
		(fp_line
			(start 22.729952 -0.85471)
			(end 23.67915 -1.765046)
			(stroke
				(width 0.1)
				(type default)
			)
			(layer "F.SilkS")
		)
		(fp_line
			(start 22.729952 -0.85471)
			(end 23.67915 -1.765046)
			(stroke
				(width 0.1)
				(type default)
			)
			(layer "F.SilkS")
		)
		(fp_line
			(start 22.730714 -4.606544)
			(end 22.74697 -4.564126)
			(stroke
				(width 0.1)
				(type default)
			)
			(layer "F.SilkS")
		)
		(fp_line
			(start 22.730714 -4.606544)
			(end 22.74697 -4.564126)
			(stroke
				(width 0.1)
				(type default)
			)
			(layer "F.SilkS")
		)
		(fp_line
			(start 22.730714 -4.606544)
			(end 23.234396 -5.089652)
			(stroke
				(width 0.1)
				(type default)
			)
			(layer "F.SilkS")
		)
		(fp_line
			(start 22.730714 -4.606544)
			(end 23.234396 -5.089652)
			(stroke
				(width 0.1)
				(type default)
			)
			(layer "F.SilkS")
		)
		(fp_line
			(start 22.74697 -4.564126)
			(end 22.762718 -4.521708)
			(stroke
				(width 0.1)
				(type default)
			)
			(layer "F.SilkS")
		)
		(fp_line
			(start 22.74697 -4.564126)
			(end 22.762718 -4.521708)
			(stroke
				(width 0.1)
				(type default)
			)
			(layer "F.SilkS")
		)
		(fp_line
			(start 22.74697 -4.564126)
			(end 23.32355 -5.117592)
			(stroke
				(width 0.1)
				(type default)
			)
			(layer "F.SilkS")
		)
		(fp_line
			(start 22.74697 -4.564126)
			(end 23.32355 -5.117592)
			(stroke
				(width 0.1)
				(type default)
			)
			(layer "F.SilkS")
		)
		(fp_line
			(start 22.762718 -4.521708)
			(end 22.778466 -4.47929)
			(stroke
				(width 0.1)
				(type default)
			)
			(layer "F.SilkS")
		)
		(fp_line
			(start 22.762718 -4.521708)
			(end 22.778466 -4.47929)
			(stroke
				(width 0.1)
				(type default)
			)
			(layer "F.SilkS")
		)
		(fp_line
			(start 22.762718 -4.521708)
			(end 23.412704 -5.145278)
			(stroke
				(width 0.1)
				(type default)
			)
			(layer "F.SilkS")
		)
		(fp_line
			(start 22.762718 -4.521708)
			(end 23.412704 -5.145278)
			(stroke
				(width 0.1)
				(type default)
			)
			(layer "F.SilkS")
		)
		(fp_line
			(start 22.777196 -0.841756)
			(end 23.748238 -1.773682)
			(stroke
				(width 0.1)
				(type default)
			)
			(layer "F.SilkS")
		)
		(fp_line
			(start 22.777196 -0.841756)
			(end 23.748238 -1.773682)
			(stroke
				(width 0.1)
				(type default)
			)
			(layer "F.SilkS")
		)
		(fp_line
			(start 22.778466 -4.47929)
			(end 22.794722 -4.436872)
			(stroke
				(width 0.1)
				(type default)
			)
			(layer "F.SilkS")
		)
		(fp_line
			(start 22.778466 -4.47929)
			(end 22.794722 -4.436872)
			(stroke
				(width 0.1)
				(type default)
			)
			(layer "F.SilkS")
		)
		(fp_line
			(start 22.778466 -4.47929)
			(end 23.494746 -5.166106)
			(stroke
				(width 0.1)
				(type default)
			)
			(layer "F.SilkS")
		)
		(fp_line
			(start 22.778466 -4.47929)
			(end 23.494746 -5.166106)
			(stroke
				(width 0.1)
				(type default)
			)
			(layer "F.SilkS")
		)
		(fp_line
			(start 22.794722 -4.436872)
			(end 22.81047 -4.394708)
			(stroke
				(width 0.1)
				(type default)
			)
			(layer "F.SilkS")
		)
		(fp_line
			(start 22.794722 -4.436872)
			(end 22.81047 -4.394708)
			(stroke
				(width 0.1)
				(type default)
			)
			(layer "F.SilkS")
		)
		(fp_line
			(start 22.794722 -4.436872)
			(end 23.573994 -5.184648)
			(stroke
				(width 0.1)
				(type default)
			)
			(layer "F.SilkS")
		)
		(fp_line
			(start 22.794722 -4.436872)
			(end 23.573994 -5.184648)
			(stroke
				(width 0.1)
				(type default)
			)
			(layer "F.SilkS")
		)
		(fp_line
			(start 22.81047 -4.394708)
			(end 22.826472 -4.352036)
			(stroke
				(width 0.1)
				(type default)
			)
			(layer "F.SilkS")
		)
		(fp_line
			(start 22.81047 -4.394708)
			(end 22.826472 -4.352036)
			(stroke
				(width 0.1)
				(type default)
			)
			(layer "F.SilkS")
		)
		(fp_line
			(start 22.81047 -4.394708)
			(end 23.652226 -5.20192)
			(stroke
				(width 0.1)
				(type default)
			)
			(layer "F.SilkS")
		)
		(fp_line
			(start 22.81047 -4.394708)
			(end 23.652226 -5.20192)
			(stroke
				(width 0.1)
				(type default)
			)
			(layer "F.SilkS")
		)
		(fp_line
			(start 22.826472 -4.352036)
			(end 22.842728 -4.309618)
			(stroke
				(width 0.1)
				(type default)
			)
			(layer "F.SilkS")
		)
		(fp_line
			(start 22.826472 -4.352036)
			(end 22.842728 -4.309618)
			(stroke
				(width 0.1)
				(type default)
			)
			(layer "F.SilkS")
		)
		(fp_line
			(start 22.826472 -4.352036)
			(end 23.724616 -5.21335)
			(stroke
				(width 0.1)
				(type default)
			)
			(layer "F.SilkS")
		)
		(fp_line
			(start 22.826472 -4.352036)
			(end 23.724616 -5.21335)
			(stroke
				(width 0.1)
				(type default)
			)
			(layer "F.SilkS")
		)
		(fp_line
			(start 22.826726 -0.831596)
			(end 23.82012 -1.78435)
			(stroke
				(width 0.1)
				(type default)
			)
			(layer "F.SilkS")
		)
		(fp_line
			(start 22.826726 -0.831596)
			(end 23.82012 -1.78435)
			(stroke
				(width 0.1)
				(type default)
			)
			(layer "F.SilkS")
		)
		(fp_line
			(start 22.842728 -4.309618)
			(end 22.858476 -4.267454)
			(stroke
				(width 0.1)
				(type default)
			)
			(layer "F.SilkS")
		)
		(fp_line
			(start 22.842728 -4.309618)
			(end 22.858476 -4.267454)
			(stroke
				(width 0.1)
				(type default)
			)
			(layer "F.SilkS")
		)
		(fp_line
			(start 22.842728 -4.309618)
			(end 23.796498 -5.22478)
			(stroke
				(width 0.1)
				(type default)
			)
			(layer "F.SilkS")
		)
		(fp_line
			(start 22.842728 -4.309618)
			(end 23.796498 -5.22478)
			(stroke
				(width 0.1)
				(type default)
			)
			(layer "F.SilkS")
		)
		(fp_line
			(start 22.858476 -4.267454)
			(end 22.874224 -4.225036)
			(stroke
				(width 0.1)
				(type default)
			)
			(layer "F.SilkS")
		)
		(fp_line
			(start 22.858476 -4.267454)
			(end 22.874224 -4.225036)
			(stroke
				(width 0.1)
				(type default)
			)
			(layer "F.SilkS")
		)
		(fp_line
			(start 22.858476 -4.267454)
			(end 23.86711 -5.235194)
			(stroke
				(width 0.1)
				(type default)
			)
			(layer "F.SilkS")
		)
		(fp_line
			(start 22.858476 -4.267454)
			(end 23.86711 -5.235194)
			(stroke
				(width 0.1)
				(type default)
			)
			(layer "F.SilkS")
		)
		(fp_line
			(start 22.874224 -4.225036)
			(end 22.89048 -4.182618)
			(stroke
				(width 0.1)
				(type default)
			)
			(layer "F.SilkS")
		)
		(fp_line
			(start 22.874224 -4.225036)
			(end 22.89048 -4.182618)
			(stroke
				(width 0.1)
				(type default)
			)
			(layer "F.SilkS")
		)
		(fp_line
			(start 22.874224 -4.225036)
			(end 23.933658 -5.241036)
			(stroke
				(width 0.1)
				(type default)
			)
			(layer "F.SilkS")
		)
		(fp_line
			(start 22.874224 -4.225036)
			(end 23.933658 -5.241036)
			(stroke
				(width 0.1)
				(type default)
			)
			(layer "F.SilkS")
		)
		(fp_line
			(start 22.87651 -0.821436)
			(end 23.916894 -1.819656)
			(stroke
				(width 0.1)
				(type default)
			)
			(layer "F.SilkS")
		)
		(fp_line
			(start 22.87651 -0.821436)
			(end 23.916894 -1.819656)
			(stroke
				(width 0.1)
				(type default)
			)
			(layer "F.SilkS")
		)
		(fp_line
			(start 22.89048 -4.182618)
			(end 22.906482 -4.139946)
			(stroke
				(width 0.1)
				(type default)
			)
			(layer "F.SilkS")
		)
		(fp_line
			(start 22.89048 -4.182618)
			(end 22.906482 -4.139946)
			(stroke
				(width 0.1)
				(type default)
			)
			(layer "F.SilkS")
		)
		(fp_line
			(start 22.89048 -4.182618)
			(end 24.000206 -5.246878)
			(stroke
				(width 0.1)
				(type default)
			)
			(layer "F.SilkS")
		)
		(fp_line
			(start 22.89048 -4.182618)
			(end 24.000206 -5.246878)
			(stroke
				(width 0.1)
				(type default)
			)
			(layer "F.SilkS")
		)
		(fp_line
			(start 22.906482 -4.139946)
			(end 22.92223 -4.097782)
			(stroke
				(width 0.1)
				(type default)
			)
			(layer "F.SilkS")
		)
		(fp_line
			(start 22.906482 -4.139946)
			(end 22.92223 -4.097782)
			(stroke
				(width 0.1)
				(type default)
			)
			(layer "F.SilkS")
		)
		(fp_line
			(start 22.906482 -4.139946)
			(end 24.066246 -5.252974)
			(stroke
				(width 0.1)
				(type default)
			)
			(layer "F.SilkS")
		)
		(fp_line
			(start 22.906482 -4.139946)
			(end 24.066246 -5.252974)
			(stroke
				(width 0.1)
				(type default)
			)
			(layer "F.SilkS")
		)
		(fp_line
			(start 22.92223 -4.097782)
			(end 22.938486 -4.055364)
			(stroke
				(width 0.1)
				(type default)
			)
			(layer "F.SilkS")
		)
		(fp_line
			(start 22.92223 -4.097782)
			(end 22.938486 -4.055364)
			(stroke
				(width 0.1)
				(type default)
			)
			(layer "F.SilkS")
		)
		(fp_line
			(start 22.92223 -4.097782)
			(end 24.129492 -5.255768)
			(stroke
				(width 0.1)
				(type default)
			)
			(layer "F.SilkS")
		)
		(fp_line
			(start 22.92223 -4.097782)
			(end 24.129492 -5.255768)
			(stroke
				(width 0.1)
				(type default)
			)
			(layer "F.SilkS")
		)
		(fp_line
			(start 22.927818 -0.813308)
			(end 24.013668 -1.854962)
			(stroke
				(width 0.1)
				(type default)
			)
			(layer "F.SilkS")
		)
		(fp_line
			(start 22.927818 -0.813308)
			(end 24.013668 -1.854962)
			(stroke
				(width 0.1)
				(type default)
			)
			(layer "F.SilkS")
		)
		(fp_line
			(start 22.938486 -4.055364)
			(end 24.191468 -5.257546)
			(stroke
				(width 0.1)
				(type default)
			)
			(layer "F.SilkS")
		)
		(fp_line
			(start 22.938486 -4.055364)
			(end 24.191468 -5.257546)
			(stroke
				(width 0.1)
				(type default)
			)
			(layer "F.SilkS")
		)
		(fp_line
			(start 22.981158 -0.806704)
			(end 24.158956 -1.93675)
			(stroke
				(width 0.1)
				(type default)
			)
			(layer "F.SilkS")
		)
		(fp_line
			(start 22.981158 -0.806704)
			(end 24.158956 -1.93675)
			(stroke
				(width 0.1)
				(type default)
			)
			(layer "F.SilkS")
		)
		(fp_line
			(start 23.029672 -4.085336)
			(end 24.253444 -5.25907)
			(stroke
				(width 0.1)
				(type default)
			)
			(layer "F.SilkS")
		)
		(fp_line
			(start 23.029672 -4.085336)
			(end 24.253444 -5.25907)
			(stroke
				(width 0.1)
				(type default)
			)
			(layer "F.SilkS")
		)
		(fp_line
			(start 23.091394 -0.797052)
			(end 25.733502 -3.331464)
			(stroke
				(width 0.1)
				(type default)
			)
			(layer "F.SilkS")
		)
		(fp_line
			(start 23.091394 -0.797052)
			(end 25.733502 -3.331464)
			(stroke
				(width 0.1)
				(type default)
			)
			(layer "F.SilkS")
		)
		(fp_line
			(start 23.143718 -4.136898)
			(end 24.31542 -5.260848)
			(stroke
				(width 0.1)
				(type default)
			)
			(layer "F.SilkS")
		)
		(fp_line
			(start 23.143718 -4.136898)
			(end 24.31542 -5.260848)
			(stroke
				(width 0.1)
				(type default)
			)
			(layer "F.SilkS")
		)
		(fp_line
			(start 23.149306 -0.79502)
			(end 25.721056 -3.262122)
			(stroke
				(width 0.1)
				(type default)
			)
			(layer "F.SilkS")
		)
		(fp_line
			(start 23.149306 -0.79502)
			(end 25.721056 -3.262122)
			(stroke
				(width 0.1)
				(type default)
			)
			(layer "F.SilkS")
		)
		(fp_line
			(start 23.208488 -0.794258)
			(end 25.708864 -3.19278)
			(stroke
				(width 0.1)
				(type default)
			)
			(layer "F.SilkS")
		)
		(fp_line
			(start 23.208488 -0.794258)
			(end 25.708864 -3.19278)
			(stroke
				(width 0.1)
				(type default)
			)
			(layer "F.SilkS")
		)
		(fp_line
			(start 23.23084 -2.720086)
			(end 24.256492 -3.704082)
			(stroke
				(width 0.1)
				(type default)
			)
			(layer "F.SilkS")
		)
		(fp_line
			(start 23.23084 -2.720086)
			(end 24.256492 -3.704082)
			(stroke
				(width 0.1)
				(type default)
			)
			(layer "F.SilkS")
		)
		(fp_line
			(start 23.249382 -4.180586)
			(end 24.372824 -5.258562)
			(stroke
				(width 0.1)
				(type default)
			)
			(layer "F.SilkS")
		)
		(fp_line
			(start 23.249382 -4.180586)
			(end 24.372824 -5.258562)
			(stroke
				(width 0.1)
				(type default)
			)
			(layer "F.SilkS")
		)
		(fp_line
			(start 23.275798 -0.800608)
			(end 25.696926 -3.123184)
			(stroke
				(width 0.1)
				(type default)
			)
			(layer "F.SilkS")
		)
		(fp_line
			(start 23.275798 -0.800608)
			(end 25.696926 -3.123184)
			(stroke
				(width 0.1)
				(type default)
			)
			(layer "F.SilkS")
		)
		(fp_line
			(start 23.3426 -0.807466)
			(end 25.68448 -3.054096)
			(stroke
				(width 0.1)
				(type default)
			)
			(layer "F.SilkS")
		)
		(fp_line
			(start 23.3426 -0.807466)
			(end 25.68448 -3.054096)
			(stroke
				(width 0.1)
				(type default)
			)
			(layer "F.SilkS")
		)
		(fp_line
			(start 23.344632 -4.214114)
			(end 24.429212 -5.254752)
			(stroke
				(width 0.1)
				(type default)
			)
			(layer "F.SilkS")
		)
		(fp_line
			(start 23.344632 -4.214114)
			(end 24.429212 -5.254752)
			(stroke
				(width 0.1)
				(type default)
			)
			(layer "F.SilkS")
		)
		(fp_line
			(start 23.34895 -2.775712)
			(end 24.307546 -3.695192)
			(stroke
				(width 0.1)
				(type default)
			)
			(layer "F.SilkS")
		)
		(fp_line
			(start 23.34895 -2.775712)
			(end 24.307546 -3.695192)
			(stroke
				(width 0.1)
				(type default)
			)
			(layer "F.SilkS")
		)
		(fp_line
			(start 23.409402 -0.813562)
			(end 25.672542 -2.984754)
			(stroke
				(width 0.1)
				(type default)
			)
			(layer "F.SilkS")
		)
		(fp_line
			(start 23.409402 -0.813562)
			(end 25.672542 -2.984754)
			(stroke
				(width 0.1)
				(type default)
			)
			(layer "F.SilkS")
		)
		(fp_line
			(start 23.46071 -2.825242)
			(end 24.35606 -3.684016)
			(stroke
				(width 0.1)
				(type default)
			)
			(layer "F.SilkS")
		)
		(fp_line
			(start 23.46071 -2.825242)
			(end 24.35606 -3.684016)
			(stroke
				(width 0.1)
				(type default)
			)
			(layer "F.SilkS")
		)
		(fp_line
			(start 23.476458 -0.82042)
			(end 25.66035 -2.915412)
			(stroke
				(width 0.1)
				(type default)
			)
			(layer "F.SilkS")
		)
		(fp_line
			(start 23.476458 -0.82042)
			(end 25.66035 -2.915412)
			(stroke
				(width 0.1)
				(type default)
			)
			(layer "F.SilkS")
		)
		(fp_line
			(start 23.530052 -2.833878)
			(end 24.401272 -3.669538)
			(stroke
				(width 0.1)
				(type default)
			)
			(layer "F.SilkS")
		)
		(fp_line
			(start 23.530052 -2.833878)
			(end 24.401272 -3.669538)
			(stroke
				(width 0.1)
				(type default)
			)
			(layer "F.SilkS")
		)
		(fp_line
			(start 23.557484 -0.840232)
			(end 25.648412 -2.845816)
			(stroke
				(width 0.1)
				(type default)
			)
			(layer "F.SilkS")
		)
		(fp_line
			(start 23.557484 -0.840232)
			(end 25.648412 -2.845816)
			(stroke
				(width 0.1)
				(type default)
			)
			(layer "F.SilkS")
		)
		(fp_line
			(start 23.642828 -0.864616)
			(end 25.635966 -2.776474)
			(stroke
				(width 0.1)
				(type default)
			)
			(layer "F.SilkS")
		)
		(fp_line
			(start 23.642828 -0.864616)
			(end 25.635966 -2.776474)
			(stroke
				(width 0.1)
				(type default)
			)
			(layer "F.SilkS")
		)
		(fp_line
			(start 23.683468 -3.731514)
			(end 21.836634 -1.95961)
			(stroke
				(width 0.1)
				(type default)
			)
			(layer "F.SilkS")
		)
		(fp_line
			(start 23.683468 -3.731514)
			(end 21.836634 -1.95961)
			(stroke
				(width 0.1)
				(type default)
			)
			(layer "F.SilkS")
		)
		(fp_line
			(start 23.728426 -0.888746)
			(end 25.623774 -2.707132)
			(stroke
				(width 0.1)
				(type default)
			)
			(layer "F.SilkS")
		)
		(fp_line
			(start 23.728426 -0.888746)
			(end 25.623774 -2.707132)
			(stroke
				(width 0.1)
				(type default)
			)
			(layer "F.SilkS")
		)
		(fp_line
			(start 23.831296 -0.929894)
			(end 25.611836 -2.63779)
			(stroke
				(width 0.1)
				(type default)
			)
			(layer "F.SilkS")
		)
		(fp_line
			(start 23.831296 -0.929894)
			(end 25.611836 -2.63779)
			(stroke
				(width 0.1)
				(type default)
			)
			(layer "F.SilkS")
		)
		(fp_line
			(start 23.951692 -0.987552)
			(end 25.59939 -2.568194)
			(stroke
				(width 0.1)
				(type default)
			)
			(layer "F.SilkS")
		)
		(fp_line
			(start 23.951692 -0.987552)
			(end 25.59939 -2.568194)
			(stroke
				(width 0.1)
				(type default)
			)
			(layer "F.SilkS")
		)
		(fp_line
			(start 24.122888 -1.094232)
			(end 25.587452 -2.498852)
			(stroke
				(width 0.1)
				(type default)
			)
			(layer "F.SilkS")
		)
		(fp_line
			(start 24.122888 -1.094232)
			(end 25.587452 -2.498852)
			(stroke
				(width 0.1)
				(type default)
			)
			(layer "F.SilkS")
		)
		(fp_line
			(start 24.17699 -0.882904)
			(end 24.203406 -0.882904)
			(stroke
				(width 0.1)
				(type default)
			)
			(layer "F.SilkS")
		)
		(fp_line
			(start 24.17699 -0.882904)
			(end 24.203406 -0.882904)
			(stroke
				(width 0.1)
				(type default)
			)
			(layer "F.SilkS")
		)
		(fp_line
			(start 24.183848 -0.921512)
			(end 24.17699 -0.882904)
			(stroke
				(width 0.1)
				(type default)
			)
			(layer "F.SilkS")
		)
		(fp_line
			(start 24.183848 -0.921512)
			(end 24.17699 -0.882904)
			(stroke
				(width 0.1)
				(type default)
			)
			(layer "F.SilkS")
		)
		(fp_line
			(start 24.183848 -0.921512)
			(end 25.538684 -2.221484)
			(stroke
				(width 0.1)
				(type default)
			)
			(layer "F.SilkS")
		)
		(fp_line
			(start 24.183848 -0.921512)
			(end 25.538684 -2.221484)
			(stroke
				(width 0.1)
				(type default)
			)
			(layer "F.SilkS")
		)
		(fp_line
			(start 24.195786 -0.991108)
			(end 24.183848 -0.921512)
			(stroke
				(width 0.1)
				(type default)
			)
			(layer "F.SilkS")
		)
		(fp_line
			(start 24.195786 -0.991108)
			(end 24.183848 -0.921512)
			(stroke
				(width 0.1)
				(type default)
			)
			(layer "F.SilkS")
		)
		(fp_line
			(start 24.195786 -0.991108)
			(end 25.550876 -2.290826)
			(stroke
				(width 0.1)
				(type default)
			)
			(layer "F.SilkS")
		)
		(fp_line
			(start 24.195786 -0.991108)
			(end 25.550876 -2.290826)
			(stroke
				(width 0.1)
				(type default)
			)
			(layer "F.SilkS")
		)
		(fp_line
			(start 24.203406 -0.882904)
			(end 24.263858 -0.882904)
			(stroke
				(width 0.1)
				(type default)
			)
			(layer "F.SilkS")
		)
		(fp_line
			(start 24.203406 -0.882904)
			(end 24.263858 -0.882904)
			(stroke
				(width 0.1)
				(type default)
			)
			(layer "F.SilkS")
		)
		(fp_line
			(start 24.203406 -0.882904)
			(end 25.526746 -2.152142)
			(stroke
				(width 0.1)
				(type default)
			)
			(layer "F.SilkS")
		)
		(fp_line
			(start 24.203406 -0.882904)
			(end 25.526746 -2.152142)
			(stroke
				(width 0.1)
				(type default)
			)
			(layer "F.SilkS")
		)
		(fp_line
			(start 24.208232 -1.06045)
			(end 24.195786 -0.991108)
			(stroke
				(width 0.1)
				(type default)
			)
			(layer "F.SilkS")
		)
		(fp_line
			(start 24.208232 -1.06045)
			(end 24.195786 -0.991108)
			(stroke
				(width 0.1)
				(type default)
			)
			(layer "F.SilkS")
		)
		(fp_line
			(start 24.208232 -1.06045)
			(end 25.563322 -2.360422)
			(stroke
				(width 0.1)
				(type default)
			)
			(layer "F.SilkS")
		)
		(fp_line
			(start 24.208232 -1.06045)
			(end 25.563322 -2.360422)
			(stroke
				(width 0.1)
				(type default)
			)
			(layer "F.SilkS")
		)
		(fp_line
			(start 24.220424 -1.130046)
			(end 24.208232 -1.06045)
			(stroke
				(width 0.1)
				(type default)
			)
			(layer "F.SilkS")
		)
		(fp_line
			(start 24.220424 -1.130046)
			(end 24.208232 -1.06045)
			(stroke
				(width 0.1)
				(type default)
			)
			(layer "F.SilkS")
		)
		(fp_line
			(start 24.263858 -0.882904)
			(end 24.324056 -0.882904)
			(stroke
				(width 0.1)
				(type default)
			)
			(layer "F.SilkS")
		)
		(fp_line
			(start 24.263858 -0.882904)
			(end 24.324056 -0.882904)
			(stroke
				(width 0.1)
				(type default)
			)
			(layer "F.SilkS")
		)
		(fp_line
			(start 24.263858 -0.882904)
			(end 25.5143 -2.0828)
			(stroke
				(width 0.1)
				(type default)
			)
			(layer "F.SilkS")
		)
		(fp_line
			(start 24.263858 -0.882904)
			(end 25.5143 -2.0828)
			(stroke
				(width 0.1)
				(type default)
			)
			(layer "F.SilkS")
		)
		(fp_line
			(start 24.324056 -0.882904)
			(end 24.384 -0.882904)
			(stroke
				(width 0.1)
				(type default)
			)
			(layer "F.SilkS")
		)
		(fp_line
			(start 24.324056 -0.882904)
			(end 24.384 -0.882904)
			(stroke
				(width 0.1)
				(type default)
			)
			(layer "F.SilkS")
		)
		(fp_line
			(start 24.324056 -0.882904)
			(end 25.502362 -2.013204)
			(stroke
				(width 0.1)
				(type default)
			)
			(layer "F.SilkS")
		)
		(fp_line
			(start 24.324056 -0.882904)
			(end 25.502362 -2.013204)
			(stroke
				(width 0.1)
				(type default)
			)
			(layer "F.SilkS")
		)
		(fp_line
			(start 24.384 -0.882904)
			(end 24.443944 -0.882904)
			(stroke
				(width 0.1)
				(type default)
			)
			(layer "F.SilkS")
		)
		(fp_line
			(start 24.384 -0.882904)
			(end 24.443944 -0.882904)
			(stroke
				(width 0.1)
				(type default)
			)
			(layer "F.SilkS")
		)
		(fp_line
			(start 24.384 -0.882904)
			(end 25.49017 -1.943862)
			(stroke
				(width 0.1)
				(type default)
			)
			(layer "F.SilkS")
		)
		(fp_line
			(start 24.384 -0.882904)
			(end 25.49017 -1.943862)
			(stroke
				(width 0.1)
				(type default)
			)
			(layer "F.SilkS")
		)
		(fp_line
			(start 24.414988 -2.24028)
			(end 24.402796 -2.170938)
			(stroke
				(width 0.1)
				(type default)
			)
			(layer "F.SilkS")
		)
		(fp_line
			(start 24.414988 -2.24028)
			(end 24.402796 -2.170938)
			(stroke
				(width 0.1)
				(type default)
			)
			(layer "F.SilkS")
		)
		(fp_line
			(start 24.427434 -2.309368)
			(end 24.414988 -2.24028)
			(stroke
				(width 0.1)
				(type default)
			)
			(layer "F.SilkS")
		)
		(fp_line
			(start 24.427434 -2.309368)
			(end 24.414988 -2.24028)
			(stroke
				(width 0.1)
				(type default)
			)
			(layer "F.SilkS")
		)
		(fp_line
			(start 24.439372 -2.37871)
			(end 24.427434 -2.309368)
			(stroke
				(width 0.1)
				(type default)
			)
			(layer "F.SilkS")
		)
		(fp_line
			(start 24.439372 -2.37871)
			(end 24.427434 -2.309368)
			(stroke
				(width 0.1)
				(type default)
			)
			(layer "F.SilkS")
		)
		(fp_line
			(start 24.443944 -0.882904)
			(end 24.504142 -0.882904)
			(stroke
				(width 0.1)
				(type default)
			)
			(layer "F.SilkS")
		)
		(fp_line
			(start 24.443944 -0.882904)
			(end 24.504142 -0.882904)
			(stroke
				(width 0.1)
				(type default)
			)
			(layer "F.SilkS")
		)
		(fp_line
			(start 24.443944 -0.882904)
			(end 25.478232 -1.874774)
			(stroke
				(width 0.1)
				(type default)
			)
			(layer "F.SilkS")
		)
		(fp_line
			(start 24.443944 -0.882904)
			(end 25.478232 -1.874774)
			(stroke
				(width 0.1)
				(type default)
			)
			(layer "F.SilkS")
		)
		(fp_line
			(start 24.44623 -3.655568)
			(end 23.598886 -2.842514)
			(stroke
				(width 0.1)
				(type default)
			)
			(layer "F.SilkS")
		)
		(fp_line
			(start 24.44623 -3.655568)
			(end 23.598886 -2.842514)
			(stroke
				(width 0.1)
				(type default)
			)
			(layer "F.SilkS")
		)
		(fp_line
			(start 24.451564 -2.448306)
			(end 24.439372 -2.37871)
			(stroke
				(width 0.1)
				(type default)
			)
			(layer "F.SilkS")
		)
		(fp_line
			(start 24.451564 -2.448306)
			(end 24.439372 -2.37871)
			(stroke
				(width 0.1)
				(type default)
			)
			(layer "F.SilkS")
		)
		(fp_line
			(start 24.46401 -2.517648)
			(end 24.451564 -2.448306)
			(stroke
				(width 0.1)
				(type default)
			)
			(layer "F.SilkS")
		)
		(fp_line
			(start 24.46401 -2.517648)
			(end 24.451564 -2.448306)
			(stroke
				(width 0.1)
				(type default)
			)
			(layer "F.SilkS")
		)
		(fp_line
			(start 24.475948 -2.58699)
			(end 24.46401 -2.517648)
			(stroke
				(width 0.1)
				(type default)
			)
			(layer "F.SilkS")
		)
		(fp_line
			(start 24.475948 -2.58699)
			(end 24.46401 -2.517648)
			(stroke
				(width 0.1)
				(type default)
			)
			(layer "F.SilkS")
		)
		(fp_line
			(start 24.485346 -5.250942)
			(end 23.433532 -4.2418)
			(stroke
				(width 0.1)
				(type default)
			)
			(layer "F.SilkS")
		)
		(fp_line
			(start 24.485346 -5.250942)
			(end 23.433532 -4.2418)
			(stroke
				(width 0.1)
				(type default)
			)
			(layer "F.SilkS")
		)
		(fp_line
			(start 24.487886 -2.656332)
			(end 24.475948 -2.58699)
			(stroke
				(width 0.1)
				(type default)
			)
			(layer "F.SilkS")
		)
		(fp_line
			(start 24.487886 -2.656332)
			(end 24.475948 -2.58699)
			(stroke
				(width 0.1)
				(type default)
			)
			(layer "F.SilkS")
		)
		(fp_line
			(start 24.491696 -3.64109)
			(end 23.668482 -2.85115)
			(stroke
				(width 0.1)
				(type default)
			)
			(layer "F.SilkS")
		)
		(fp_line
			(start 24.491696 -3.64109)
			(end 23.668482 -2.85115)
			(stroke
				(width 0.1)
				(type default)
			)
			(layer "F.SilkS")
		)
		(fp_line
			(start 24.504142 -0.882904)
			(end 24.564594 -0.882904)
			(stroke
				(width 0.1)
				(type default)
			)
			(layer "F.SilkS")
		)
		(fp_line
			(start 24.504142 -0.882904)
			(end 24.564594 -0.882904)
			(stroke
				(width 0.1)
				(type default)
			)
			(layer "F.SilkS")
		)
		(fp_line
			(start 24.504142 -0.882904)
			(end 25.465786 -1.805178)
			(stroke
				(width 0.1)
				(type default)
			)
			(layer "F.SilkS")
		)
		(fp_line
			(start 24.504142 -0.882904)
			(end 25.465786 -1.805178)
			(stroke
				(width 0.1)
				(type default)
			)
			(layer "F.SilkS")
		)
		(fp_line
			(start 24.534114 -3.624072)
			(end 23.73757 -2.859786)
			(stroke
				(width 0.1)
				(type default)
			)
			(layer "F.SilkS")
		)
		(fp_line
			(start 24.534114 -3.624072)
			(end 23.73757 -2.859786)
			(stroke
				(width 0.1)
				(type default)
			)
			(layer "F.SilkS")
		)
		(fp_line
			(start 24.541734 -5.246878)
			(end 23.518114 -4.265168)
			(stroke
				(width 0.1)
				(type default)
			)
			(layer "F.SilkS")
		)
		(fp_line
			(start 24.541734 -5.246878)
			(end 23.518114 -4.265168)
			(stroke
				(width 0.1)
				(type default)
			)
			(layer "F.SilkS")
		)
		(fp_line
			(start 24.564594 -0.882904)
			(end 24.624538 -0.882904)
			(stroke
				(width 0.1)
				(type default)
			)
			(layer "F.SilkS")
		)
		(fp_line
			(start 24.564594 -0.882904)
			(end 24.624538 -0.882904)
			(stroke
				(width 0.1)
				(type default)
			)
			(layer "F.SilkS")
		)
		(fp_line
			(start 24.564594 -0.882904)
			(end 25.453594 -1.735836)
			(stroke
				(width 0.1)
				(type default)
			)
			(layer "F.SilkS")
		)
		(fp_line
			(start 24.564594 -0.882904)
			(end 25.453594 -1.735836)
			(stroke
				(width 0.1)
				(type default)
			)
			(layer "F.SilkS")
		)
		(fp_line
			(start 24.5745 -3.605276)
			(end 23.797006 -2.859024)
			(stroke
				(width 0.1)
				(type default)
			)
			(layer "F.SilkS")
		)
		(fp_line
			(start 24.5745 -3.605276)
			(end 23.797006 -2.859024)
			(stroke
				(width 0.1)
				(type default)
			)
			(layer "F.SilkS")
		)
		(fp_line
			(start 24.597614 -5.243068)
			(end 23.594822 -4.280916)
			(stroke
				(width 0.1)
				(type default)
			)
			(layer "F.SilkS")
		)
		(fp_line
			(start 24.597614 -5.243068)
			(end 23.594822 -4.280916)
			(stroke
				(width 0.1)
				(type default)
			)
			(layer "F.SilkS")
		)
		(fp_line
			(start 24.614886 -3.586226)
			(end 23.855426 -2.857754)
			(stroke
				(width 0.1)
				(type default)
			)
			(layer "F.SilkS")
		)
		(fp_line
			(start 24.614886 -3.586226)
			(end 23.855426 -2.857754)
			(stroke
				(width 0.1)
				(type default)
			)
			(layer "F.SilkS")
		)
		(fp_line
			(start 24.624538 -0.882904)
			(end 24.684736 -0.882904)
			(stroke
				(width 0.1)
				(type default)
			)
			(layer "F.SilkS")
		)
		(fp_line
			(start 24.624538 -0.882904)
			(end 24.684736 -0.882904)
			(stroke
				(width 0.1)
				(type default)
			)
			(layer "F.SilkS")
		)
		(fp_line
			(start 24.624538 -0.882904)
			(end 25.441656 -1.666494)
			(stroke
				(width 0.1)
				(type default)
			)
			(layer "F.SilkS")
		)
		(fp_line
			(start 24.624538 -0.882904)
			(end 25.441656 -1.666494)
			(stroke
				(width 0.1)
				(type default)
			)
			(layer "F.SilkS")
		)
		(fp_line
			(start 24.653748 -5.239258)
			(end 23.67026 -4.295902)
			(stroke
				(width 0.1)
				(type default)
			)
			(layer "F.SilkS")
		)
		(fp_line
			(start 24.653748 -5.239258)
			(end 23.67026 -4.295902)
			(stroke
				(width 0.1)
				(type default)
			)
			(layer "F.SilkS")
		)
		(fp_line
			(start 24.67102 -3.697478)
			(end 24.658574 -3.627882)
			(stroke
				(width 0.1)
				(type default)
			)
			(layer "F.SilkS")
		)
		(fp_line
			(start 24.67102 -3.697478)
			(end 24.658574 -3.627882)
			(stroke
				(width 0.1)
				(type default)
			)
			(layer "F.SilkS")
		)
		(fp_line
			(start 24.682958 -3.76682)
			(end 24.67102 -3.697478)
			(stroke
				(width 0.1)
				(type default)
			)
			(layer "F.SilkS")
		)
		(fp_line
			(start 24.682958 -3.76682)
			(end 24.67102 -3.697478)
			(stroke
				(width 0.1)
				(type default)
			)
			(layer "F.SilkS")
		)
		(fp_line
			(start 24.684736 -0.882904)
			(end 24.744934 -0.882904)
			(stroke
				(width 0.1)
				(type default)
			)
			(layer "F.SilkS")
		)
		(fp_line
			(start 24.684736 -0.882904)
			(end 24.744934 -0.882904)
			(stroke
				(width 0.1)
				(type default)
			)
			(layer "F.SilkS")
		)
		(fp_line
			(start 24.684736 -0.882904)
			(end 25.42921 -1.597406)
			(stroke
				(width 0.1)
				(type default)
			)
			(layer "F.SilkS")
		)
		(fp_line
			(start 24.684736 -0.882904)
			(end 25.42921 -1.597406)
			(stroke
				(width 0.1)
				(type default)
			)
			(layer "F.SilkS")
		)
		(fp_line
			(start 24.708866 -5.234432)
			(end 23.739856 -4.304792)
			(stroke
				(width 0.1)
				(type default)
			)
			(layer "F.SilkS")
		)
		(fp_line
			(start 24.708866 -5.234432)
			(end 23.739856 -4.304792)
			(stroke
				(width 0.1)
				(type default)
			)
			(layer "F.SilkS")
		)
		(fp_line
			(start 24.744934 -0.882904)
			(end 24.805386 -0.882904)
			(stroke
				(width 0.1)
				(type default)
			)
			(layer "F.SilkS")
		)
		(fp_line
			(start 24.744934 -0.882904)
			(end 24.805386 -0.882904)
			(stroke
				(width 0.1)
				(type default)
			)
			(layer "F.SilkS")
		)
		(fp_line
			(start 24.744934 -0.882904)
			(end 25.417272 -1.52781)
			(stroke
				(width 0.1)
				(type default)
			)
			(layer "F.SilkS")
		)
		(fp_line
			(start 24.744934 -0.882904)
			(end 25.417272 -1.52781)
			(stroke
				(width 0.1)
				(type default)
			)
			(layer "F.SilkS")
		)
		(fp_line
			(start 24.75738 -5.223256)
			(end 23.809452 -4.313936)
			(stroke
				(width 0.1)
				(type default)
			)
			(layer "F.SilkS")
		)
		(fp_line
			(start 24.75738 -5.223256)
			(end 23.809452 -4.313936)
			(stroke
				(width 0.1)
				(type default)
			)
			(layer "F.SilkS")
		)
		(fp_line
			(start 24.805386 -0.882904)
			(end 24.86533 -0.882904)
			(stroke
				(width 0.1)
				(type default)
			)
			(layer "F.SilkS")
		)
		(fp_line
			(start 24.805386 -0.882904)
			(end 24.86533 -0.882904)
			(stroke
				(width 0.1)
				(type default)
			)
			(layer "F.SilkS")
		)
		(fp_line
			(start 24.805386 -0.882904)
			(end 25.40508 -1.458214)
			(stroke
				(width 0.1)
				(type default)
			)
			(layer "F.SilkS")
		)
		(fp_line
			(start 24.805386 -0.882904)
			(end 25.40508 -1.458214)
			(stroke
				(width 0.1)
				(type default)
			)
			(layer "F.SilkS")
		)
		(fp_line
			(start 24.805894 -5.21208)
			(end 23.87473 -4.318762)
			(stroke
				(width 0.1)
				(type default)
			)
			(layer "F.SilkS")
		)
		(fp_line
			(start 24.805894 -5.21208)
			(end 23.87473 -4.318762)
			(stroke
				(width 0.1)
				(type default)
			)
			(layer "F.SilkS")
		)
		(fp_line
			(start 24.854154 -5.200904)
			(end 23.9395 -4.323334)
			(stroke
				(width 0.1)
				(type default)
			)
			(layer "F.SilkS")
		)
		(fp_line
			(start 24.854154 -5.200904)
			(end 23.9395 -4.323334)
			(stroke
				(width 0.1)
				(type default)
			)
			(layer "F.SilkS")
		)
		(fp_line
			(start 24.86533 -0.882904)
			(end 24.925274 -0.882904)
			(stroke
				(width 0.1)
				(type default)
			)
			(layer "F.SilkS")
		)
		(fp_line
			(start 24.86533 -0.882904)
			(end 24.925274 -0.882904)
			(stroke
				(width 0.1)
				(type default)
			)
			(layer "F.SilkS")
		)
		(fp_line
			(start 24.86533 -0.882904)
			(end 25.392634 -1.388872)
			(stroke
				(width 0.1)
				(type default)
			)
			(layer "F.SilkS")
		)
		(fp_line
			(start 24.86533 -0.882904)
			(end 25.392634 -1.388872)
			(stroke
				(width 0.1)
				(type default)
			)
			(layer "F.SilkS")
		)
		(fp_line
			(start 24.903176 -5.189728)
			(end 24.003254 -4.32689)
			(stroke
				(width 0.1)
				(type default)
			)
			(layer "F.SilkS")
		)
		(fp_line
			(start 24.903176 -5.189728)
			(end 24.003254 -4.32689)
			(stroke
				(width 0.1)
				(type default)
			)
			(layer "F.SilkS")
		)
		(fp_line
			(start 24.925274 -0.882904)
			(end 24.985472 -0.882904)
			(stroke
				(width 0.1)
				(type default)
			)
			(layer "F.SilkS")
		)
		(fp_line
			(start 24.925274 -0.882904)
			(end 24.985472 -0.882904)
			(stroke
				(width 0.1)
				(type default)
			)
			(layer "F.SilkS")
		)
		(fp_line
			(start 24.925274 -0.882904)
			(end 25.380696 -1.319784)
			(stroke
				(width 0.1)
				(type default)
			)
			(layer "F.SilkS")
		)
		(fp_line
			(start 24.925274 -0.882904)
			(end 25.380696 -1.319784)
			(stroke
				(width 0.1)
				(type default)
			)
			(layer "F.SilkS")
		)
		(fp_line
			(start 24.95169 -5.178552)
			(end 24.064976 -4.327906)
			(stroke
				(width 0.1)
				(type default)
			)
			(layer "F.SilkS")
		)
		(fp_line
			(start 24.95169 -5.178552)
			(end 24.064976 -4.327906)
			(stroke
				(width 0.1)
				(type default)
			)
			(layer "F.SilkS")
		)
		(fp_line
			(start 24.985472 -0.882904)
			(end 25.04567 -0.882904)
			(stroke
				(width 0.1)
				(type default)
			)
			(layer "F.SilkS")
		)
		(fp_line
			(start 24.985472 -0.882904)
			(end 25.04567 -0.882904)
			(stroke
				(width 0.1)
				(type default)
			)
			(layer "F.SilkS")
		)
		(fp_line
			(start 24.985472 -0.882904)
			(end 25.368504 -1.250188)
			(stroke
				(width 0.1)
				(type default)
			)
			(layer "F.SilkS")
		)
		(fp_line
			(start 24.985472 -0.882904)
			(end 25.368504 -1.250188)
			(stroke
				(width 0.1)
				(type default)
			)
			(layer "F.SilkS")
		)
		(fp_line
			(start 24.99995 -5.16763)
			(end 24.12619 -4.329176)
			(stroke
				(width 0.1)
				(type default)
			)
			(layer "F.SilkS")
		)
		(fp_line
			(start 24.99995 -5.16763)
			(end 24.12619 -4.329176)
			(stroke
				(width 0.1)
				(type default)
			)
			(layer "F.SilkS")
		)
		(fp_line
			(start 25.045162 -5.152898)
			(end 24.18588 -4.328922)
			(stroke
				(width 0.1)
				(type default)
			)
			(layer "F.SilkS")
		)
		(fp_line
			(start 25.045162 -5.152898)
			(end 24.18588 -4.328922)
			(stroke
				(width 0.1)
				(type default)
			)
			(layer "F.SilkS")
		)
		(fp_line
			(start 25.04567 -0.882904)
			(end 25.106122 -0.882904)
			(stroke
				(width 0.1)
				(type default)
			)
			(layer "F.SilkS")
		)
		(fp_line
			(start 25.04567 -0.882904)
			(end 25.106122 -0.882904)
			(stroke
				(width 0.1)
				(type default)
			)
			(layer "F.SilkS")
		)
		(fp_line
			(start 25.04567 -0.882904)
			(end 25.356058 -1.180592)
			(stroke
				(width 0.1)
				(type default)
			)
			(layer "F.SilkS")
		)
		(fp_line
			(start 25.04567 -0.882904)
			(end 25.356058 -1.180592)
			(stroke
				(width 0.1)
				(type default)
			)
			(layer "F.SilkS")
		)
		(fp_line
			(start 25.086056 -5.13461)
			(end 24.241252 -4.32435)
			(stroke
				(width 0.1)
				(type default)
			)
			(layer "F.SilkS")
		)
		(fp_line
			(start 25.086056 -5.13461)
			(end 24.241252 -4.32435)
			(stroke
				(width 0.1)
				(type default)
			)
			(layer "F.SilkS")
		)
		(fp_line
			(start 25.106122 -0.882904)
			(end 25.166066 -0.882904)
			(stroke
				(width 0.1)
				(type default)
			)
			(layer "F.SilkS")
		)
		(fp_line
			(start 25.106122 -0.882904)
			(end 25.166066 -0.882904)
			(stroke
				(width 0.1)
				(type default)
			)
			(layer "F.SilkS")
		)
		(fp_line
			(start 25.106122 -0.882904)
			(end 25.34412 -1.111504)
			(stroke
				(width 0.1)
				(type default)
			)
			(layer "F.SilkS")
		)
		(fp_line
			(start 25.106122 -0.882904)
			(end 25.34412 -1.111504)
			(stroke
				(width 0.1)
				(type default)
			)
			(layer "F.SilkS")
		)
		(fp_line
			(start 25.127458 -5.116322)
			(end 24.297132 -4.320032)
			(stroke
				(width 0.1)
				(type default)
			)
			(layer "F.SilkS")
		)
		(fp_line
			(start 25.127458 -5.116322)
			(end 24.297132 -4.320032)
			(stroke
				(width 0.1)
				(type default)
			)
			(layer "F.SilkS")
		)
		(fp_line
			(start 25.166066 -0.882904)
			(end 25.226264 -0.882904)
			(stroke
				(width 0.1)
				(type default)
			)
			(layer "F.SilkS")
		)
		(fp_line
			(start 25.166066 -0.882904)
			(end 25.226264 -0.882904)
			(stroke
				(width 0.1)
				(type default)
			)
			(layer "F.SilkS")
		)
		(fp_line
			(start 25.166066 -0.882904)
			(end 25.332182 -1.042416)
			(stroke
				(width 0.1)
				(type default)
			)
			(layer "F.SilkS")
		)
		(fp_line
			(start 25.166066 -0.882904)
			(end 25.332182 -1.042416)
			(stroke
				(width 0.1)
				(type default)
			)
			(layer "F.SilkS")
		)
		(fp_line
			(start 25.168352 -5.098034)
			(end 24.346408 -4.309618)
			(stroke
				(width 0.1)
				(type default)
			)
			(layer "F.SilkS")
		)
		(fp_line
			(start 25.168352 -5.098034)
			(end 24.346408 -4.309618)
			(stroke
				(width 0.1)
				(type default)
			)
			(layer "F.SilkS")
		)
		(fp_line
			(start 25.2095 -5.08)
			(end 24.393398 -4.296918)
			(stroke
				(width 0.1)
				(type default)
			)
			(layer "F.SilkS")
		)
		(fp_line
			(start 25.2095 -5.08)
			(end 24.393398 -4.296918)
			(stroke
				(width 0.1)
				(type default)
			)
			(layer "F.SilkS")
		)
		(fp_line
			(start 25.226264 -0.882904)
			(end 25.286462 -0.882904)
			(stroke
				(width 0.1)
				(type default)
			)
			(layer "F.SilkS")
		)
		(fp_line
			(start 25.226264 -0.882904)
			(end 25.286462 -0.882904)
			(stroke
				(width 0.1)
				(type default)
			)
			(layer "F.SilkS")
		)
		(fp_line
			(start 25.226264 -0.882904)
			(end 25.31999 -0.97282)
			(stroke
				(width 0.1)
				(type default)
			)
			(layer "F.SilkS")
		)
		(fp_line
			(start 25.226264 -0.882904)
			(end 25.31999 -0.97282)
			(stroke
				(width 0.1)
				(type default)
			)
			(layer "F.SilkS")
		)
		(fp_line
			(start 25.250648 -5.061712)
			(end 24.438356 -4.28244)
			(stroke
				(width 0.1)
				(type default)
			)
			(layer "F.SilkS")
		)
		(fp_line
			(start 25.250648 -5.061712)
			(end 24.438356 -4.28244)
			(stroke
				(width 0.1)
				(type default)
			)
			(layer "F.SilkS")
		)
		(fp_line
			(start 25.286462 -0.882904)
			(end 25.304242 -0.882904)
			(stroke
				(width 0.1)
				(type default)
			)
			(layer "F.SilkS")
		)
		(fp_line
			(start 25.286462 -0.882904)
			(end 25.304242 -0.882904)
			(stroke
				(width 0.1)
				(type default)
			)
			(layer "F.SilkS")
		)
		(fp_line
			(start 25.286462 -0.882904)
			(end 25.307544 -0.903224)
			(stroke
				(width 0.1)
				(type default)
			)
			(layer "F.SilkS")
		)
		(fp_line
			(start 25.286462 -0.882904)
			(end 25.307544 -0.903224)
			(stroke
				(width 0.1)
				(type default)
			)
			(layer "F.SilkS")
		)
		(fp_line
			(start 25.29205 -5.043424)
			(end 24.477726 -4.26212)
			(stroke
				(width 0.1)
				(type default)
			)
			(layer "F.SilkS")
		)
		(fp_line
			(start 25.29205 -5.043424)
			(end 24.477726 -4.26212)
			(stroke
				(width 0.1)
				(type default)
			)
			(layer "F.SilkS")
		)
		(fp_line
			(start 25.304242 -0.882904)
			(end 25.307544 -0.903224)
			(stroke
				(width 0.1)
				(type default)
			)
			(layer "F.SilkS")
		)
		(fp_line
			(start 25.304242 -0.882904)
			(end 25.307544 -0.903224)
			(stroke
				(width 0.1)
				(type default)
			)
			(layer "F.SilkS")
		)
		(fp_line
			(start 25.307544 -0.903224)
			(end 25.31999 -0.97282)
			(stroke
				(width 0.1)
				(type default)
			)
			(layer "F.SilkS")
		)
		(fp_line
			(start 25.307544 -0.903224)
			(end 25.31999 -0.97282)
			(stroke
				(width 0.1)
				(type default)
			)
			(layer "F.SilkS")
		)
		(fp_line
			(start 25.31999 -0.97282)
			(end 25.332182 -1.042416)
			(stroke
				(width 0.1)
				(type default)
			)
			(layer "F.SilkS")
		)
		(fp_line
			(start 25.31999 -0.97282)
			(end 25.332182 -1.042416)
			(stroke
				(width 0.1)
				(type default)
			)
			(layer "F.SilkS")
		)
		(fp_line
			(start 25.327356 -5.019294)
			(end 24.516334 -4.2418)
			(stroke
				(width 0.1)
				(type default)
			)
			(layer "F.SilkS")
		)
		(fp_line
			(start 25.327356 -5.019294)
			(end 24.516334 -4.2418)
			(stroke
				(width 0.1)
				(type default)
			)
			(layer "F.SilkS")
		)
		(fp_line
			(start 25.332182 -1.042416)
			(end 25.34412 -1.111504)
			(stroke
				(width 0.1)
				(type default)
			)
			(layer "F.SilkS")
		)
		(fp_line
			(start 25.332182 -1.042416)
			(end 25.34412 -1.111504)
			(stroke
				(width 0.1)
				(type default)
			)
			(layer "F.SilkS")
		)
		(fp_line
			(start 25.34412 -1.111504)
			(end 25.356058 -1.180592)
			(stroke
				(width 0.1)
				(type default)
			)
			(layer "F.SilkS")
		)
		(fp_line
			(start 25.34412 -1.111504)
			(end 25.356058 -1.180592)
			(stroke
				(width 0.1)
				(type default)
			)
			(layer "F.SilkS")
		)
		(fp_line
			(start 25.356058 -1.180592)
			(end 25.368504 -1.250188)
			(stroke
				(width 0.1)
				(type default)
			)
			(layer "F.SilkS")
		)
		(fp_line
			(start 25.356058 -1.180592)
			(end 25.368504 -1.250188)
			(stroke
				(width 0.1)
				(type default)
			)
			(layer "F.SilkS")
		)
		(fp_line
			(start 25.36063 -4.994148)
			(end 24.549354 -4.215892)
			(stroke
				(width 0.1)
				(type default)
			)
			(layer "F.SilkS")
		)
		(fp_line
			(start 25.36063 -4.994148)
			(end 24.549354 -4.215892)
			(stroke
				(width 0.1)
				(type default)
			)
			(layer "F.SilkS")
		)
		(fp_line
			(start 25.368504 -1.250188)
			(end 25.380696 -1.319784)
			(stroke
				(width 0.1)
				(type default)
			)
			(layer "F.SilkS")
		)
		(fp_line
			(start 25.368504 -1.250188)
			(end 25.380696 -1.319784)
			(stroke
				(width 0.1)
				(type default)
			)
			(layer "F.SilkS")
		)
		(fp_line
			(start 25.380696 -1.319784)
			(end 25.392634 -1.388872)
			(stroke
				(width 0.1)
				(type default)
			)
			(layer "F.SilkS")
		)
		(fp_line
			(start 25.380696 -1.319784)
			(end 25.392634 -1.388872)
			(stroke
				(width 0.1)
				(type default)
			)
			(layer "F.SilkS")
		)
		(fp_line
			(start 25.392634 -1.388872)
			(end 25.40508 -1.458214)
			(stroke
				(width 0.1)
				(type default)
			)
			(layer "F.SilkS")
		)
		(fp_line
			(start 25.392634 -1.388872)
			(end 25.40508 -1.458214)
			(stroke
				(width 0.1)
				(type default)
			)
			(layer "F.SilkS")
		)
		(fp_line
			(start 25.394412 -4.968494)
			(end 24.580596 -4.187952)
			(stroke
				(width 0.1)
				(type default)
			)
			(layer "F.SilkS")
		)
		(fp_line
			(start 25.394412 -4.968494)
			(end 24.580596 -4.187952)
			(stroke
				(width 0.1)
				(type default)
			)
			(layer "F.SilkS")
		)
		(fp_line
			(start 25.40508 -1.458214)
			(end 25.417272 -1.52781)
			(stroke
				(width 0.1)
				(type default)
			)
			(layer "F.SilkS")
		)
		(fp_line
			(start 25.40508 -1.458214)
			(end 25.417272 -1.52781)
			(stroke
				(width 0.1)
				(type default)
			)
			(layer "F.SilkS")
		)
		(fp_line
			(start 25.417272 -1.52781)
			(end 25.42921 -1.597406)
			(stroke
				(width 0.1)
				(type default)
			)
			(layer "F.SilkS")
		)
		(fp_line
			(start 25.417272 -1.52781)
			(end 25.42921 -1.597406)
			(stroke
				(width 0.1)
				(type default)
			)
			(layer "F.SilkS")
		)
		(fp_line
			(start 25.428194 -4.943094)
			(end 24.609044 -4.157218)
			(stroke
				(width 0.1)
				(type default)
			)
			(layer "F.SilkS")
		)
		(fp_line
			(start 25.428194 -4.943094)
			(end 24.609044 -4.157218)
			(stroke
				(width 0.1)
				(type default)
			)
			(layer "F.SilkS")
		)
		(fp_line
			(start 25.42921 -1.597406)
			(end 25.441656 -1.666494)
			(stroke
				(width 0.1)
				(type default)
			)
			(layer "F.SilkS")
		)
		(fp_line
			(start 25.42921 -1.597406)
			(end 25.441656 -1.666494)
			(stroke
				(width 0.1)
				(type default)
			)
			(layer "F.SilkS")
		)
		(fp_line
			(start 25.441656 -1.666494)
			(end 25.453594 -1.735836)
			(stroke
				(width 0.1)
				(type default)
			)
			(layer "F.SilkS")
		)
		(fp_line
			(start 25.441656 -1.666494)
			(end 25.453594 -1.735836)
			(stroke
				(width 0.1)
				(type default)
			)
			(layer "F.SilkS")
		)
		(fp_line
			(start 25.453594 -1.735836)
			(end 25.465786 -1.805178)
			(stroke
				(width 0.1)
				(type default)
			)
			(layer "F.SilkS")
		)
		(fp_line
			(start 25.453594 -1.735836)
			(end 25.465786 -1.805178)
			(stroke
				(width 0.1)
				(type default)
			)
			(layer "F.SilkS")
		)
		(fp_line
			(start 25.461722 -4.917694)
			(end 24.631904 -4.121912)
			(stroke
				(width 0.1)
				(type default)
			)
			(layer "F.SilkS")
		)
		(fp_line
			(start 25.461722 -4.917694)
			(end 24.631904 -4.121912)
			(stroke
				(width 0.1)
				(type default)
			)
			(layer "F.SilkS")
		)
		(fp_line
			(start 25.465786 -1.805178)
			(end 25.478232 -1.874774)
			(stroke
				(width 0.1)
				(type default)
			)
			(layer "F.SilkS")
		)
		(fp_line
			(start 25.465786 -1.805178)
			(end 25.478232 -1.874774)
			(stroke
				(width 0.1)
				(type default)
			)
			(layer "F.SilkS")
		)
		(fp_line
			(start 25.478232 -1.874774)
			(end 25.49017 -1.943862)
			(stroke
				(width 0.1)
				(type default)
			)
			(layer "F.SilkS")
		)
		(fp_line
			(start 25.478232 -1.874774)
			(end 25.49017 -1.943862)
			(stroke
				(width 0.1)
				(type default)
			)
			(layer "F.SilkS")
		)
		(fp_line
			(start 25.49017 -1.943862)
			(end 25.502362 -2.013204)
			(stroke
				(width 0.1)
				(type default)
			)
			(layer "F.SilkS")
		)
		(fp_line
			(start 25.49017 -1.943862)
			(end 25.502362 -2.013204)
			(stroke
				(width 0.1)
				(type default)
			)
			(layer "F.SilkS")
		)
		(fp_line
			(start 25.49525 -4.892294)
			(end 24.65451 -4.085844)
			(stroke
				(width 0.1)
				(type default)
			)
			(layer "F.SilkS")
		)
		(fp_line
			(start 25.49525 -4.892294)
			(end 24.65451 -4.085844)
			(stroke
				(width 0.1)
				(type default)
			)
			(layer "F.SilkS")
		)
		(fp_line
			(start 25.502362 -2.013204)
			(end 25.5143 -2.0828)
			(stroke
				(width 0.1)
				(type default)
			)
			(layer "F.SilkS")
		)
		(fp_line
			(start 25.502362 -2.013204)
			(end 25.5143 -2.0828)
			(stroke
				(width 0.1)
				(type default)
			)
			(layer "F.SilkS")
		)
		(fp_line
			(start 25.5143 -2.0828)
			(end 25.526746 -2.152142)
			(stroke
				(width 0.1)
				(type default)
			)
			(layer "F.SilkS")
		)
		(fp_line
			(start 25.5143 -2.0828)
			(end 25.526746 -2.152142)
			(stroke
				(width 0.1)
				(type default)
			)
			(layer "F.SilkS")
		)
		(fp_line
			(start 25.526746 -2.152142)
			(end 25.538684 -2.221484)
			(stroke
				(width 0.1)
				(type default)
			)
			(layer "F.SilkS")
		)
		(fp_line
			(start 25.526746 -2.152142)
			(end 25.538684 -2.221484)
			(stroke
				(width 0.1)
				(type default)
			)
			(layer "F.SilkS")
		)
		(fp_line
			(start 25.527508 -4.865624)
			(end 24.669242 -4.042156)
			(stroke
				(width 0.1)
				(type default)
			)
			(layer "F.SilkS")
		)
		(fp_line
			(start 25.527508 -4.865624)
			(end 24.669242 -4.042156)
			(stroke
				(width 0.1)
				(type default)
			)
			(layer "F.SilkS")
		)
		(fp_line
			(start 25.538684 -2.221484)
			(end 25.550876 -2.290826)
			(stroke
				(width 0.1)
				(type default)
			)
			(layer "F.SilkS")
		)
		(fp_line
			(start 25.538684 -2.221484)
			(end 25.550876 -2.290826)
			(stroke
				(width 0.1)
				(type default)
			)
			(layer "F.SilkS")
		)
		(fp_line
			(start 25.550876 -2.290826)
			(end 25.563322 -2.360422)
			(stroke
				(width 0.1)
				(type default)
			)
			(layer "F.SilkS")
		)
		(fp_line
			(start 25.550876 -2.290826)
			(end 25.563322 -2.360422)
			(stroke
				(width 0.1)
				(type default)
			)
			(layer "F.SilkS")
		)
		(fp_line
			(start 25.553162 -4.83235)
			(end 24.683974 -3.998722)
			(stroke
				(width 0.1)
				(type default)
			)
			(layer "F.SilkS")
		)
		(fp_line
			(start 25.553162 -4.83235)
			(end 24.683974 -3.998722)
			(stroke
				(width 0.1)
				(type default)
			)
			(layer "F.SilkS")
		)
		(fp_line
			(start 25.563322 -2.360422)
			(end 25.57526 -2.429764)
			(stroke
				(width 0.1)
				(type default)
			)
			(layer "F.SilkS")
		)
		(fp_line
			(start 25.563322 -2.360422)
			(end 25.57526 -2.429764)
			(stroke
				(width 0.1)
				(type default)
			)
			(layer "F.SilkS")
		)
		(fp_line
			(start 25.57526 -2.429764)
			(end 24.220424 -1.130046)
			(stroke
				(width 0.1)
				(type default)
			)
			(layer "F.SilkS")
		)
		(fp_line
			(start 25.57526 -2.429764)
			(end 24.220424 -1.130046)
			(stroke
				(width 0.1)
				(type default)
			)
			(layer "F.SilkS")
		)
		(fp_line
			(start 25.57526 -2.429764)
			(end 25.587452 -2.498852)
			(stroke
				(width 0.1)
				(type default)
			)
			(layer "F.SilkS")
		)
		(fp_line
			(start 25.57526 -2.429764)
			(end 25.587452 -2.498852)
			(stroke
				(width 0.1)
				(type default)
			)
			(layer "F.SilkS")
		)
		(fp_line
			(start 25.57907 -4.79933)
			(end 24.690324 -3.946652)
			(stroke
				(width 0.1)
				(type default)
			)
			(layer "F.SilkS")
		)
		(fp_line
			(start 25.57907 -4.79933)
			(end 24.690324 -3.946652)
			(stroke
				(width 0.1)
				(type default)
			)
			(layer "F.SilkS")
		)
		(fp_line
			(start 25.587452 -2.498852)
			(end 25.59939 -2.568194)
			(stroke
				(width 0.1)
				(type default)
			)
			(layer "F.SilkS")
		)
		(fp_line
			(start 25.587452 -2.498852)
			(end 25.59939 -2.568194)
			(stroke
				(width 0.1)
				(type default)
			)
			(layer "F.SilkS")
		)
		(fp_line
			(start 25.59939 -2.568194)
			(end 25.611836 -2.63779)
			(stroke
				(width 0.1)
				(type default)
			)
			(layer "F.SilkS")
		)
		(fp_line
			(start 25.59939 -2.568194)
			(end 25.611836 -2.63779)
			(stroke
				(width 0.1)
				(type default)
			)
			(layer "F.SilkS")
		)
		(fp_line
			(start 25.60447 -4.766564)
			(end 24.695658 -3.894328)
			(stroke
				(width 0.1)
				(type default)
			)
			(layer "F.SilkS")
		)
		(fp_line
			(start 25.60447 -4.766564)
			(end 24.695658 -3.894328)
			(stroke
				(width 0.1)
				(type default)
			)
			(layer "F.SilkS")
		)
		(fp_line
			(start 25.611836 -2.63779)
			(end 25.623774 -2.707132)
			(stroke
				(width 0.1)
				(type default)
			)
			(layer "F.SilkS")
		)
		(fp_line
			(start 25.611836 -2.63779)
			(end 25.623774 -2.707132)
			(stroke
				(width 0.1)
				(type default)
			)
			(layer "F.SilkS")
		)
		(fp_line
			(start 25.623774 -2.707132)
			(end 25.635966 -2.776474)
			(stroke
				(width 0.1)
				(type default)
			)
			(layer "F.SilkS")
		)
		(fp_line
			(start 25.623774 -2.707132)
			(end 25.635966 -2.776474)
			(stroke
				(width 0.1)
				(type default)
			)
			(layer "F.SilkS")
		)
		(fp_line
			(start 25.630378 -4.73329)
			(end 24.690324 -3.83159)
			(stroke
				(width 0.1)
				(type default)
			)
			(layer "F.SilkS")
		)
		(fp_line
			(start 25.630378 -4.73329)
			(end 24.690324 -3.83159)
			(stroke
				(width 0.1)
				(type default)
			)
			(layer "F.SilkS")
		)
		(fp_line
			(start 25.635966 -2.776474)
			(end 25.648412 -2.845816)
			(stroke
				(width 0.1)
				(type default)
			)
			(layer "F.SilkS")
		)
		(fp_line
			(start 25.635966 -2.776474)
			(end 25.648412 -2.845816)
			(stroke
				(width 0.1)
				(type default)
			)
			(layer "F.SilkS")
		)
		(fp_line
			(start 25.648412 -2.845816)
			(end 25.66035 -2.915412)
			(stroke
				(width 0.1)
				(type default)
			)
			(layer "F.SilkS")
		)
		(fp_line
			(start 25.648412 -2.845816)
			(end 25.66035 -2.915412)
			(stroke
				(width 0.1)
				(type default)
			)
			(layer "F.SilkS")
		)
		(fp_line
			(start 25.656286 -4.70027)
			(end 24.682958 -3.76682)
			(stroke
				(width 0.1)
				(type default)
			)
			(layer "F.SilkS")
		)
		(fp_line
			(start 25.656286 -4.70027)
			(end 24.682958 -3.76682)
			(stroke
				(width 0.1)
				(type default)
			)
			(layer "F.SilkS")
		)
		(fp_line
			(start 25.66035 -2.915412)
			(end 25.672542 -2.984754)
			(stroke
				(width 0.1)
				(type default)
			)
			(layer "F.SilkS")
		)
		(fp_line
			(start 25.66035 -2.915412)
			(end 25.672542 -2.984754)
			(stroke
				(width 0.1)
				(type default)
			)
			(layer "F.SilkS")
		)
		(fp_line
			(start 25.672542 -2.984754)
			(end 25.68448 -3.054096)
			(stroke
				(width 0.1)
				(type default)
			)
			(layer "F.SilkS")
		)
		(fp_line
			(start 25.672542 -2.984754)
			(end 25.68448 -3.054096)
			(stroke
				(width 0.1)
				(type default)
			)
			(layer "F.SilkS")
		)
		(fp_line
			(start 25.681686 -4.66725)
			(end 24.67102 -3.697478)
			(stroke
				(width 0.1)
				(type default)
			)
			(layer "F.SilkS")
		)
		(fp_line
			(start 25.681686 -4.66725)
			(end 24.67102 -3.697478)
			(stroke
				(width 0.1)
				(type default)
			)
			(layer "F.SilkS")
		)
		(fp_line
			(start 25.68448 -3.054096)
			(end 25.696926 -3.123184)
			(stroke
				(width 0.1)
				(type default)
			)
			(layer "F.SilkS")
		)
		(fp_line
			(start 25.68448 -3.054096)
			(end 25.696926 -3.123184)
			(stroke
				(width 0.1)
				(type default)
			)
			(layer "F.SilkS")
		)
		(fp_line
			(start 25.696926 -3.123184)
			(end 25.708864 -3.19278)
			(stroke
				(width 0.1)
				(type default)
			)
			(layer "F.SilkS")
		)
		(fp_line
			(start 25.696926 -3.123184)
			(end 25.708864 -3.19278)
			(stroke
				(width 0.1)
				(type default)
			)
			(layer "F.SilkS")
		)
		(fp_line
			(start 25.701498 -4.628388)
			(end 24.658574 -3.627882)
			(stroke
				(width 0.1)
				(type default)
			)
			(layer "F.SilkS")
		)
		(fp_line
			(start 25.701498 -4.628388)
			(end 24.658574 -3.627882)
			(stroke
				(width 0.1)
				(type default)
			)
			(layer "F.SilkS")
		)
		(fp_line
			(start 25.708864 -3.19278)
			(end 25.721056 -3.262122)
			(stroke
				(width 0.1)
				(type default)
			)
			(layer "F.SilkS")
		)
		(fp_line
			(start 25.708864 -3.19278)
			(end 25.721056 -3.262122)
			(stroke
				(width 0.1)
				(type default)
			)
			(layer "F.SilkS")
		)
		(fp_line
			(start 25.718516 -4.586986)
			(end 23.913084 -2.85496)
			(stroke
				(width 0.1)
				(type default)
			)
			(layer "F.SilkS")
		)
		(fp_line
			(start 25.718516 -4.586986)
			(end 23.913084 -2.85496)
			(stroke
				(width 0.1)
				(type default)
			)
			(layer "F.SilkS")
		)
		(fp_line
			(start 25.721056 -3.262122)
			(end 25.733502 -3.331464)
			(stroke
				(width 0.1)
				(type default)
			)
			(layer "F.SilkS")
		)
		(fp_line
			(start 25.721056 -3.262122)
			(end 25.733502 -3.331464)
			(stroke
				(width 0.1)
				(type default)
			)
			(layer "F.SilkS")
		)
		(fp_line
			(start 25.733502 -3.331464)
			(end 25.74544 -3.400806)
			(stroke
				(width 0.1)
				(type default)
			)
			(layer "F.SilkS")
		)
		(fp_line
			(start 25.733502 -3.331464)
			(end 25.74544 -3.400806)
			(stroke
				(width 0.1)
				(type default)
			)
			(layer "F.SilkS")
		)
		(fp_line
			(start 25.735534 -4.54533)
			(end 23.969472 -2.85115)
			(stroke
				(width 0.1)
				(type default)
			)
			(layer "F.SilkS")
		)
		(fp_line
			(start 25.735534 -4.54533)
			(end 23.969472 -2.85115)
			(stroke
				(width 0.1)
				(type default)
			)
			(layer "F.SilkS")
		)
		(fp_line
			(start 25.74544 -3.400806)
			(end 23.034752 -0.800608)
			(stroke
				(width 0.1)
				(type default)
			)
			(layer "F.SilkS")
		)
		(fp_line
			(start 25.74544 -3.400806)
			(end 23.034752 -0.800608)
			(stroke
				(width 0.1)
				(type default)
			)
			(layer "F.SilkS")
		)
		(fp_line
			(start 25.74544 -3.400806)
			(end 25.757632 -3.470402)
			(stroke
				(width 0.1)
				(type default)
			)
			(layer "F.SilkS")
		)
		(fp_line
			(start 25.74544 -3.400806)
			(end 25.757632 -3.470402)
			(stroke
				(width 0.1)
				(type default)
			)
			(layer "F.SilkS")
		)
		(fp_line
			(start 25.752298 -4.503928)
			(end 24.024336 -2.846324)
			(stroke
				(width 0.1)
				(type default)
			)
			(layer "F.SilkS")
		)
		(fp_line
			(start 25.752298 -4.503928)
			(end 24.024336 -2.846324)
			(stroke
				(width 0.1)
				(type default)
			)
			(layer "F.SilkS")
		)
		(fp_line
			(start 25.757632 -3.470402)
			(end 24.402796 -2.170938)
			(stroke
				(width 0.1)
				(type default)
			)
			(layer "F.SilkS")
		)
		(fp_line
			(start 25.757632 -3.470402)
			(end 24.402796 -2.170938)
			(stroke
				(width 0.1)
				(type default)
			)
			(layer "F.SilkS")
		)
		(fp_line
			(start 25.757632 -3.470402)
			(end 25.769824 -3.539744)
			(stroke
				(width 0.1)
				(type default)
			)
			(layer "F.SilkS")
		)
		(fp_line
			(start 25.757632 -3.470402)
			(end 25.769824 -3.539744)
			(stroke
				(width 0.1)
				(type default)
			)
			(layer "F.SilkS")
		)
		(fp_line
			(start 25.769316 -4.46278)
			(end 24.076914 -2.839466)
			(stroke
				(width 0.1)
				(type default)
			)
			(layer "F.SilkS")
		)
		(fp_line
			(start 25.769316 -4.46278)
			(end 24.076914 -2.839466)
			(stroke
				(width 0.1)
				(type default)
			)
			(layer "F.SilkS")
		)
		(fp_line
			(start 25.769824 -3.539744)
			(end 24.414988 -2.24028)
			(stroke
				(width 0.1)
				(type default)
			)
			(layer "F.SilkS")
		)
		(fp_line
			(start 25.769824 -3.539744)
			(end 24.414988 -2.24028)
			(stroke
				(width 0.1)
				(type default)
			)
			(layer "F.SilkS")
		)
		(fp_line
			(start 25.769824 -3.539744)
			(end 25.782016 -3.609086)
			(stroke
				(width 0.1)
				(type default)
			)
			(layer "F.SilkS")
		)
		(fp_line
			(start 25.769824 -3.539744)
			(end 25.782016 -3.609086)
			(stroke
				(width 0.1)
				(type default)
			)
			(layer "F.SilkS")
		)
		(fp_line
			(start 25.782016 -3.609086)
			(end 24.427434 -2.309368)
			(stroke
				(width 0.1)
				(type default)
			)
			(layer "F.SilkS")
		)
		(fp_line
			(start 25.782016 -3.609086)
			(end 24.427434 -2.309368)
			(stroke
				(width 0.1)
				(type default)
			)
			(layer "F.SilkS")
		)
		(fp_line
			(start 25.782016 -3.609086)
			(end 25.793954 -3.678174)
			(stroke
				(width 0.1)
				(type default)
			)
			(layer "F.SilkS")
		)
		(fp_line
			(start 25.782016 -3.609086)
			(end 25.793954 -3.678174)
			(stroke
				(width 0.1)
				(type default)
			)
			(layer "F.SilkS")
		)
		(fp_line
			(start 25.786588 -4.421378)
			(end 24.12873 -2.831084)
			(stroke
				(width 0.1)
				(type default)
			)
			(layer "F.SilkS")
		)
		(fp_line
			(start 25.786588 -4.421378)
			(end 24.12873 -2.831084)
			(stroke
				(width 0.1)
				(type default)
			)
			(layer "F.SilkS")
		)
		(fp_line
			(start 25.793954 -3.678174)
			(end 24.439372 -2.37871)
			(stroke
				(width 0.1)
				(type default)
			)
			(layer "F.SilkS")
		)
		(fp_line
			(start 25.793954 -3.678174)
			(end 24.439372 -2.37871)
			(stroke
				(width 0.1)
				(type default)
			)
			(layer "F.SilkS")
		)
		(fp_line
			(start 25.793954 -3.678174)
			(end 25.806146 -3.74777)
			(stroke
				(width 0.1)
				(type default)
			)
			(layer "F.SilkS")
		)
		(fp_line
			(start 25.793954 -3.678174)
			(end 25.806146 -3.74777)
			(stroke
				(width 0.1)
				(type default)
			)
			(layer "F.SilkS")
		)
		(fp_line
			(start 25.798526 -4.37515)
			(end 24.17826 -2.82067)
			(stroke
				(width 0.1)
				(type default)
			)
			(layer "F.SilkS")
		)
		(fp_line
			(start 25.798526 -4.37515)
			(end 24.17826 -2.82067)
			(stroke
				(width 0.1)
				(type default)
			)
			(layer "F.SilkS")
		)
		(fp_line
			(start 25.805384 -4.324096)
			(end 24.225504 -2.808478)
			(stroke
				(width 0.1)
				(type default)
			)
			(layer "F.SilkS")
		)
		(fp_line
			(start 25.805384 -4.324096)
			(end 24.225504 -2.808478)
			(stroke
				(width 0.1)
				(type default)
			)
			(layer "F.SilkS")
		)
		(fp_line
			(start 25.806146 -3.74777)
			(end 24.451564 -2.448306)
			(stroke
				(width 0.1)
				(type default)
			)
			(layer "F.SilkS")
		)
		(fp_line
			(start 25.806146 -3.74777)
			(end 24.451564 -2.448306)
			(stroke
				(width 0.1)
				(type default)
			)
			(layer "F.SilkS")
		)
		(fp_line
			(start 25.812242 -4.273296)
			(end 24.27097 -2.794508)
			(stroke
				(width 0.1)
				(type default)
			)
			(layer "F.SilkS")
		)
		(fp_line
			(start 25.812242 -4.273296)
			(end 24.27097 -2.794508)
			(stroke
				(width 0.1)
				(type default)
			)
			(layer "F.SilkS")
		)
		(fp_line
			(start 25.81275 -3.811524)
			(end 24.46401 -2.517648)
			(stroke
				(width 0.1)
				(type default)
			)
			(layer "F.SilkS")
		)
		(fp_line
			(start 25.81275 -3.811524)
			(end 24.46401 -2.517648)
			(stroke
				(width 0.1)
				(type default)
			)
			(layer "F.SilkS")
		)
		(fp_line
			(start 25.817576 -3.874008)
			(end 24.475948 -2.58699)
			(stroke
				(width 0.1)
				(type default)
			)
			(layer "F.SilkS")
		)
		(fp_line
			(start 25.817576 -3.874008)
			(end 24.475948 -2.58699)
			(stroke
				(width 0.1)
				(type default)
			)
			(layer "F.SilkS")
		)
		(fp_line
			(start 25.819608 -4.222242)
			(end 24.31415 -2.777998)
			(stroke
				(width 0.1)
				(type default)
			)
			(layer "F.SilkS")
		)
		(fp_line
			(start 25.819608 -4.222242)
			(end 24.31415 -2.777998)
			(stroke
				(width 0.1)
				(type default)
			)
			(layer "F.SilkS")
		)
		(fp_line
			(start 25.822656 -3.936492)
			(end 24.487886 -2.656332)
			(stroke
				(width 0.1)
				(type default)
			)
			(layer "F.SilkS")
		)
		(fp_line
			(start 25.822656 -3.936492)
			(end 24.487886 -2.656332)
			(stroke
				(width 0.1)
				(type default)
			)
			(layer "F.SilkS")
		)
		(fp_line
			(start 25.826466 -4.170934)
			(end 24.35606 -2.760472)
			(stroke
				(width 0.1)
				(type default)
			)
			(layer "F.SilkS")
		)
		(fp_line
			(start 25.826466 -4.170934)
			(end 24.35606 -2.760472)
			(stroke
				(width 0.1)
				(type default)
			)
			(layer "F.SilkS")
		)
		(fp_line
			(start 25.827736 -3.99923)
			(end 24.468836 -2.695448)
			(stroke
				(width 0.1)
				(type default)
			)
			(layer "F.SilkS")
		)
		(fp_line
			(start 25.827736 -3.99923)
			(end 24.468836 -2.695448)
			(stroke
				(width 0.1)
				(type default)
			)
			(layer "F.SilkS")
		)
		(fp_line
			(start 25.83307 -4.062222)
			(end 24.432514 -2.718816)
			(stroke
				(width 0.1)
				(type default)
			)
			(layer "F.SilkS")
		)
		(fp_line
			(start 25.83307 -4.062222)
			(end 24.432514 -2.718816)
			(stroke
				(width 0.1)
				(type default)
			)
			(layer "F.SilkS")
		)
		(fp_line
			(start 25.833324 -4.120134)
			(end 24.394668 -2.739898)
			(stroke
				(width 0.1)
				(type default)
			)
			(layer "F.SilkS")
		)
		(fp_line
			(start 25.833324 -4.120134)
			(end 24.394668 -2.739898)
			(stroke
				(width 0.1)
				(type default)
			)
			(layer "F.SilkS")
		)
	)
	(footprint ""
		(layer "F.Cu")
		(at 450.342 -41.148 -90)
		(property "Reference" "R5"
			(at 0 0 270)
			(layer "F.SilkS")
			(hide yes)
			(effects
				(font
					(size 1.27 1.27)
				)
			)
		)
		(property "Value" ""
			(at 0 0 270)
			(layer "F.Fab")
			(effects
				(font
					(size 1.27 1.27)
				)
			)
		)
		(duplicate_pad_numbers_are_jumpers no)
		(fp_line
			(start -0.7874 0.4064)
			(end -0.7874 -0.4064)
			(stroke
				(width 0.1524)
				(type default)
			)
			(layer "F.SilkS")
		)
		(fp_line
			(start 0.7874 0.4064)
			(end -0.7874 0.4064)
			(stroke
				(width 0.1524)
				(type default)
			)
			(layer "F.SilkS")
		)
		(fp_line
			(start -0.7874 -0.4064)
			(end 0.7874 -0.4064)
			(stroke
				(width 0.1524)
				(type default)
			)
			(layer "F.SilkS")
		)
		(fp_line
			(start 0.7874 -0.4064)
			(end 0.7874 0.4064)
			(stroke
				(width 0.1524)
				(type default)
			)
			(layer "F.SilkS")
		)
		(fp_line
			(start -0.67945 0.3048)
			(end -0.67945 -0.305054)
			(stroke
				(width 0.1)
				(type default)
			)
			(layer "F.Fab")
		)
		(fp_line
			(start -0.12065 0.3048)
			(end -0.67945 0.3048)
			(stroke
				(width 0.1)
				(type default)
			)
			(layer "F.Fab")
		)
		(fp_line
			(start 0.120396 0.3048)
			(end 0.120396 0.2794)
			(stroke
				(width 0.1)
				(type default)
			)
			(layer "F.Fab")
		)
		(fp_line
			(start 0.67945 0.3048)
			(end 0.120396 0.3048)
			(stroke
				(width 0.1)
				(type default)
			)
			(layer "F.Fab")
		)
		(fp_line
			(start -0.12065 0.2794)
			(end -0.12065 0.3048)
			(stroke
				(width 0.1)
				(type default)
			)
			(layer "F.Fab")
		)
		(fp_line
			(start 0.120396 0.2794)
			(end -0.12065 0.2794)
			(stroke
				(width 0.1)
				(type default)
			)
			(layer "F.Fab")
		)
		(fp_line
			(start -0.12065 -0.2794)
			(end 0.12065 -0.2794)
			(stroke
				(width 0.1)
				(type default)
			)
			(layer "F.Fab")
		)
		(fp_line
			(start 0.12065 -0.2794)
			(end 0.12065 -0.3048)
			(stroke
				(width 0.1)
				(type default)
			)
			(layer "F.Fab")
		)
		(fp_line
			(start 0.12065 -0.3048)
			(end 0.67945 -0.3048)
			(stroke
				(width 0.1)
				(type default)
			)
			(layer "F.Fab")
		)
		(fp_line
			(start 0.67945 -0.3048)
			(end 0.67945 0.3048)
			(stroke
				(width 0.1)
				(type default)
			)
			(layer "F.Fab")
		)
		(fp_line
			(start -0.67945 -0.305054)
			(end -0.12065 -0.305054)
			(stroke
				(width 0.1)
				(type default)
			)
			(layer "F.Fab")
		)
		(fp_line
			(start -0.12065 -0.305054)
			(end -0.12065 -0.2794)
			(stroke
				(width 0.1)
				(type default)
			)
			(layer "F.Fab")
		)
		(pad "1" smd circle
			(at -0.40005 0 270)
			(size 0 0)
			(layers "F.Cu" "F.Mask" "F.Paste")
			(net "SMB_PDB_MISC_SDA_R")
		)
		(pad "2" smd circle
			(at 0.40005 0 270)
			(size 0 0)
			(layers "F.Cu" "F.Mask" "F.Paste")
			(net "SMB_PDB_MISC_SDA")
		)
	)
	(footprint ""
		(layer "F.Cu")
		(at 172.466 -81.153)
		(property "Reference" "U35"
			(at 0.9525 -2.24663 0)
			(unlocked yes)
			(layer "F.SilkS")
			(effects
				(font
					(size 0.7874 0.5842)
					(thickness 0.1524)
				)
				(justify left)
			)
		)
		(property "Value" ""
			(at 0 0 0)
			(layer "F.Fab")
			(effects
				(font
					(size 1.27 1.27)
				)
			)
		)
		(duplicate_pad_numbers_are_jumpers no)
		(fp_line
			(start -1.733296 -1.549908)
			(end -1.733296 1.549908)
			(stroke
				(width 0.1524)
				(type default)
			)
			(layer "F.SilkS")
		)
		(fp_line
			(start -1.733296 1.549908)
			(end 1.733296 1.549908)
			(stroke
				(width 0.1524)
				(type default)
			)
			(layer "F.SilkS")
		)
		(fp_line
			(start -0.660908 -1.549908)
			(end -1.733296 -1.549908)
			(stroke
				(width 0.1524)
				(type default)
			)
			(layer "F.SilkS")
		)
		(fp_line
			(start 0 -0.889)
			(end -0.660908 -1.549908)
			(stroke
				(width 0.1524)
				(type default)
			)
			(layer "F.SilkS")
		)
		(fp_line
			(start 0.660908 -1.549908)
			(end 0 -0.889)
			(stroke
				(width 0.1524)
				(type default)
			)
			(layer "F.SilkS")
		)
		(fp_line
			(start 1.733296 -1.549908)
			(end 0.660908 -1.549908)
			(stroke
				(width 0.1524)
				(type default)
			)
			(layer "F.SilkS")
		)
		(fp_line
			(start 1.733296 1.549908)
			(end 1.733296 -1.549908)
			(stroke
				(width 0.1524)
				(type default)
			)
			(layer "F.SilkS")
		)
		(fp_poly
			(pts
				(xy -2.159 -1.883156) (xy -2.518156 -1.524) (xy -1.979422 -1.344422)
			)
			(stroke
				(width 0)
				(type default)
			)
			(fill yes)
			(layer "F.SilkS")
		)
		(fp_line
			(start -0.849884 -1.549908)
			(end -0.849884 1.549908)
			(stroke
				(width 0.1)
				(type default)
			)
			(layer "F.Fab")
		)
		(fp_line
			(start -0.849884 1.549908)
			(end 0.849884 1.549908)
			(stroke
				(width 0.1)
				(type default)
			)
			(layer "F.Fab")
		)
		(fp_line
			(start 0.849884 -1.549908)
			(end -0.849884 -1.549908)
			(stroke
				(width 0.1)
				(type default)
			)
			(layer "F.Fab")
		)
		(fp_line
			(start 0.849884 1.549908)
			(end 0.849884 -1.549908)
			(stroke
				(width 0.1)
				(type default)
			)
			(layer "F.Fab")
		)
		(fp_poly
			(pts
				(xy -2.4384 -1.20396) (xy -2.4384 -0.69596) (xy -1.9304 -0.94996)
			)
			(stroke
				(width 0)
				(type default)
			)
			(fill yes)
			(layer "F.Fab")
		)
		(pad "1" smd rect
			(at -1.199896 -0.94996 270)
			(size 0.5588 0.8128)
			(layers "F.Cu" "F.Mask" "F.Paste")
			(net "FM_HS2_EN_BUSBAR")
		)
		(pad "2" smd rect
			(at -1.199896 0 270)
			(size 0.5588 0.8128)
			(layers "F.Cu" "F.Mask" "F.Paste")
			(net "FM_HS2_EN_FUSE")
		)
		(pad "3" smd rect
			(at -1.199896 0.94996 270)
			(size 0.5588 0.8128)
			(layers "F.Cu" "F.Mask" "F.Paste")
			(net "GND")
		)
		(pad "4" smd rect
			(at 1.199896 0.94996 270)
			(size 0.5588 0.8128)
			(layers "F.Cu" "F.Mask" "F.Paste")
			(net "P52V_HS2_EN")
		)
		(pad "5" smd rect
			(at 1.199896 -0.94996 270)
			(size 0.5588 0.8128)
			(layers "F.Cu" "F.Mask" "F.Paste")
			(net "P3V3_2_AND")
		)
	)
	(footprint ""
		(layer "F.Cu")
		(at 275.3614 -63.881 180)
		(property "Reference" "R357"
			(at 0 0 180)
			(layer "F.SilkS")
			(hide yes)
			(effects
				(font
					(size 1.27 1.27)
				)
			)
		)
		(property "Value" ""
			(at 0 0 180)
			(layer "F.Fab")
			(effects
				(font
					(size 1.27 1.27)
				)
			)
		)
		(duplicate_pad_numbers_are_jumpers no)
		(fp_line
			(start 0.7874 0.4064)
			(end -0.7874 0.4064)
			(stroke
				(width 0.1524)
				(type default)
			)
			(layer "F.SilkS")
		)
		(fp_line
			(start 0.7874 -0.4064)
			(end 0.7874 0.4064)
			(stroke
				(width 0.1524)
				(type default)
			)
			(layer "F.SilkS")
		)
		(fp_line
			(start -0.7874 0.4064)
			(end -0.7874 -0.4064)
			(stroke
				(width 0.1524)
				(type default)
			)
			(layer "F.SilkS")
		)
		(fp_line
			(start -0.7874 -0.4064)
			(end 0.7874 -0.4064)
			(stroke
				(width 0.1524)
				(type default)
			)
			(layer "F.SilkS")
		)
		(fp_line
			(start 0.67945 0.3048)
			(end 0.120396 0.3048)
			(stroke
				(width 0.1)
				(type default)
			)
			(layer "F.Fab")
		)
		(fp_line
			(start 0.67945 -0.3048)
			(end 0.67945 0.3048)
			(stroke
				(width 0.1)
				(type default)
			)
			(layer "F.Fab")
		)
		(fp_line
			(start 0.12065 -0.2794)
			(end 0.12065 -0.3048)
			(stroke
				(width 0.1)
				(type default)
			)
			(layer "F.Fab")
		)
		(fp_line
			(start 0.12065 -0.3048)
			(end 0.67945 -0.3048)
			(stroke
				(width 0.1)
				(type default)
			)
			(layer "F.Fab")
		)
		(fp_line
			(start 0.120396 0.3048)
			(end 0.120396 0.2794)
			(stroke
				(width 0.1)
				(type default)
			)
			(layer "F.Fab")
		)
		(fp_line
			(start 0.120396 0.2794)
			(end -0.12065 0.2794)
			(stroke
				(width 0.1)
				(type default)
			)
			(layer "F.Fab")
		)
		(fp_line
			(start -0.12065 0.3048)
			(end -0.67945 0.3048)
			(stroke
				(width 0.1)
				(type default)
			)
			(layer "F.Fab")
		)
		(fp_line
			(start -0.12065 0.2794)
			(end -0.12065 0.3048)
			(stroke
				(width 0.1)
				(type default)
			)
			(layer "F.Fab")
		)
		(fp_line
			(start -0.12065 -0.2794)
			(end 0.12065 -0.2794)
			(stroke
				(width 0.1)
				(type default)
			)
			(layer "F.Fab")
		)
		(fp_line
			(start -0.12065 -0.305054)
			(end -0.12065 -0.2794)
			(stroke
				(width 0.1)
				(type default)
			)
			(layer "F.Fab")
		)
		(fp_line
			(start -0.67945 0.3048)
			(end -0.67945 -0.305054)
			(stroke
				(width 0.1)
				(type default)
			)
			(layer "F.Fab")
		)
		(fp_line
			(start -0.67945 -0.305054)
			(end -0.12065 -0.305054)
			(stroke
				(width 0.1)
				(type default)
			)
			(layer "F.Fab")
		)
		(pad "1" smd circle
			(at -0.40005 0 180)
			(size 0 0)
			(layers "F.Cu" "F.Mask" "F.Paste")
			(net "P3V3_AUX")
		)
		(pad "2" smd circle
			(at 0.40005 0 180)
			(size 0 0)
			(layers "F.Cu" "F.Mask" "F.Paste")
			(net "P52V_HS1_GPO1")
		)
	)
	(footprint ""
		(layer "F.Cu")
		(at 140.79982 -71.755 180)
		(property "Reference" "PR6982"
			(at 0 0 180)
			(layer "F.SilkS")
			(hide yes)
			(effects
				(font
					(size 1.27 1.27)
				)
			)
		)
		(property "Value" ""
			(at 0 0 180)
			(layer "F.Fab")
			(effects
				(font
					(size 1.27 1.27)
				)
			)
		)
		(duplicate_pad_numbers_are_jumpers no)
		(fp_line
			(start 1.2954 0.5842)
			(end -1.2954 0.5842)
			(stroke
				(width 0.1524)
				(type default)
			)
			(layer "F.SilkS")
		)
		(fp_line
			(start 1.2954 -0.5842)
			(end 1.2954 0.5842)
			(stroke
				(width 0.1524)
				(type default)
			)
			(layer "F.SilkS")
		)
		(fp_line
			(start -1.2954 0.5842)
			(end -1.2954 -0.5842)
			(stroke
				(width 0.1524)
				(type default)
			)
			(layer "F.SilkS")
		)
		(fp_line
			(start -1.2954 -0.5842)
			(end 1.2954 -0.5842)
			(stroke
				(width 0.1524)
				(type default)
			)
			(layer "F.SilkS")
		)
		(fp_line
			(start 1.1938 0.4064)
			(end 0.8636 0.4064)
			(stroke
				(width 0.1)
				(type default)
			)
			(layer "F.Fab")
		)
		(fp_line
			(start 1.1938 -0.406654)
			(end 1.1938 0.4064)
			(stroke
				(width 0.1)
				(type default)
			)
			(layer "F.Fab")
		)
		(fp_line
			(start 0.8636 0.4572)
			(end -0.8636 0.4572)
			(stroke
				(width 0.1)
				(type default)
			)
			(layer "F.Fab")
		)
		(fp_line
			(start 0.8636 0.4064)
			(end 0.8636 0.4572)
			(stroke
				(width 0.1)
				(type default)
			)
			(layer "F.Fab")
		)
		(fp_line
			(start 0.8636 -0.406654)
			(end 1.1938 -0.406654)
			(stroke
				(width 0.1)
				(type default)
			)
			(layer "F.Fab")
		)
		(fp_line
			(start 0.8636 -0.4572)
			(end 0.8636 -0.406654)
			(stroke
				(width 0.1)
				(type default)
			)
			(layer "F.Fab")
		)
		(fp_line
			(start -0.8636 0.4572)
			(end -0.8636 0.4318)
			(stroke
				(width 0.1)
				(type default)
			)
			(layer "F.Fab")
		)
		(fp_line
			(start -0.8636 0.4318)
			(end -0.8636 0.4064)
			(stroke
				(width 0.1)
				(type default)
			)
			(layer "F.Fab")
		)
		(fp_line
			(start -0.8636 0.4064)
			(end -1.1938 0.4064)
			(stroke
				(width 0.1)
				(type default)
			)
			(layer "F.Fab")
		)
		(fp_line
			(start -0.8636 -0.406654)
			(end -0.8636 -0.4572)
			(stroke
				(width 0.1)
				(type default)
			)
			(layer "F.Fab")
		)
		(fp_line
			(start -0.8636 -0.4572)
			(end 0.8636 -0.4572)
			(stroke
				(width 0.1)
				(type default)
			)
			(layer "F.Fab")
		)
		(fp_line
			(start -1.1938 0.4064)
			(end -1.1938 -0.406654)
			(stroke
				(width 0.1)
				(type default)
			)
			(layer "F.Fab")
		)
		(fp_line
			(start -1.1938 -0.406654)
			(end -0.8636 -0.406654)
			(stroke
				(width 0.1)
				(type default)
			)
			(layer "F.Fab")
		)
		(pad "1" smd rect
			(at -0.7366 0 90)
			(size 0.7112 0.8128)
			(layers "F.Cu" "F.Mask" "F.Paste")
			(net "P52V_HS2_4287_S1N")
		)
		(pad "2" smd rect
			(at 0.7366 0 90)
			(size 0.7112 0.8128)
			(layers "F.Cu" "F.Mask" "F.Paste")
			(net "P52V_HS2_SENSE_N_R1")
		)
	)
	(footprint ""
		(layer "F.Cu")
		(at 33.72739 -30.607)
		(property "Reference" "D2"
			(at -0.93599 1.29667 0)
			(unlocked yes)
			(layer "F.SilkS")
			(effects
				(font
					(size 0.7874 0.5842)
					(thickness 0.1524)
				)
				(justify left)
			)
		)
		(property "Value" ""
			(at 0 0 0)
			(layer "F.Fab")
			(effects
				(font
					(size 1.27 1.27)
				)
			)
		)
		(duplicate_pad_numbers_are_jumpers no)
		(fp_line
			(start -0.90678 0.4826)
			(end -0.90678 -0.4699)
			(stroke
				(width 0.1524)
				(type default)
			)
			(layer "F.SilkS")
		)
		(fp_line
			(start -0.89408 -0.4826)
			(end 0.90678 -0.4826)
			(stroke
				(width 0.1524)
				(type default)
			)
			(layer "F.SilkS")
		)
		(fp_line
			(start -0.79248 -0.4826)
			(end 1.03378 -0.4826)
			(stroke
				(width 0.1524)
				(type default)
			)
			(layer "F.SilkS")
		)
		(fp_line
			(start -0.64008 -0.4826)
			(end 1.16078 -0.4826)
			(stroke
				(width 0.1524)
				(type default)
			)
			(layer "F.SilkS")
		)
		(fp_line
			(start 0.90678 -0.4826)
			(end 0.90678 0.4826)
			(stroke
				(width 0.1524)
				(type default)
			)
			(layer "F.SilkS")
		)
		(fp_line
			(start 0.90678 0.4826)
			(end -0.90678 0.4826)
			(stroke
				(width 0.1524)
				(type default)
			)
			(layer "F.SilkS")
		)
		(fp_line
			(start 1.03378 -0.4826)
			(end 1.03378 0.4826)
			(stroke
				(width 0.1524)
				(type default)
			)
			(layer "F.SilkS")
		)
		(fp_line
			(start 1.03378 0.4826)
			(end -0.79248 0.4826)
			(stroke
				(width 0.1524)
				(type default)
			)
			(layer "F.SilkS")
		)
		(fp_line
			(start 1.16078 -0.4826)
			(end 1.16078 0.4826)
			(stroke
				(width 0.1524)
				(type default)
			)
			(layer "F.SilkS")
		)
		(fp_line
			(start 1.16078 0.4826)
			(end -0.64008 0.4826)
			(stroke
				(width 0.1524)
				(type default)
			)
			(layer "F.SilkS")
		)
		(fp_line
			(start -0.499872 -0.249936)
			(end 0.499872 -0.249936)
			(stroke
				(width 0.1)
				(type default)
			)
			(layer "F.Fab")
		)
		(fp_line
			(start -0.499872 0.249936)
			(end -0.499872 -0.249936)
			(stroke
				(width 0.1)
				(type default)
			)
			(layer "F.Fab")
		)
		(fp_line
			(start 0.499872 -0.249936)
			(end 0.499872 0.249936)
			(stroke
				(width 0.1)
				(type default)
			)
			(layer "F.Fab")
		)
		(fp_line
			(start 0.499872 0.249936)
			(end -0.499872 0.249936)
			(stroke
				(width 0.1)
				(type default)
			)
			(layer "F.Fab")
		)
		(pad "A" smd rect
			(at -0.47498 0)
			(size 0.6096 0.7112)
			(layers "F.Cu" "F.Mask" "F.Paste")
			(net "LED_D2_R5")
		)
		(pad "C" smd rect
			(at 0.47498 0)
			(size 0.6096 0.7112)
			(layers "F.Cu" "F.Mask" "F.Paste")
			(net "GND")
		)
	)
	(footprint ""
		(layer "F.Cu")
		(at 145.11782 -37.9222)
		(property "Reference" "PR6992"
			(at 0 0 0)
			(layer "F.SilkS")
			(hide yes)
			(effects
				(font
					(size 1.27 1.27)
				)
			)
		)
		(property "Value" ""
			(at 0 0 0)
			(layer "F.Fab")
			(effects
				(font
					(size 1.27 1.27)
				)
			)
		)
		(duplicate_pad_numbers_are_jumpers no)
		(fp_line
			(start -1.2954 -0.5842)
			(end 1.2954 -0.5842)
			(stroke
				(width 0.1524)
				(type default)
			)
			(layer "F.SilkS")
		)
		(fp_line
			(start -1.2954 0.5842)
			(end -1.2954 -0.5842)
			(stroke
				(width 0.1524)
				(type default)
			)
			(layer "F.SilkS")
		)
		(fp_line
			(start 1.2954 -0.5842)
			(end 1.2954 0.5842)
			(stroke
				(width 0.1524)
				(type default)
			)
			(layer "F.SilkS")
		)
		(fp_line
			(start 1.2954 0.5842)
			(end -1.2954 0.5842)
			(stroke
				(width 0.1524)
				(type default)
			)
			(layer "F.SilkS")
		)
		(fp_line
			(start -1.1938 -0.406654)
			(end -0.8636 -0.406654)
			(stroke
				(width 0.1)
				(type default)
			)
			(layer "F.Fab")
		)
		(fp_line
			(start -1.1938 0.4064)
			(end -1.1938 -0.406654)
			(stroke
				(width 0.1)
				(type default)
			)
			(layer "F.Fab")
		)
		(fp_line
			(start -0.8636 -0.4572)
			(end 0.8636 -0.4572)
			(stroke
				(width 0.1)
				(type default)
			)
			(layer "F.Fab")
		)
		(fp_line
			(start -0.8636 -0.406654)
			(end -0.8636 -0.4572)
			(stroke
				(width 0.1)
				(type default)
			)
			(layer "F.Fab")
		)
		(fp_line
			(start -0.8636 0.4064)
			(end -1.1938 0.4064)
			(stroke
				(width 0.1)
				(type default)
			)
			(layer "F.Fab")
		)
		(fp_line
			(start -0.8636 0.4318)
			(end -0.8636 0.4064)
			(stroke
				(width 0.1)
				(type default)
			)
			(layer "F.Fab")
		)
		(fp_line
			(start -0.8636 0.4572)
			(end -0.8636 0.4318)
			(stroke
				(width 0.1)
				(type default)
			)
			(layer "F.Fab")
		)
		(fp_line
			(start 0.8636 -0.4572)
			(end 0.8636 -0.406654)
			(stroke
				(width 0.1)
				(type default)
			)
			(layer "F.Fab")
		)
		(fp_line
			(start 0.8636 -0.406654)
			(end 1.1938 -0.406654)
			(stroke
				(width 0.1)
				(type default)
			)
			(layer "F.Fab")
		)
		(fp_line
			(start 0.8636 0.4064)
			(end 0.8636 0.4572)
			(stroke
				(width 0.1)
				(type default)
			)
			(layer "F.Fab")
		)
		(fp_line
			(start 0.8636 0.4572)
			(end -0.8636 0.4572)
			(stroke
				(width 0.1)
				(type default)
			)
			(layer "F.Fab")
		)
		(fp_line
			(start 1.1938 -0.406654)
			(end 1.1938 0.4064)
			(stroke
				(width 0.1)
				(type default)
			)
			(layer "F.Fab")
		)
		(fp_line
			(start 1.1938 0.4064)
			(end 0.8636 0.4064)
			(stroke
				(width 0.1)
				(type default)
			)
			(layer "F.Fab")
		)
		(pad "1" smd rect
			(at -0.7366 0 270)
			(size 0.7112 0.8128)
			(layers "F.Cu" "F.Mask" "F.Paste")
			(net "P52V_HS2_4287_S2P")
		)
		(pad "2" smd rect
			(at 0.7366 0 270)
			(size 0.7112 0.8128)
			(layers "F.Cu" "F.Mask" "F.Paste")
			(net "P52V_HS2_SENSE_P_R2")
		)
	)
	(footprint ""
		(layer "F.Cu")
		(at 306.7304 -34.3662)
		(property "Reference" "PR6959"
			(at 0 0 0)
			(layer "F.SilkS")
			(hide yes)
			(effects
				(font
					(size 1.27 1.27)
				)
			)
		)
		(property "Value" ""
			(at 0 0 0)
			(layer "F.Fab")
			(effects
				(font
					(size 1.27 1.27)
				)
			)
		)
		(duplicate_pad_numbers_are_jumpers no)
		(fp_line
			(start -1.2954 -0.5842)
			(end 1.2954 -0.5842)
			(stroke
				(width 0.1524)
				(type default)
			)
			(layer "F.SilkS")
		)
		(fp_line
			(start -1.2954 0.5842)
			(end -1.2954 -0.5842)
			(stroke
				(width 0.1524)
				(type default)
			)
			(layer "F.SilkS")
		)
		(fp_line
			(start 1.2954 -0.5842)
			(end 1.2954 0.5842)
			(stroke
				(width 0.1524)
				(type default)
			)
			(layer "F.SilkS")
		)
		(fp_line
			(start 1.2954 0.5842)
			(end -1.2954 0.5842)
			(stroke
				(width 0.1524)
				(type default)
			)
			(layer "F.SilkS")
		)
		(fp_line
			(start -1.1938 -0.406654)
			(end -0.8636 -0.406654)
			(stroke
				(width 0.1)
				(type default)
			)
			(layer "F.Fab")
		)
		(fp_line
			(start -1.1938 0.4064)
			(end -1.1938 -0.406654)
			(stroke
				(width 0.1)
				(type default)
			)
			(layer "F.Fab")
		)
		(fp_line
			(start -0.8636 -0.4572)
			(end 0.8636 -0.4572)
			(stroke
				(width 0.1)
				(type default)
			)
			(layer "F.Fab")
		)
		(fp_line
			(start -0.8636 -0.406654)
			(end -0.8636 -0.4572)
			(stroke
				(width 0.1)
				(type default)
			)
			(layer "F.Fab")
		)
		(fp_line
			(start -0.8636 0.4064)
			(end -1.1938 0.4064)
			(stroke
				(width 0.1)
				(type default)
			)
			(layer "F.Fab")
		)
		(fp_line
			(start -0.8636 0.4318)
			(end -0.8636 0.4064)
			(stroke
				(width 0.1)
				(type default)
			)
			(layer "F.Fab")
		)
		(fp_line
			(start -0.8636 0.4572)
			(end -0.8636 0.4318)
			(stroke
				(width 0.1)
				(type default)
			)
			(layer "F.Fab")
		)
		(fp_line
			(start 0.8636 -0.4572)
			(end 0.8636 -0.406654)
			(stroke
				(width 0.1)
				(type default)
			)
			(layer "F.Fab")
		)
		(fp_line
			(start 0.8636 -0.406654)
			(end 1.1938 -0.406654)
			(stroke
				(width 0.1)
				(type default)
			)
			(layer "F.Fab")
		)
		(fp_line
			(start 0.8636 0.4064)
			(end 0.8636 0.4572)
			(stroke
				(width 0.1)
				(type default)
			)
			(layer "F.Fab")
		)
		(fp_line
			(start 0.8636 0.4572)
			(end -0.8636 0.4572)
			(stroke
				(width 0.1)
				(type default)
			)
			(layer "F.Fab")
		)
		(fp_line
			(start 1.1938 -0.406654)
			(end 1.1938 0.4064)
			(stroke
				(width 0.1)
				(type default)
			)
			(layer "F.Fab")
		)
		(fp_line
			(start 1.1938 0.4064)
			(end 0.8636 0.4064)
			(stroke
				(width 0.1)
				(type default)
			)
			(layer "F.Fab")
		)
		(pad "1" smd rect
			(at -0.7366 0 270)
			(size 0.7112 0.8128)
			(layers "F.Cu" "F.Mask" "F.Paste")
			(net "P52V_HS_1272_S_N")
		)
		(pad "2" smd rect
			(at 0.7366 0 270)
			(size 0.7112 0.8128)
			(layers "F.Cu" "F.Mask" "F.Paste")
			(net "P52V_HS1_SENSE_N_R2")
		)
	)
	(footprint ""
		(layer "F.Cu")
		(at 390.652 -25.273)
		(property "Reference" "PU3"
			(at -1.143 1.93167 0)
			(unlocked yes)
			(layer "F.SilkS")
			(effects
				(font
					(size 0.7874 0.5842)
					(thickness 0.1524)
				)
				(justify left)
			)
		)
		(property "Value" ""
			(at 0 0 0)
			(layer "F.Fab")
			(effects
				(font
					(size 1.27 1.27)
				)
			)
		)
		(duplicate_pad_numbers_are_jumpers no)
		(fp_line
			(start -1.335278 -1.100074)
			(end -1.335278 1.100074)
			(stroke
				(width 0.1524)
				(type default)
			)
			(layer "F.SilkS")
		)
		(fp_line
			(start -1.335278 1.100074)
			(end 1.335278 1.100074)
			(stroke
				(width 0.1524)
				(type default)
			)
			(layer "F.SilkS")
		)
		(fp_line
			(start 1.335278 -1.100074)
			(end -1.335278 -1.100074)
			(stroke
				(width 0.1524)
				(type default)
			)
			(layer "F.SilkS")
		)
		(fp_line
			(start 1.335278 1.100074)
			(end 1.335278 -1.100074)
			(stroke
				(width 0.1524)
				(type default)
			)
			(layer "F.SilkS")
		)
		(fp_line
			(start -0.674878 -1.100074)
			(end -0.674878 1.100074)
			(stroke
				(width 0.1)
				(type default)
			)
			(layer "F.Fab")
		)
		(fp_line
			(start -0.674878 1.100074)
			(end 0.674878 1.100074)
			(stroke
				(width 0.1)
				(type default)
			)
			(layer "F.Fab")
		)
		(fp_line
			(start 0.674878 -1.100074)
			(end -0.674878 -1.100074)
			(stroke
				(width 0.1)
				(type default)
			)
			(layer "F.Fab")
		)
		(fp_line
			(start 0.674878 1.100074)
			(end 0.674878 -1.100074)
			(stroke
				(width 0.1)
				(type default)
			)
			(layer "F.Fab")
		)
		(pad "D" smd rect
			(at 0.8001 0 270)
			(size 0.6096 0.8128)
			(layers "F.Cu" "F.Mask" "F.Paste")
			(net "P52V_HS1_EN_DISCHARGE_N")
		)
		(pad "G" smd rect
			(at -0.8001 -0.649986 270)
			(size 0.6096 0.8128)
			(layers "F.Cu" "F.Mask" "F.Paste")
			(net "P52V_HS1_EN_DISCHARGE")
		)
		(pad "S" smd rect
			(at -0.8001 0.649986 270)
			(size 0.6096 0.8128)
			(layers "F.Cu" "F.Mask" "F.Paste")
			(net "GND")
		)
	)
	(footprint ""
		(layer "F.Cu")
		(at 145.11782 -68.199)
		(property "Reference" "PR6985"
			(at 0 0 0)
			(layer "F.SilkS")
			(hide yes)
			(effects
				(font
					(size 1.27 1.27)
				)
			)
		)
		(property "Value" ""
			(at 0 0 0)
			(layer "F.Fab")
			(effects
				(font
					(size 1.27 1.27)
				)
			)
		)
		(duplicate_pad_numbers_are_jumpers no)
		(fp_line
			(start -1.2954 -0.5842)
			(end 1.2954 -0.5842)
			(stroke
				(width 0.1524)
				(type default)
			)
			(layer "F.SilkS")
		)
		(fp_line
			(start -1.2954 0.5842)
			(end -1.2954 -0.5842)
			(stroke
				(width 0.1524)
				(type default)
			)
			(layer "F.SilkS")
		)
		(fp_line
			(start 1.2954 -0.5842)
			(end 1.2954 0.5842)
			(stroke
				(width 0.1524)
				(type default)
			)
			(layer "F.SilkS")
		)
		(fp_line
			(start 1.2954 0.5842)
			(end -1.2954 0.5842)
			(stroke
				(width 0.1524)
				(type default)
			)
			(layer "F.SilkS")
		)
		(fp_line
			(start -1.1938 -0.406654)
			(end -0.8636 -0.406654)
			(stroke
				(width 0.1)
				(type default)
			)
			(layer "F.Fab")
		)
		(fp_line
			(start -1.1938 0.4064)
			(end -1.1938 -0.406654)
			(stroke
				(width 0.1)
				(type default)
			)
			(layer "F.Fab")
		)
		(fp_line
			(start -0.8636 -0.4572)
			(end 0.8636 -0.4572)
			(stroke
				(width 0.1)
				(type default)
			)
			(layer "F.Fab")
		)
		(fp_line
			(start -0.8636 -0.406654)
			(end -0.8636 -0.4572)
			(stroke
				(width 0.1)
				(type default)
			)
			(layer "F.Fab")
		)
		(fp_line
			(start -0.8636 0.4064)
			(end -1.1938 0.4064)
			(stroke
				(width 0.1)
				(type default)
			)
			(layer "F.Fab")
		)
		(fp_line
			(start -0.8636 0.4318)
			(end -0.8636 0.4064)
			(stroke
				(width 0.1)
				(type default)
			)
			(layer "F.Fab")
		)
		(fp_line
			(start -0.8636 0.4572)
			(end -0.8636 0.4318)
			(stroke
				(width 0.1)
				(type default)
			)
			(layer "F.Fab")
		)
		(fp_line
			(start 0.8636 -0.4572)
			(end 0.8636 -0.406654)
			(stroke
				(width 0.1)
				(type default)
			)
			(layer "F.Fab")
		)
		(fp_line
			(start 0.8636 -0.406654)
			(end 1.1938 -0.406654)
			(stroke
				(width 0.1)
				(type default)
			)
			(layer "F.Fab")
		)
		(fp_line
			(start 0.8636 0.4064)
			(end 0.8636 0.4572)
			(stroke
				(width 0.1)
				(type default)
			)
			(layer "F.Fab")
		)
		(fp_line
			(start 0.8636 0.4572)
			(end -0.8636 0.4572)
			(stroke
				(width 0.1)
				(type default)
			)
			(layer "F.Fab")
		)
		(fp_line
			(start 1.1938 -0.406654)
			(end 1.1938 0.4064)
			(stroke
				(width 0.1)
				(type default)
			)
			(layer "F.Fab")
		)
		(fp_line
			(start 1.1938 0.4064)
			(end 0.8636 0.4064)
			(stroke
				(width 0.1)
				(type default)
			)
			(layer "F.Fab")
		)
		(pad "1" smd rect
			(at -0.7366 0 270)
			(size 0.7112 0.8128)
			(layers "F.Cu" "F.Mask" "F.Paste")
			(net "P52V_HS2_1272_S_P")
		)
		(pad "2" smd rect
			(at 0.7366 0 270)
			(size 0.7112 0.8128)
			(layers "F.Cu" "F.Mask" "F.Paste")
			(net "P52V_HS2_SENSE_P_R1")
		)
	)
	(footprint ""
		(layer "F.Cu")
		(at 437.134 -37.211 90)
		(property "Reference" "R13"
			(at 0 0 90)
			(layer "F.SilkS")
			(hide yes)
			(effects
				(font
					(size 1.27 1.27)
				)
			)
		)
		(property "Value" ""
			(at 0 0 90)
			(layer "F.Fab")
			(effects
				(font
					(size 1.27 1.27)
				)
			)
		)
		(duplicate_pad_numbers_are_jumpers no)
		(fp_line
			(start 0.7874 -0.4064)
			(end 0.7874 0.4064)
			(stroke
				(width 0.1524)
				(type default)
			)
			(layer "F.SilkS")
		)
		(fp_line
			(start -0.7874 -0.4064)
			(end 0.7874 -0.4064)
			(stroke
				(width 0.1524)
				(type default)
			)
			(layer "F.SilkS")
		)
		(fp_line
			(start 0.7874 0.4064)
			(end -0.7874 0.4064)
			(stroke
				(width 0.1524)
				(type default)
			)
			(layer "F.SilkS")
		)
		(fp_line
			(start -0.7874 0.4064)
			(end -0.7874 -0.4064)
			(stroke
				(width 0.1524)
				(type default)
			)
			(layer "F.SilkS")
		)
		(fp_line
			(start -0.12065 -0.305054)
			(end -0.12065 -0.2794)
			(stroke
				(width 0.1)
				(type default)
			)
			(layer "F.Fab")
		)
		(fp_line
			(start -0.67945 -0.305054)
			(end -0.12065 -0.305054)
			(stroke
				(width 0.1)
				(type default)
			)
			(layer "F.Fab")
		)
		(fp_line
			(start 0.67945 -0.3048)
			(end 0.67945 0.3048)
			(stroke
				(width 0.1)
				(type default)
			)
			(layer "F.Fab")
		)
		(fp_line
			(start 0.12065 -0.3048)
			(end 0.67945 -0.3048)
			(stroke
				(width 0.1)
				(type default)
			)
			(layer "F.Fab")
		)
		(fp_line
			(start 0.12065 -0.2794)
			(end 0.12065 -0.3048)
			(stroke
				(width 0.1)
				(type default)
			)
			(layer "F.Fab")
		)
		(fp_line
			(start -0.12065 -0.2794)
			(end 0.12065 -0.2794)
			(stroke
				(width 0.1)
				(type default)
			)
			(layer "F.Fab")
		)
		(fp_line
			(start 0.120396 0.2794)
			(end -0.12065 0.2794)
			(stroke
				(width 0.1)
				(type default)
			)
			(layer "F.Fab")
		)
		(fp_line
			(start -0.12065 0.2794)
			(end -0.12065 0.3048)
			(stroke
				(width 0.1)
				(type default)
			)
			(layer "F.Fab")
		)
		(fp_line
			(start 0.67945 0.3048)
			(end 0.120396 0.3048)
			(stroke
				(width 0.1)
				(type default)
			)
			(layer "F.Fab")
		)
		(fp_line
			(start 0.120396 0.3048)
			(end 0.120396 0.2794)
			(stroke
				(width 0.1)
				(type default)
			)
			(layer "F.Fab")
		)
		(fp_line
			(start -0.12065 0.3048)
			(end -0.67945 0.3048)
			(stroke
				(width 0.1)
				(type default)
			)
			(layer "F.Fab")
		)
		(fp_line
			(start -0.67945 0.3048)
			(end -0.67945 -0.305054)
			(stroke
				(width 0.1)
				(type default)
			)
			(layer "F.Fab")
		)
		(pad "1" smd circle
			(at -0.40005 0 90)
			(size 0 0)
			(layers "F.Cu" "F.Mask" "F.Paste")
			(net "SMB_P52V_SCL")
		)
		(pad "2" smd circle
			(at 0.40005 0 90)
			(size 0 0)
			(layers "F.Cu" "F.Mask" "F.Paste")
			(net "SMB_P52V_PDB_SCL_R")
		)
	)
	(footprint ""
		(layer "F.Cu")
		(at 438.3278 -22.352 180)
		(property "Reference" "R64"
			(at 0 0 180)
			(layer "F.SilkS")
			(hide yes)
			(effects
				(font
					(size 1.27 1.27)
				)
			)
		)
		(property "Value" ""
			(at 0 0 180)
			(layer "F.Fab")
			(effects
				(font
					(size 1.27 1.27)
				)
			)
		)
		(duplicate_pad_numbers_are_jumpers no)
		(fp_line
			(start 0.7874 0.4064)
			(end -0.7874 0.4064)
			(stroke
				(width 0.1524)
				(type default)
			)
			(layer "F.SilkS")
		)
		(fp_line
			(start 0.7874 -0.4064)
			(end 0.7874 0.4064)
			(stroke
				(width 0.1524)
				(type default)
			)
			(layer "F.SilkS")
		)
		(fp_line
			(start -0.7874 0.4064)
			(end -0.7874 -0.4064)
			(stroke
				(width 0.1524)
				(type default)
			)
			(layer "F.SilkS")
		)
		(fp_line
			(start -0.7874 -0.4064)
			(end 0.7874 -0.4064)
			(stroke
				(width 0.1524)
				(type default)
			)
			(layer "F.SilkS")
		)
		(fp_line
			(start 0.67945 0.3048)
			(end 0.120396 0.3048)
			(stroke
				(width 0.1)
				(type default)
			)
			(layer "F.Fab")
		)
		(fp_line
			(start 0.67945 -0.3048)
			(end 0.67945 0.3048)
			(stroke
				(width 0.1)
				(type default)
			)
			(layer "F.Fab")
		)
		(fp_line
			(start 0.12065 -0.2794)
			(end 0.12065 -0.3048)
			(stroke
				(width 0.1)
				(type default)
			)
			(layer "F.Fab")
		)
		(fp_line
			(start 0.12065 -0.3048)
			(end 0.67945 -0.3048)
			(stroke
				(width 0.1)
				(type default)
			)
			(layer "F.Fab")
		)
		(fp_line
			(start 0.120396 0.3048)
			(end 0.120396 0.2794)
			(stroke
				(width 0.1)
				(type default)
			)
			(layer "F.Fab")
		)
		(fp_line
			(start 0.120396 0.2794)
			(end -0.12065 0.2794)
			(stroke
				(width 0.1)
				(type default)
			)
			(layer "F.Fab")
		)
		(fp_line
			(start -0.12065 0.3048)
			(end -0.67945 0.3048)
			(stroke
				(width 0.1)
				(type default)
			)
			(layer "F.Fab")
		)
		(fp_line
			(start -0.12065 0.2794)
			(end -0.12065 0.3048)
			(stroke
				(width 0.1)
				(type default)
			)
			(layer "F.Fab")
		)
		(fp_line
			(start -0.12065 -0.2794)
			(end 0.12065 -0.2794)
			(stroke
				(width 0.1)
				(type default)
			)
			(layer "F.Fab")
		)
		(fp_line
			(start -0.12065 -0.305054)
			(end -0.12065 -0.2794)
			(stroke
				(width 0.1)
				(type default)
			)
			(layer "F.Fab")
		)
		(fp_line
			(start -0.67945 0.3048)
			(end -0.67945 -0.305054)
			(stroke
				(width 0.1)
				(type default)
			)
			(layer "F.Fab")
		)
		(fp_line
			(start -0.67945 -0.305054)
			(end -0.12065 -0.305054)
			(stroke
				(width 0.1)
				(type default)
			)
			(layer "F.Fab")
		)
		(pad "1" smd circle
			(at -0.40005 0 180)
			(size 0 0)
			(layers "F.Cu" "F.Mask" "F.Paste")
			(net "GND")
		)
		(pad "2" smd circle
			(at 0.40005 0 180)
			(size 0 0)
			(layers "F.Cu" "F.Mask" "F.Paste")
			(net "FRU_ADDR2")
		)
	)
	(footprint ""
		(layer "F.Cu")
		(at 416.814 -51.562 90)
		(property "Reference" "R161"
			(at 0 0 90)
			(layer "F.SilkS")
			(hide yes)
			(effects
				(font
					(size 1.27 1.27)
				)
			)
		)
		(property "Value" ""
			(at 0 0 90)
			(layer "F.Fab")
			(effects
				(font
					(size 1.27 1.27)
				)
			)
		)
		(duplicate_pad_numbers_are_jumpers no)
		(fp_line
			(start 0.7874 -0.4064)
			(end 0.7874 0.4064)
			(stroke
				(width 0.1524)
				(type default)
			)
			(layer "F.SilkS")
		)
		(fp_line
			(start -0.7874 -0.4064)
			(end 0.7874 -0.4064)
			(stroke
				(width 0.1524)
				(type default)
			)
			(layer "F.SilkS")
		)
		(fp_line
			(start 0.7874 0.4064)
			(end -0.7874 0.4064)
			(stroke
				(width 0.1524)
				(type default)
			)
			(layer "F.SilkS")
		)
		(fp_line
			(start -0.7874 0.4064)
			(end -0.7874 -0.4064)
			(stroke
				(width 0.1524)
				(type default)
			)
			(layer "F.SilkS")
		)
		(fp_line
			(start -0.12065 -0.305054)
			(end -0.12065 -0.2794)
			(stroke
				(width 0.1)
				(type default)
			)
			(layer "F.Fab")
		)
		(fp_line
			(start -0.67945 -0.305054)
			(end -0.12065 -0.305054)
			(stroke
				(width 0.1)
				(type default)
			)
			(layer "F.Fab")
		)
		(fp_line
			(start 0.67945 -0.3048)
			(end 0.67945 0.3048)
			(stroke
				(width 0.1)
				(type default)
			)
			(layer "F.Fab")
		)
		(fp_line
			(start 0.12065 -0.3048)
			(end 0.67945 -0.3048)
			(stroke
				(width 0.1)
				(type default)
			)
			(layer "F.Fab")
		)
		(fp_line
			(start 0.12065 -0.2794)
			(end 0.12065 -0.3048)
			(stroke
				(width 0.1)
				(type default)
			)
			(layer "F.Fab")
		)
		(fp_line
			(start -0.12065 -0.2794)
			(end 0.12065 -0.2794)
			(stroke
				(width 0.1)
				(type default)
			)
			(layer "F.Fab")
		)
		(fp_line
			(start 0.120396 0.2794)
			(end -0.12065 0.2794)
			(stroke
				(width 0.1)
				(type default)
			)
			(layer "F.Fab")
		)
		(fp_line
			(start -0.12065 0.2794)
			(end -0.12065 0.3048)
			(stroke
				(width 0.1)
				(type default)
			)
			(layer "F.Fab")
		)
		(fp_line
			(start 0.67945 0.3048)
			(end 0.120396 0.3048)
			(stroke
				(width 0.1)
				(type default)
			)
			(layer "F.Fab")
		)
		(fp_line
			(start 0.120396 0.3048)
			(end 0.120396 0.2794)
			(stroke
				(width 0.1)
				(type default)
			)
			(layer "F.Fab")
		)
		(fp_line
			(start -0.12065 0.3048)
			(end -0.67945 0.3048)
			(stroke
				(width 0.1)
				(type default)
			)
			(layer "F.Fab")
		)
		(fp_line
			(start -0.67945 0.3048)
			(end -0.67945 -0.305054)
			(stroke
				(width 0.1)
				(type default)
			)
			(layer "F.Fab")
		)
		(pad "1" smd circle
			(at -0.40005 0 90)
			(size 0 0)
			(layers "F.Cu" "F.Mask" "F.Paste")
			(net "PWRGD_P52V_HS1_4287_PG_R_N")
		)
		(pad "2" smd circle
			(at 0.40005 0 90)
			(size 0 0)
			(layers "F.Cu" "F.Mask" "F.Paste")
			(net "GND")
		)
	)
	(footprint ""
		(layer "F.Cu")
		(at 417.90112 -32.766 90)
		(property "Reference" "R5923"
			(at 0 0 90)
			(layer "F.SilkS")
			(hide yes)
			(effects
				(font
					(size 1.27 1.27)
				)
			)
		)
		(property "Value" ""
			(at 0 0 90)
			(layer "F.Fab")
			(effects
				(font
					(size 1.27 1.27)
				)
			)
		)
		(duplicate_pad_numbers_are_jumpers no)
		(fp_line
			(start 0.7874 -0.4064)
			(end 0.7874 0.4064)
			(stroke
				(width 0.1524)
				(type default)
			)
			(layer "F.SilkS")
		)
		(fp_line
			(start -0.7874 -0.4064)
			(end 0.7874 -0.4064)
			(stroke
				(width 0.1524)
				(type default)
			)
			(layer "F.SilkS")
		)
		(fp_line
			(start 0.7874 0.4064)
			(end -0.7874 0.4064)
			(stroke
				(width 0.1524)
				(type default)
			)
			(layer "F.SilkS")
		)
		(fp_line
			(start -0.7874 0.4064)
			(end -0.7874 -0.4064)
			(stroke
				(width 0.1524)
				(type default)
			)
			(layer "F.SilkS")
		)
		(fp_line
			(start -0.12065 -0.305054)
			(end -0.12065 -0.2794)
			(stroke
				(width 0.1)
				(type default)
			)
			(layer "F.Fab")
		)
		(fp_line
			(start -0.67945 -0.305054)
			(end -0.12065 -0.305054)
			(stroke
				(width 0.1)
				(type default)
			)
			(layer "F.Fab")
		)
		(fp_line
			(start 0.67945 -0.3048)
			(end 0.67945 0.3048)
			(stroke
				(width 0.1)
				(type default)
			)
			(layer "F.Fab")
		)
		(fp_line
			(start 0.12065 -0.3048)
			(end 0.67945 -0.3048)
			(stroke
				(width 0.1)
				(type default)
			)
			(layer "F.Fab")
		)
		(fp_line
			(start 0.12065 -0.2794)
			(end 0.12065 -0.3048)
			(stroke
				(width 0.1)
				(type default)
			)
			(layer "F.Fab")
		)
		(fp_line
			(start -0.12065 -0.2794)
			(end 0.12065 -0.2794)
			(stroke
				(width 0.1)
				(type default)
			)
			(layer "F.Fab")
		)
		(fp_line
			(start 0.120396 0.2794)
			(end -0.12065 0.2794)
			(stroke
				(width 0.1)
				(type default)
			)
			(layer "F.Fab")
		)
		(fp_line
			(start -0.12065 0.2794)
			(end -0.12065 0.3048)
			(stroke
				(width 0.1)
				(type default)
			)
			(layer "F.Fab")
		)
		(fp_line
			(start 0.67945 0.3048)
			(end 0.120396 0.3048)
			(stroke
				(width 0.1)
				(type default)
			)
			(layer "F.Fab")
		)
		(fp_line
			(start 0.120396 0.3048)
			(end 0.120396 0.2794)
			(stroke
				(width 0.1)
				(type default)
			)
			(layer "F.Fab")
		)
		(fp_line
			(start -0.12065 0.3048)
			(end -0.67945 0.3048)
			(stroke
				(width 0.1)
				(type default)
			)
			(layer "F.Fab")
		)
		(fp_line
			(start -0.67945 0.3048)
			(end -0.67945 -0.305054)
			(stroke
				(width 0.1)
				(type default)
			)
			(layer "F.Fab")
		)
		(pad "1" smd circle
			(at -0.40005 0 90)
			(size 0 0)
			(layers "F.Cu" "F.Mask" "F.Paste")
			(net "P12V_LED_ISET")
		)
		(pad "2" smd circle
			(at 0.40005 0 90)
			(size 0 0)
			(layers "F.Cu" "F.Mask" "F.Paste")
			(net "GND")
		)
	)
	(footprint ""
		(layer "F.Cu")
		(at 430.276 -38.989 180)
		(property "Reference" "R134"
			(at 0 0 180)
			(layer "F.SilkS")
			(hide yes)
			(effects
				(font
					(size 1.27 1.27)
				)
			)
		)
		(property "Value" ""
			(at 0 0 180)
			(layer "F.Fab")
			(effects
				(font
					(size 1.27 1.27)
				)
			)
		)
		(duplicate_pad_numbers_are_jumpers no)
		(fp_line
			(start 0.7874 0.4064)
			(end -0.7874 0.4064)
			(stroke
				(width 0.1524)
				(type default)
			)
			(layer "F.SilkS")
		)
		(fp_line
			(start 0.7874 -0.4064)
			(end 0.7874 0.4064)
			(stroke
				(width 0.1524)
				(type default)
			)
			(layer "F.SilkS")
		)
		(fp_line
			(start -0.7874 0.4064)
			(end -0.7874 -0.4064)
			(stroke
				(width 0.1524)
				(type default)
			)
			(layer "F.SilkS")
		)
		(fp_line
			(start -0.7874 -0.4064)
			(end 0.7874 -0.4064)
			(stroke
				(width 0.1524)
				(type default)
			)
			(layer "F.SilkS")
		)
		(fp_line
			(start 0.67945 0.3048)
			(end 0.120396 0.3048)
			(stroke
				(width 0.1)
				(type default)
			)
			(layer "F.Fab")
		)
		(fp_line
			(start 0.67945 -0.3048)
			(end 0.67945 0.3048)
			(stroke
				(width 0.1)
				(type default)
			)
			(layer "F.Fab")
		)
		(fp_line
			(start 0.12065 -0.2794)
			(end 0.12065 -0.3048)
			(stroke
				(width 0.1)
				(type default)
			)
			(layer "F.Fab")
		)
		(fp_line
			(start 0.12065 -0.3048)
			(end 0.67945 -0.3048)
			(stroke
				(width 0.1)
				(type default)
			)
			(layer "F.Fab")
		)
		(fp_line
			(start 0.120396 0.3048)
			(end 0.120396 0.2794)
			(stroke
				(width 0.1)
				(type default)
			)
			(layer "F.Fab")
		)
		(fp_line
			(start 0.120396 0.2794)
			(end -0.12065 0.2794)
			(stroke
				(width 0.1)
				(type default)
			)
			(layer "F.Fab")
		)
		(fp_line
			(start -0.12065 0.3048)
			(end -0.67945 0.3048)
			(stroke
				(width 0.1)
				(type default)
			)
			(layer "F.Fab")
		)
		(fp_line
			(start -0.12065 0.2794)
			(end -0.12065 0.3048)
			(stroke
				(width 0.1)
				(type default)
			)
			(layer "F.Fab")
		)
		(fp_line
			(start -0.12065 -0.2794)
			(end 0.12065 -0.2794)
			(stroke
				(width 0.1)
				(type default)
			)
			(layer "F.Fab")
		)
		(fp_line
			(start -0.12065 -0.305054)
			(end -0.12065 -0.2794)
			(stroke
				(width 0.1)
				(type default)
			)
			(layer "F.Fab")
		)
		(fp_line
			(start -0.67945 0.3048)
			(end -0.67945 -0.305054)
			(stroke
				(width 0.1)
				(type default)
			)
			(layer "F.Fab")
		)
		(fp_line
			(start -0.67945 -0.305054)
			(end -0.12065 -0.305054)
			(stroke
				(width 0.1)
				(type default)
			)
			(layer "F.Fab")
		)
		(pad "1" smd circle
			(at -0.40005 0 180)
			(size 0 0)
			(layers "F.Cu" "F.Mask" "F.Paste")
			(net "P3V3_AUX")
		)
		(pad "2" smd circle
			(at 0.40005 0 180)
			(size 0 0)
			(layers "F.Cu" "F.Mask" "F.Paste")
			(net "BOARD_ID_1")
		)
	)
	(footprint ""
		(layer "F.Cu")
		(at 424.942 -26.67 90)
		(property "Reference" "D4"
			(at -3.7084 -2.733548 90)
			(unlocked yes)
			(layer "F.SilkS")
			(effects
				(font
					(size 0.7874 0.5842)
					(thickness 0.1524)
				)
				(justify left)
			)
		)
		(property "Value" ""
			(at 0 0 90)
			(layer "F.Fab")
			(effects
				(font
					(size 1.27 1.27)
				)
			)
		)
		(duplicate_pad_numbers_are_jumpers no)
		(fp_line
			(start 4.240784 -1.970024)
			(end -3.656584 -1.970024)
			(stroke
				(width 0.1524)
				(type default)
			)
			(layer "F.SilkS")
		)
		(fp_line
			(start -3.656584 -1.970024)
			(end -3.656584 1.970024)
			(stroke
				(width 0.1524)
				(type default)
			)
			(layer "F.SilkS")
		)
		(fp_line
			(start 4.240784 1.970024)
			(end 4.240784 -1.970024)
			(stroke
				(width 0.1524)
				(type default)
			)
			(layer "F.SilkS")
		)
		(fp_line
			(start -3.656584 1.970024)
			(end 4.240784 1.970024)
			(stroke
				(width 0.1524)
				(type default)
			)
			(layer "F.SilkS")
		)
		(fp_poly
			(pts
				(xy 3.580384 1.970024) (xy 3.580384 -1.970024) (xy 4.240784 -1.970024) (xy 4.240784 1.970024)
			)
			(stroke
				(width 0)
				(type default)
			)
			(fill yes)
			(layer "F.SilkS")
		)
		(fp_line
			(start 2.3749 -1.970024)
			(end -2.3749 -1.970024)
			(stroke
				(width 0.1)
				(type default)
			)
			(layer "F.Fab")
		)
		(fp_line
			(start -2.3749 -1.970024)
			(end -2.3749 1.970024)
			(stroke
				(width 0.1)
				(type default)
			)
			(layer "F.Fab")
		)
		(fp_line
			(start 2.3749 1.970024)
			(end 2.3749 -1.970024)
			(stroke
				(width 0.1)
				(type default)
			)
			(layer "F.Fab")
		)
		(fp_line
			(start -2.3749 1.970024)
			(end 2.3749 1.970024)
			(stroke
				(width 0.1)
				(type default)
			)
			(layer "F.Fab")
		)
		(fp_text user "-"
			(at 4.1656 -0.23495 90)
			(unlocked yes)
			(layer "F.Fab")
			(effects
				(font
					(size 1.905 1.4224)
					(thickness 0.1524)
				)
				(justify left)
			)
		)
		(fp_text user "+"
			(at -4.9784 -0.23495 90)
			(unlocked yes)
			(layer "F.Fab")
			(effects
				(font
					(size 1.905 1.4224)
					(thickness 0.1524)
				)
				(justify left)
			)
		)
		(pad "A" smd rect
			(at -2.450084 0 90)
			(size 2.159 2.2606)
			(layers "F.Cu" "F.Mask" "F.Paste")
			(net "GND")
		)
		(pad "C" smd rect
			(at 2.450084 0 90)
			(size 2.159 2.2606)
			(layers "F.Cu" "F.Mask" "F.Paste")
			(net "P12V_HPDB")
		)
	)
	(footprint ""
		(layer "F.Cu")
		(at 130.412236 -83.566)
		(property "Reference" "PR6997"
			(at 0 0 0)
			(layer "F.SilkS")
			(hide yes)
			(effects
				(font
					(size 1.27 1.27)
				)
			)
		)
		(property "Value" ""
			(at 0 0 0)
			(layer "F.Fab")
			(effects
				(font
					(size 1.27 1.27)
				)
			)
		)
		(duplicate_pad_numbers_are_jumpers no)
		(fp_line
			(start -0.7874 -0.4064)
			(end 0.7874 -0.4064)
			(stroke
				(width 0.1524)
				(type default)
			)
			(layer "F.SilkS")
		)
		(fp_line
			(start -0.7874 0.4064)
			(end -0.7874 -0.4064)
			(stroke
				(width 0.1524)
				(type default)
			)
			(layer "F.SilkS")
		)
		(fp_line
			(start 0.7874 -0.4064)
			(end 0.7874 0.4064)
			(stroke
				(width 0.1524)
				(type default)
			)
			(layer "F.SilkS")
		)
		(fp_line
			(start 0.7874 0.4064)
			(end -0.7874 0.4064)
			(stroke
				(width 0.1524)
				(type default)
			)
			(layer "F.SilkS")
		)
		(fp_line
			(start -0.67945 -0.305054)
			(end -0.12065 -0.305054)
			(stroke
				(width 0.1)
				(type default)
			)
			(layer "F.Fab")
		)
		(fp_line
			(start -0.67945 0.3048)
			(end -0.67945 -0.305054)
			(stroke
				(width 0.1)
				(type default)
			)
			(layer "F.Fab")
		)
		(fp_line
			(start -0.12065 -0.305054)
			(end -0.12065 -0.2794)
			(stroke
				(width 0.1)
				(type default)
			)
			(layer "F.Fab")
		)
		(fp_line
			(start -0.12065 -0.2794)
			(end 0.12065 -0.2794)
			(stroke
				(width 0.1)
				(type default)
			)
			(layer "F.Fab")
		)
		(fp_line
			(start -0.12065 0.2794)
			(end -0.12065 0.3048)
			(stroke
				(width 0.1)
				(type default)
			)
			(layer "F.Fab")
		)
		(fp_line
			(start -0.12065 0.3048)
			(end -0.67945 0.3048)
			(stroke
				(width 0.1)
				(type default)
			)
			(layer "F.Fab")
		)
		(fp_line
			(start 0.120396 0.2794)
			(end -0.12065 0.2794)
			(stroke
				(width 0.1)
				(type default)
			)
			(layer "F.Fab")
		)
		(fp_line
			(start 0.120396 0.3048)
			(end 0.120396 0.2794)
			(stroke
				(width 0.1)
				(type default)
			)
			(layer "F.Fab")
		)
		(fp_line
			(start 0.12065 -0.3048)
			(end 0.67945 -0.3048)
			(stroke
				(width 0.1)
				(type default)
			)
			(layer "F.Fab")
		)
		(fp_line
			(start 0.12065 -0.2794)
			(end 0.12065 -0.3048)
			(stroke
				(width 0.1)
				(type default)
			)
			(layer "F.Fab")
		)
		(fp_line
			(start 0.67945 -0.3048)
			(end 0.67945 0.3048)
			(stroke
				(width 0.1)
				(type default)
			)
			(layer "F.Fab")
		)
		(fp_line
			(start 0.67945 0.3048)
			(end 0.120396 0.3048)
			(stroke
				(width 0.1)
				(type default)
			)
			(layer "F.Fab")
		)
		(pad "1" smd rect
			(at -0.40005 0 180)
			(size 0.4572 0.508)
			(layers "F.Cu" "F.Mask" "F.Paste")
			(net "P52V_HS2_TEMPN_R")
		)
		(pad "2" smd rect
			(at 0.40005 0 180)
			(size 0.4572 0.508)
			(layers "F.Cu" "F.Mask" "F.Paste")
			(net "GND1_FIELD_SIGNAL")
		)
	)
	(footprint ""
		(layer "F.Cu")
		(at 271.2974 -79.121 180)
		(property "Reference" "PC576"
			(at 0 0 180)
			(layer "F.SilkS")
			(hide yes)
			(effects
				(font
					(size 1.27 1.27)
				)
			)
		)
		(property "Value" ""
			(at 0 0 180)
			(layer "F.Fab")
			(effects
				(font
					(size 1.27 1.27)
				)
			)
		)
		(duplicate_pad_numbers_are_jumpers no)
		(fp_line
			(start 0.7874 0.4064)
			(end -0.7874 0.4064)
			(stroke
				(width 0.1524)
				(type default)
			)
			(layer "F.SilkS")
		)
		(fp_line
			(start 0.7874 -0.4064)
			(end 0.7874 0.4064)
			(stroke
				(width 0.1524)
				(type default)
			)
			(layer "F.SilkS")
		)
		(fp_line
			(start -0.7874 0.4064)
			(end -0.7874 -0.4064)
			(stroke
				(width 0.1524)
				(type default)
			)
			(layer "F.SilkS")
		)
		(fp_line
			(start -0.7874 -0.4064)
			(end 0.7874 -0.4064)
			(stroke
				(width 0.1524)
				(type default)
			)
			(layer "F.SilkS")
		)
		(fp_line
			(start 0.67945 0.3048)
			(end 0.120396 0.3048)
			(stroke
				(width 0.1)
				(type default)
			)
			(layer "F.Fab")
		)
		(fp_line
			(start 0.67945 -0.3048)
			(end 0.67945 0.3048)
			(stroke
				(width 0.1)
				(type default)
			)
			(layer "F.Fab")
		)
		(fp_line
			(start 0.12065 -0.2794)
			(end 0.12065 -0.3048)
			(stroke
				(width 0.1)
				(type default)
			)
			(layer "F.Fab")
		)
		(fp_line
			(start 0.12065 -0.3048)
			(end 0.67945 -0.3048)
			(stroke
				(width 0.1)
				(type default)
			)
			(layer "F.Fab")
		)
		(fp_line
			(start 0.120396 0.3048)
			(end 0.120396 0.2794)
			(stroke
				(width 0.1)
				(type default)
			)
			(layer "F.Fab")
		)
		(fp_line
			(start 0.120396 0.2794)
			(end -0.12065 0.2794)
			(stroke
				(width 0.1)
				(type default)
			)
			(layer "F.Fab")
		)
		(fp_line
			(start -0.12065 0.3048)
			(end -0.67945 0.3048)
			(stroke
				(width 0.1)
				(type default)
			)
			(layer "F.Fab")
		)
		(fp_line
			(start -0.12065 0.2794)
			(end -0.12065 0.3048)
			(stroke
				(width 0.1)
				(type default)
			)
			(layer "F.Fab")
		)
		(fp_line
			(start -0.12065 -0.2794)
			(end 0.12065 -0.2794)
			(stroke
				(width 0.1)
				(type default)
			)
			(layer "F.Fab")
		)
		(fp_line
			(start -0.12065 -0.305054)
			(end -0.12065 -0.2794)
			(stroke
				(width 0.1)
				(type default)
			)
			(layer "F.Fab")
		)
		(fp_line
			(start -0.67945 0.3048)
			(end -0.67945 -0.305054)
			(stroke
				(width 0.1)
				(type default)
			)
			(layer "F.Fab")
		)
		(fp_line
			(start -0.67945 -0.305054)
			(end -0.12065 -0.305054)
			(stroke
				(width 0.1)
				(type default)
			)
			(layer "F.Fab")
		)
		(pad "1" smd circle
			(at -0.40005 0 180)
			(size 0 0)
			(layers "F.Cu" "F.Mask" "F.Paste")
			(net "P52V_HS1_UVLO_EN")
		)
		(pad "2" smd circle
			(at 0.40005 0 180)
			(size 0 0)
			(layers "F.Cu" "F.Mask" "F.Paste")
			(net "GND_FIELD_SIGNAL")
		)
	)
	(footprint ""
		(layer "F.Cu")
		(at 334.631284 -61.6204 -90)
		(property "Reference" "PR475"
			(at 0 0 270)
			(layer "F.SilkS")
			(hide yes)
			(effects
				(font
					(size 1.27 1.27)
				)
			)
		)
		(property "Value" ""
			(at 0 0 270)
			(layer "F.Fab")
			(effects
				(font
					(size 1.27 1.27)
				)
			)
		)
		(duplicate_pad_numbers_are_jumpers no)
		(fp_line
			(start -1.2954 0.5842)
			(end -1.2954 -0.5842)
			(stroke
				(width 0.1524)
				(type default)
			)
			(layer "F.SilkS")
		)
		(fp_line
			(start 1.2954 0.5842)
			(end -1.2954 0.5842)
			(stroke
				(width 0.1524)
				(type default)
			)
			(layer "F.SilkS")
		)
		(fp_line
			(start -1.2954 -0.5842)
			(end 1.2954 -0.5842)
			(stroke
				(width 0.1524)
				(type default)
			)
			(layer "F.SilkS")
		)
		(fp_line
			(start 1.2954 -0.5842)
			(end 1.2954 0.5842)
			(stroke
				(width 0.1524)
				(type default)
			)
			(layer "F.SilkS")
		)
		(fp_line
			(start -0.8636 0.4572)
			(end -0.8636 0.4318)
			(stroke
				(width 0.1)
				(type default)
			)
			(layer "F.Fab")
		)
		(fp_line
			(start 0.8636 0.4572)
			(end -0.8636 0.4572)
			(stroke
				(width 0.1)
				(type default)
			)
			(layer "F.Fab")
		)
		(fp_line
			(start -0.8636 0.4318)
			(end -0.8636 0.4064)
			(stroke
				(width 0.1)
				(type default)
			)
			(layer "F.Fab")
		)
		(fp_line
			(start -1.1938 0.4064)
			(end -1.1938 -0.406654)
			(stroke
				(width 0.1)
				(type default)
			)
			(layer "F.Fab")
		)
		(fp_line
			(start -0.8636 0.4064)
			(end -1.1938 0.4064)
			(stroke
				(width 0.1)
				(type default)
			)
			(layer "F.Fab")
		)
		(fp_line
			(start 0.8636 0.4064)
			(end 0.8636 0.4572)
			(stroke
				(width 0.1)
				(type default)
			)
			(layer "F.Fab")
		)
		(fp_line
			(start 1.1938 0.4064)
			(end 0.8636 0.4064)
			(stroke
				(width 0.1)
				(type default)
			)
			(layer "F.Fab")
		)
		(fp_line
			(start -1.1938 -0.406654)
			(end -0.8636 -0.406654)
			(stroke
				(width 0.1)
				(type default)
			)
			(layer "F.Fab")
		)
		(fp_line
			(start -0.8636 -0.406654)
			(end -0.8636 -0.4572)
			(stroke
				(width 0.1)
				(type default)
			)
			(layer "F.Fab")
		)
		(fp_line
			(start 0.8636 -0.406654)
			(end 1.1938 -0.406654)
			(stroke
				(width 0.1)
				(type default)
			)
			(layer "F.Fab")
		)
		(fp_line
			(start 1.1938 -0.406654)
			(end 1.1938 0.4064)
			(stroke
				(width 0.1)
				(type default)
			)
			(layer "F.Fab")
		)
		(fp_line
			(start -0.8636 -0.4572)
			(end 0.8636 -0.4572)
			(stroke
				(width 0.1)
				(type default)
			)
			(layer "F.Fab")
		)
		(fp_line
			(start 0.8636 -0.4572)
			(end 0.8636 -0.406654)
			(stroke
				(width 0.1)
				(type default)
			)
			(layer "F.Fab")
		)
		(pad "1" smd rect
			(at -0.7366 0 180)
			(size 0.7112 0.8128)
			(layers "F.Cu" "F.Mask" "F.Paste")
			(net "P52V_HS1_GATE1_R")
		)
		(pad "2" smd rect
			(at 0.7366 0 180)
			(size 0.7112 0.8128)
			(layers "F.Cu" "F.Mask" "F.Paste")
			(net "P52V_HS1_GATE2")
		)
	)
	(footprint ""
		(layer "F.Cu")
		(at 430.276 -37.592 180)
		(property "Reference" "R135"
			(at 0 0 180)
			(layer "F.SilkS")
			(hide yes)
			(effects
				(font
					(size 1.27 1.27)
				)
			)
		)
		(property "Value" ""
			(at 0 0 180)
			(layer "F.Fab")
			(effects
				(font
					(size 1.27 1.27)
				)
			)
		)
		(duplicate_pad_numbers_are_jumpers no)
		(fp_line
			(start 0.7874 0.4064)
			(end -0.7874 0.4064)
			(stroke
				(width 0.1524)
				(type default)
			)
			(layer "F.SilkS")
		)
		(fp_line
			(start 0.7874 -0.4064)
			(end 0.7874 0.4064)
			(stroke
				(width 0.1524)
				(type default)
			)
			(layer "F.SilkS")
		)
		(fp_line
			(start -0.7874 0.4064)
			(end -0.7874 -0.4064)
			(stroke
				(width 0.1524)
				(type default)
			)
			(layer "F.SilkS")
		)
		(fp_line
			(start -0.7874 -0.4064)
			(end 0.7874 -0.4064)
			(stroke
				(width 0.1524)
				(type default)
			)
			(layer "F.SilkS")
		)
		(fp_line
			(start 0.67945 0.3048)
			(end 0.120396 0.3048)
			(stroke
				(width 0.1)
				(type default)
			)
			(layer "F.Fab")
		)
		(fp_line
			(start 0.67945 -0.3048)
			(end 0.67945 0.3048)
			(stroke
				(width 0.1)
				(type default)
			)
			(layer "F.Fab")
		)
		(fp_line
			(start 0.12065 -0.2794)
			(end 0.12065 -0.3048)
			(stroke
				(width 0.1)
				(type default)
			)
			(layer "F.Fab")
		)
		(fp_line
			(start 0.12065 -0.3048)
			(end 0.67945 -0.3048)
			(stroke
				(width 0.1)
				(type default)
			)
			(layer "F.Fab")
		)
		(fp_line
			(start 0.120396 0.3048)
			(end 0.120396 0.2794)
			(stroke
				(width 0.1)
				(type default)
			)
			(layer "F.Fab")
		)
		(fp_line
			(start 0.120396 0.2794)
			(end -0.12065 0.2794)
			(stroke
				(width 0.1)
				(type default)
			)
			(layer "F.Fab")
		)
		(fp_line
			(start -0.12065 0.3048)
			(end -0.67945 0.3048)
			(stroke
				(width 0.1)
				(type default)
			)
			(layer "F.Fab")
		)
		(fp_line
			(start -0.12065 0.2794)
			(end -0.12065 0.3048)
			(stroke
				(width 0.1)
				(type default)
			)
			(layer "F.Fab")
		)
		(fp_line
			(start -0.12065 -0.2794)
			(end 0.12065 -0.2794)
			(stroke
				(width 0.1)
				(type default)
			)
			(layer "F.Fab")
		)
		(fp_line
			(start -0.12065 -0.305054)
			(end -0.12065 -0.2794)
			(stroke
				(width 0.1)
				(type default)
			)
			(layer "F.Fab")
		)
		(fp_line
			(start -0.67945 0.3048)
			(end -0.67945 -0.305054)
			(stroke
				(width 0.1)
				(type default)
			)
			(layer "F.Fab")
		)
		(fp_line
			(start -0.67945 -0.305054)
			(end -0.12065 -0.305054)
			(stroke
				(width 0.1)
				(type default)
			)
			(layer "F.Fab")
		)
		(pad "1" smd circle
			(at -0.40005 0 180)
			(size 0 0)
			(layers "F.Cu" "F.Mask" "F.Paste")
			(net "P3V3_AUX")
		)
		(pad "2" smd circle
			(at 0.40005 0 180)
			(size 0 0)
			(layers "F.Cu" "F.Mask" "F.Paste")
			(net "BOARD_ID_0")
		)
	)
	(footprint ""
		(layer "F.Cu")
		(at 112.988852 -66.6496 -90)
		(property "Reference" "PR6971"
			(at 0 0 270)
			(layer "F.SilkS")
			(hide yes)
			(effects
				(font
					(size 1.27 1.27)
				)
			)
		)
		(property "Value" ""
			(at 0 0 270)
			(layer "F.Fab")
			(effects
				(font
					(size 1.27 1.27)
				)
			)
		)
		(duplicate_pad_numbers_are_jumpers no)
		(fp_line
			(start -1.2954 0.5842)
			(end -1.2954 -0.5842)
			(stroke
				(width 0.1524)
				(type default)
			)
			(layer "F.SilkS")
		)
		(fp_line
			(start 1.2954 0.5842)
			(end -1.2954 0.5842)
			(stroke
				(width 0.1524)
				(type default)
			)
			(layer "F.SilkS")
		)
		(fp_line
			(start -1.2954 -0.5842)
			(end 1.2954 -0.5842)
			(stroke
				(width 0.1524)
				(type default)
			)
			(layer "F.SilkS")
		)
		(fp_line
			(start 1.2954 -0.5842)
			(end 1.2954 0.5842)
			(stroke
				(width 0.1524)
				(type default)
			)
			(layer "F.SilkS")
		)
		(fp_line
			(start -0.8636 0.4572)
			(end -0.8636 0.4318)
			(stroke
				(width 0.1)
				(type default)
			)
			(layer "F.Fab")
		)
		(fp_line
			(start 0.8636 0.4572)
			(end -0.8636 0.4572)
			(stroke
				(width 0.1)
				(type default)
			)
			(layer "F.Fab")
		)
		(fp_line
			(start -0.8636 0.4318)
			(end -0.8636 0.4064)
			(stroke
				(width 0.1)
				(type default)
			)
			(layer "F.Fab")
		)
		(fp_line
			(start -1.1938 0.4064)
			(end -1.1938 -0.406654)
			(stroke
				(width 0.1)
				(type default)
			)
			(layer "F.Fab")
		)
		(fp_line
			(start -0.8636 0.4064)
			(end -1.1938 0.4064)
			(stroke
				(width 0.1)
				(type default)
			)
			(layer "F.Fab")
		)
		(fp_line
			(start 0.8636 0.4064)
			(end 0.8636 0.4572)
			(stroke
				(width 0.1)
				(type default)
			)
			(layer "F.Fab")
		)
		(fp_line
			(start 1.1938 0.4064)
			(end 0.8636 0.4064)
			(stroke
				(width 0.1)
				(type default)
			)
			(layer "F.Fab")
		)
		(fp_line
			(start -1.1938 -0.406654)
			(end -0.8636 -0.406654)
			(stroke
				(width 0.1)
				(type default)
			)
			(layer "F.Fab")
		)
		(fp_line
			(start -0.8636 -0.406654)
			(end -0.8636 -0.4572)
			(stroke
				(width 0.1)
				(type default)
			)
			(layer "F.Fab")
		)
		(fp_line
			(start 0.8636 -0.406654)
			(end 1.1938 -0.406654)
			(stroke
				(width 0.1)
				(type default)
			)
			(layer "F.Fab")
		)
		(fp_line
			(start 1.1938 -0.406654)
			(end 1.1938 0.4064)
			(stroke
				(width 0.1)
				(type default)
			)
			(layer "F.Fab")
		)
		(fp_line
			(start -0.8636 -0.4572)
			(end 0.8636 -0.4572)
			(stroke
				(width 0.1)
				(type default)
			)
			(layer "F.Fab")
		)
		(fp_line
			(start 0.8636 -0.4572)
			(end 0.8636 -0.406654)
			(stroke
				(width 0.1)
				(type default)
			)
			(layer "F.Fab")
		)
		(pad "1" smd rect
			(at -0.7366 0 180)
			(size 0.7112 0.8128)
			(layers "F.Cu" "F.Mask" "F.Paste")
			(net "P52V_HS2_GATE1_R")
		)
		(pad "2" smd rect
			(at 0.7366 0 180)
			(size 0.7112 0.8128)
			(layers "F.Cu" "F.Mask" "F.Paste")
			(net "P52V_HS2_GATE2")
		)
	)
	(footprint ""
		(layer "F.Cu")
		(at 440.309 -51.181 180)
		(property "Reference" "R386"
			(at 0 0 180)
			(layer "F.SilkS")
			(hide yes)
			(effects
				(font
					(size 1.27 1.27)
				)
			)
		)
		(property "Value" ""
			(at 0 0 180)
			(layer "F.Fab")
			(effects
				(font
					(size 1.27 1.27)
				)
			)
		)
		(duplicate_pad_numbers_are_jumpers no)
		(fp_line
			(start 0.7874 0.4064)
			(end -0.7874 0.4064)
			(stroke
				(width 0.1524)
				(type default)
			)
			(layer "F.SilkS")
		)
		(fp_line
			(start 0.7874 -0.4064)
			(end 0.7874 0.4064)
			(stroke
				(width 0.1524)
				(type default)
			)
			(layer "F.SilkS")
		)
		(fp_line
			(start -0.7874 0.4064)
			(end -0.7874 -0.4064)
			(stroke
				(width 0.1524)
				(type default)
			)
			(layer "F.SilkS")
		)
		(fp_line
			(start -0.7874 -0.4064)
			(end 0.7874 -0.4064)
			(stroke
				(width 0.1524)
				(type default)
			)
			(layer "F.SilkS")
		)
		(fp_line
			(start 0.67945 0.3048)
			(end 0.120396 0.3048)
			(stroke
				(width 0.1)
				(type default)
			)
			(layer "F.Fab")
		)
		(fp_line
			(start 0.67945 -0.3048)
			(end 0.67945 0.3048)
			(stroke
				(width 0.1)
				(type default)
			)
			(layer "F.Fab")
		)
		(fp_line
			(start 0.12065 -0.2794)
			(end 0.12065 -0.3048)
			(stroke
				(width 0.1)
				(type default)
			)
			(layer "F.Fab")
		)
		(fp_line
			(start 0.12065 -0.3048)
			(end 0.67945 -0.3048)
			(stroke
				(width 0.1)
				(type default)
			)
			(layer "F.Fab")
		)
		(fp_line
			(start 0.120396 0.3048)
			(end 0.120396 0.2794)
			(stroke
				(width 0.1)
				(type default)
			)
			(layer "F.Fab")
		)
		(fp_line
			(start 0.120396 0.2794)
			(end -0.12065 0.2794)
			(stroke
				(width 0.1)
				(type default)
			)
			(layer "F.Fab")
		)
		(fp_line
			(start -0.12065 0.3048)
			(end -0.67945 0.3048)
			(stroke
				(width 0.1)
				(type default)
			)
			(layer "F.Fab")
		)
		(fp_line
			(start -0.12065 0.2794)
			(end -0.12065 0.3048)
			(stroke
				(width 0.1)
				(type default)
			)
			(layer "F.Fab")
		)
		(fp_line
			(start -0.12065 -0.2794)
			(end 0.12065 -0.2794)
			(stroke
				(width 0.1)
				(type default)
			)
			(layer "F.Fab")
		)
		(fp_line
			(start -0.12065 -0.305054)
			(end -0.12065 -0.2794)
			(stroke
				(width 0.1)
				(type default)
			)
			(layer "F.Fab")
		)
		(fp_line
			(start -0.67945 0.3048)
			(end -0.67945 -0.305054)
			(stroke
				(width 0.1)
				(type default)
			)
			(layer "F.Fab")
		)
		(fp_line
			(start -0.67945 -0.305054)
			(end -0.12065 -0.305054)
			(stroke
				(width 0.1)
				(type default)
			)
			(layer "F.Fab")
		)
		(pad "1" smd circle
			(at -0.40005 0 180)
			(size 0 0)
			(layers "F.Cu" "F.Mask" "F.Paste")
			(net "PWRGD_P3V3_AUX_MB_BUF_N")
		)
		(pad "2" smd circle
			(at 0.40005 0 180)
			(size 0 0)
			(layers "F.Cu" "F.Mask" "F.Paste")
			(net "P3V3_AUX")
		)
	)
	(footprint ""
		(layer "F.Cu")
		(at 174.2694 -47.752)
		(property "Reference" "U23"
			(at -4.24307 1.16967 0)
			(unlocked yes)
			(layer "F.SilkS")
			(effects
				(font
					(size 0.7874 0.5842)
					(thickness 0.1524)
				)
				(justify left)
			)
		)
		(property "Value" ""
			(at 0 0 0)
			(layer "F.Fab")
			(effects
				(font
					(size 1.27 1.27)
				)
			)
		)
		(duplicate_pad_numbers_are_jumpers no)
		(fp_line
			(start -1.603248 -1.500124)
			(end 1.603248 -1.500124)
			(stroke
				(width 0.1524)
				(type default)
			)
			(layer "F.SilkS")
		)
		(fp_line
			(start -1.603248 1.500124)
			(end -1.603248 -1.500124)
			(stroke
				(width 0.1524)
				(type default)
			)
			(layer "F.SilkS")
		)
		(fp_line
			(start 1.603248 -1.500124)
			(end 1.603248 1.500124)
			(stroke
				(width 0.1524)
				(type default)
			)
			(layer "F.SilkS")
		)
		(fp_line
			(start 1.603248 1.500124)
			(end -1.603248 1.500124)
			(stroke
				(width 0.1524)
				(type default)
			)
			(layer "F.SilkS")
		)
		(fp_line
			(start -1.249934 -1.169924)
			(end -1.249934 -0.729996)
			(stroke
				(width 0.1)
				(type default)
			)
			(layer "F.Fab")
		)
		(fp_line
			(start -1.249934 -0.729996)
			(end -0.6985 -0.729996)
			(stroke
				(width 0.1)
				(type default)
			)
			(layer "F.Fab")
		)
		(fp_line
			(start -1.249934 0.729996)
			(end -1.249934 1.169924)
			(stroke
				(width 0.1)
				(type default)
			)
			(layer "F.Fab")
		)
		(fp_line
			(start -1.249934 1.169924)
			(end -0.700024 1.169924)
			(stroke
				(width 0.1)
				(type default)
			)
			(layer "F.Fab")
		)
		(fp_line
			(start -0.700024 -1.500124)
			(end -0.700024 -1.169924)
			(stroke
				(width 0.1)
				(type default)
			)
			(layer "F.Fab")
		)
		(fp_line
			(start -0.700024 -1.169924)
			(end -1.249934 -1.169924)
			(stroke
				(width 0.1)
				(type default)
			)
			(layer "F.Fab")
		)
		(fp_line
			(start -0.700024 1.169924)
			(end -0.700024 1.500124)
			(stroke
				(width 0.1)
				(type default)
			)
			(layer "F.Fab")
		)
		(fp_line
			(start -0.700024 1.500124)
			(end 0.700024 1.500124)
			(stroke
				(width 0.1)
				(type default)
			)
			(layer "F.Fab")
		)
		(fp_line
			(start -0.6985 -0.729996)
			(end -0.6985 0.729996)
			(stroke
				(width 0.1)
				(type default)
			)
			(layer "F.Fab")
		)
		(fp_line
			(start -0.6985 0.729996)
			(end -1.249934 0.729996)
			(stroke
				(width 0.1)
				(type default)
			)
			(layer "F.Fab")
		)
		(fp_line
			(start 0.700024 -1.500124)
			(end -0.700024 -1.500124)
			(stroke
				(width 0.1)
				(type default)
			)
			(layer "F.Fab")
		)
		(fp_line
			(start 0.700024 -0.219964)
			(end 0.700024 -1.500124)
			(stroke
				(width 0.1)
				(type default)
			)
			(layer "F.Fab")
		)
		(fp_line
			(start 0.700024 0.219964)
			(end 1.249934 0.219964)
			(stroke
				(width 0.1)
				(type default)
			)
			(layer "F.Fab")
		)
		(fp_line
			(start 0.700024 1.500124)
			(end 0.700024 0.219964)
			(stroke
				(width 0.1)
				(type default)
			)
			(layer "F.Fab")
		)
		(fp_line
			(start 1.249934 -0.219964)
			(end 0.700024 -0.219964)
			(stroke
				(width 0.1)
				(type default)
			)
			(layer "F.Fab")
		)
		(fp_line
			(start 1.249934 0.219964)
			(end 1.249934 -0.219964)
			(stroke
				(width 0.1)
				(type default)
			)
			(layer "F.Fab")
		)
		(fp_rect
			(start -0.700024 1.500124)
			(end 0.700024 -1.500124)
			(stroke
				(width 0)
				(type default)
			)
			(fill no)
			(layer "F.Fab")
		)
		(pad "D" smd rect
			(at 0.999998 0 270)
			(size 0.8128 0.9144)
			(layers "F.Cu" "F.Mask" "F.Paste")
			(net "GPU_HSC2_BUF_EN_N")
		)
		(pad "G" smd rect
			(at -0.999998 -0.94996 270)
			(size 0.8128 0.9144)
			(layers "F.Cu" "F.Mask" "F.Paste")
			(net "GPU_HSC_BUF_EN")
		)
		(pad "S" smd rect
			(at -0.999998 0.94996 270)
			(size 0.8128 0.9144)
			(layers "F.Cu" "F.Mask" "F.Paste")
			(net "GND")
		)
	)
	(footprint ""
		(layer "F.Cu")
		(at 323.13626 -63.373 180)
		(property "Reference" "PQ33"
			(at -9.628886 -3.917188 0)
			(unlocked yes)
			(layer "F.SilkS")
			(effects
				(font
					(size 0.7874 0.5842)
					(thickness 0.1524)
				)
				(justify left)
			)
		)
		(property "Value" ""
			(at 0 0 180)
			(layer "F.Fab")
			(effects
				(font
					(size 1.27 1.27)
				)
			)
		)
		(duplicate_pad_numbers_are_jumpers no)
		(fp_line
			(start 7.649972 4.99999)
			(end 7.649972 -4.99999)
			(stroke
				(width 0.1524)
				(type default)
			)
			(layer "F.SilkS")
		)
		(fp_line
			(start 7.649972 -4.99999)
			(end 7.630414 -4.99999)
			(stroke
				(width 0.1524)
				(type default)
			)
			(layer "F.SilkS")
		)
		(fp_line
			(start 7.630414 4.99999)
			(end 7.649972 4.99999)
			(stroke
				(width 0.1524)
				(type default)
			)
			(layer "F.SilkS")
		)
		(fp_line
			(start 5.115814 -4.99999)
			(end -7.649972 -4.99999)
			(stroke
				(width 0.1524)
				(type default)
			)
			(layer "F.SilkS")
		)
		(fp_line
			(start -7.649972 4.99999)
			(end 5.115814 4.99999)
			(stroke
				(width 0.1524)
				(type default)
			)
			(layer "F.SilkS")
		)
		(fp_line
			(start -7.649972 3.3274)
			(end -7.649972 4.99999)
			(stroke
				(width 0.1524)
				(type default)
			)
			(layer "F.SilkS")
		)
		(fp_line
			(start -7.649972 -1.7526)
			(end -7.649972 1.7526)
			(stroke
				(width 0.1524)
				(type default)
			)
			(layer "F.SilkS")
		)
		(fp_line
			(start -7.649972 -4.99999)
			(end -7.649972 -3.3274)
			(stroke
				(width 0.1524)
				(type default)
			)
			(layer "F.SilkS")
		)
		(fp_line
			(start 7.649972 4.99999)
			(end 7.649972 -4.99999)
			(stroke
				(width 0.1)
				(type default)
			)
			(layer "F.Fab")
		)
		(fp_line
			(start 7.649972 -4.99999)
			(end -7.649972 -4.99999)
			(stroke
				(width 0.1)
				(type default)
			)
			(layer "F.Fab")
		)
		(fp_line
			(start -7.649972 4.99999)
			(end 7.649972 4.99999)
			(stroke
				(width 0.1)
				(type default)
			)
			(layer "F.Fab")
		)
		(fp_line
			(start -7.649972 -4.99999)
			(end -7.649972 4.99999)
			(stroke
				(width 0.1)
				(type default)
			)
			(layer "F.Fab")
		)
		(pad "D" smd circle
			(at 2.15011 0 180)
			(size 0 0)
			(layers "F.Cu" "F.Mask" "F.Paste")
			(net "P52V_HS1_DRAIN_1")
		)
		(pad "G" smd rect
			(at -7.050024 -2.54 90)
			(size 1.3208 3.0988)
			(layers "F.Cu" "F.Mask" "F.Paste")
			(net "P52V_HS1_GATE2")
		)
		(pad "S" smd rect
			(at -7.050024 2.54 90)
			(size 1.3208 3.0988)
			(layers "F.Cu" "F.Mask" "F.Paste")
			(net "P52V_HS1")
		)
		(zone
			(layer "F.Cu")
			(hatch none 0.5)
			(connect_pads
				(clearance 0)
			)
			(min_thickness 0.25)
			(keepout
				(tracks not_allowed)
				(vias allowed)
				(pads allowed)
				(copperpour not_allowed)
				(footprints allowed)
			)
			(placement
				(enabled no)
				(sheetname "")
			)
			(fill
				(thermal_gap 0.5)
				(thermal_bridge_width 0.5)
				(island_removal_mode 0)
			)
			(polygon
				(pts
					(xy 317.95466 -58.3946) (xy 330.78166 -58.3946) (xy 330.78166 -60.1218) (xy 328.57186 -60.1218)
					(xy 328.57186 -61.5442) (xy 330.78166 -61.5442) (xy 330.78166 -65.2018) (xy 328.57186 -65.2018)
					(xy 328.57186 -66.6242) (xy 330.78166 -66.6242) (xy 330.78166 -68.3514) (xy 317.95466 -68.3514)
					(xy 317.95466 -67.183) (xy 324.15226 -67.183) (xy 324.15226 -59.563) (xy 317.95466 -59.563)
				)
			)
		)
	)
	(footprint ""
		(layer "F.Cu")
		(at 129.612136 -81.788)
		(property "Reference" "PR6995"
			(at 0 0 0)
			(layer "F.SilkS")
			(hide yes)
			(effects
				(font
					(size 1.27 1.27)
				)
			)
		)
		(property "Value" ""
			(at 0 0 0)
			(layer "F.Fab")
			(effects
				(font
					(size 1.27 1.27)
				)
			)
		)
		(duplicate_pad_numbers_are_jumpers no)
		(fp_line
			(start -0.7874 -0.4064)
			(end 0.7874 -0.4064)
			(stroke
				(width 0.1524)
				(type default)
			)
			(layer "F.SilkS")
		)
		(fp_line
			(start -0.7874 0.4064)
			(end -0.7874 -0.4064)
			(stroke
				(width 0.1524)
				(type default)
			)
			(layer "F.SilkS")
		)
		(fp_line
			(start 0.7874 -0.4064)
			(end 0.7874 0.4064)
			(stroke
				(width 0.1524)
				(type default)
			)
			(layer "F.SilkS")
		)
		(fp_line
			(start 0.7874 0.4064)
			(end -0.7874 0.4064)
			(stroke
				(width 0.1524)
				(type default)
			)
			(layer "F.SilkS")
		)
		(fp_line
			(start -0.67945 -0.305054)
			(end -0.12065 -0.305054)
			(stroke
				(width 0.1)
				(type default)
			)
			(layer "F.Fab")
		)
		(fp_line
			(start -0.67945 0.3048)
			(end -0.67945 -0.305054)
			(stroke
				(width 0.1)
				(type default)
			)
			(layer "F.Fab")
		)
		(fp_line
			(start -0.12065 -0.305054)
			(end -0.12065 -0.2794)
			(stroke
				(width 0.1)
				(type default)
			)
			(layer "F.Fab")
		)
		(fp_line
			(start -0.12065 -0.2794)
			(end 0.12065 -0.2794)
			(stroke
				(width 0.1)
				(type default)
			)
			(layer "F.Fab")
		)
		(fp_line
			(start -0.12065 0.2794)
			(end -0.12065 0.3048)
			(stroke
				(width 0.1)
				(type default)
			)
			(layer "F.Fab")
		)
		(fp_line
			(start -0.12065 0.3048)
			(end -0.67945 0.3048)
			(stroke
				(width 0.1)
				(type default)
			)
			(layer "F.Fab")
		)
		(fp_line
			(start 0.120396 0.2794)
			(end -0.12065 0.2794)
			(stroke
				(width 0.1)
				(type default)
			)
			(layer "F.Fab")
		)
		(fp_line
			(start 0.120396 0.3048)
			(end 0.120396 0.2794)
			(stroke
				(width 0.1)
				(type default)
			)
			(layer "F.Fab")
		)
		(fp_line
			(start 0.12065 -0.3048)
			(end 0.67945 -0.3048)
			(stroke
				(width 0.1)
				(type default)
			)
			(layer "F.Fab")
		)
		(fp_line
			(start 0.12065 -0.2794)
			(end 0.12065 -0.3048)
			(stroke
				(width 0.1)
				(type default)
			)
			(layer "F.Fab")
		)
		(fp_line
			(start 0.67945 -0.3048)
			(end 0.67945 0.3048)
			(stroke
				(width 0.1)
				(type default)
			)
			(layer "F.Fab")
		)
		(fp_line
			(start 0.67945 0.3048)
			(end 0.120396 0.3048)
			(stroke
				(width 0.1)
				(type default)
			)
			(layer "F.Fab")
		)
		(pad "1" smd rect
			(at -0.40005 0 180)
			(size 0.4572 0.508)
			(layers "F.Cu" "F.Mask" "F.Paste")
			(net "P52V_HS2_TEMPP")
		)
		(pad "2" smd rect
			(at 0.40005 0 180)
			(size 0.4572 0.508)
			(layers "F.Cu" "F.Mask" "F.Paste")
			(net "P52V_HS2_TEMP_R")
		)
	)
	(footprint ""
		(layer "F.Cu")
		(at 445.741806 -92.843858 180)
		(property "Reference" "PC617"
			(at 0 0 180)
			(layer "F.SilkS")
			(hide yes)
			(effects
				(font
					(size 1.27 1.27)
				)
			)
		)
		(property "Value" ""
			(at 0 0 180)
			(layer "F.Fab")
			(effects
				(font
					(size 1.27 1.27)
				)
			)
		)
		(duplicate_pad_numbers_are_jumpers no)
		(fp_line
			(start 1.524 0.762)
			(end -1.524 0.762)
			(stroke
				(width 0.1524)
				(type default)
			)
			(layer "F.SilkS")
		)
		(fp_line
			(start 1.524 -0.762)
			(end 1.524 0.762)
			(stroke
				(width 0.1524)
				(type default)
			)
			(layer "F.SilkS")
		)
		(fp_line
			(start -1.524 0.762)
			(end -1.524 -0.762)
			(stroke
				(width 0.1524)
				(type default)
			)
			(layer "F.SilkS")
		)
		(fp_line
			(start -1.524 -0.762)
			(end 1.524 -0.762)
			(stroke
				(width 0.1524)
				(type default)
			)
			(layer "F.SilkS")
		)
		(fp_line
			(start 1.1049 0.724916)
			(end 1.1049 -0.724916)
			(stroke
				(width 0.1)
				(type default)
			)
			(layer "F.Fab")
		)
		(fp_line
			(start 1.1049 -0.724916)
			(end -1.1049 -0.724916)
			(stroke
				(width 0.1)
				(type default)
			)
			(layer "F.Fab")
		)
		(fp_line
			(start -1.1049 0.724916)
			(end 1.1049 0.724916)
			(stroke
				(width 0.1)
				(type default)
			)
			(layer "F.Fab")
		)
		(fp_line
			(start -1.1049 -0.724916)
			(end -1.1049 0.724916)
			(stroke
				(width 0.1)
				(type default)
			)
			(layer "F.Fab")
		)
		(pad "1" smd rect
			(at -0.889 0)
			(size 1.016 1.27)
			(layers "F.Cu" "F.Mask" "F.Paste")
			(net "SW_P3V3_HPDB_FLT")
		)
		(pad "2" smd rect
			(at 0.889 0)
			(size 1.016 1.27)
			(layers "F.Cu" "F.Mask" "F.Paste")
			(net "GND")
		)
	)
	(footprint ""
		(layer "F.Cu")
		(at 427.228 -41.783)
		(property "Reference" "R101"
			(at 0 0 0)
			(layer "F.SilkS")
			(hide yes)
			(effects
				(font
					(size 1.27 1.27)
				)
			)
		)
		(property "Value" ""
			(at 0 0 0)
			(layer "F.Fab")
			(effects
				(font
					(size 1.27 1.27)
				)
			)
		)
		(duplicate_pad_numbers_are_jumpers no)
		(fp_line
			(start -0.7874 -0.4064)
			(end 0.7874 -0.4064)
			(stroke
				(width 0.1524)
				(type default)
			)
			(layer "F.SilkS")
		)
		(fp_line
			(start -0.7874 0.4064)
			(end -0.7874 -0.4064)
			(stroke
				(width 0.1524)
				(type default)
			)
			(layer "F.SilkS")
		)
		(fp_line
			(start 0.7874 -0.4064)
			(end 0.7874 0.4064)
			(stroke
				(width 0.1524)
				(type default)
			)
			(layer "F.SilkS")
		)
		(fp_line
			(start 0.7874 0.4064)
			(end -0.7874 0.4064)
			(stroke
				(width 0.1524)
				(type default)
			)
			(layer "F.SilkS")
		)
		(fp_line
			(start -0.67945 -0.305054)
			(end -0.12065 -0.305054)
			(stroke
				(width 0.1)
				(type default)
			)
			(layer "F.Fab")
		)
		(fp_line
			(start -0.67945 0.3048)
			(end -0.67945 -0.305054)
			(stroke
				(width 0.1)
				(type default)
			)
			(layer "F.Fab")
		)
		(fp_line
			(start -0.12065 -0.305054)
			(end -0.12065 -0.2794)
			(stroke
				(width 0.1)
				(type default)
			)
			(layer "F.Fab")
		)
		(fp_line
			(start -0.12065 -0.2794)
			(end 0.12065 -0.2794)
			(stroke
				(width 0.1)
				(type default)
			)
			(layer "F.Fab")
		)
		(fp_line
			(start -0.12065 0.2794)
			(end -0.12065 0.3048)
			(stroke
				(width 0.1)
				(type default)
			)
			(layer "F.Fab")
		)
		(fp_line
			(start -0.12065 0.3048)
			(end -0.67945 0.3048)
			(stroke
				(width 0.1)
				(type default)
			)
			(layer "F.Fab")
		)
		(fp_line
			(start 0.120396 0.2794)
			(end -0.12065 0.2794)
			(stroke
				(width 0.1)
				(type default)
			)
			(layer "F.Fab")
		)
		(fp_line
			(start 0.120396 0.3048)
			(end 0.120396 0.2794)
			(stroke
				(width 0.1)
				(type default)
			)
			(layer "F.Fab")
		)
		(fp_line
			(start 0.12065 -0.3048)
			(end 0.67945 -0.3048)
			(stroke
				(width 0.1)
				(type default)
			)
			(layer "F.Fab")
		)
		(fp_line
			(start 0.12065 -0.2794)
			(end 0.12065 -0.3048)
			(stroke
				(width 0.1)
				(type default)
			)
			(layer "F.Fab")
		)
		(fp_line
			(start 0.67945 -0.3048)
			(end 0.67945 0.3048)
			(stroke
				(width 0.1)
				(type default)
			)
			(layer "F.Fab")
		)
		(fp_line
			(start 0.67945 0.3048)
			(end 0.120396 0.3048)
			(stroke
				(width 0.1)
				(type default)
			)
			(layer "F.Fab")
		)
		(pad "1" smd circle
			(at -0.40005 0)
			(size 0 0)
			(layers "F.Cu" "F.Mask" "F.Paste")
			(net "SKU_ID_0")
		)
		(pad "2" smd circle
			(at 0.40005 0)
			(size 0 0)
			(layers "F.Cu" "F.Mask" "F.Paste")
			(net "GND")
		)
	)
	(footprint ""
		(layer "F.Cu")
		(at 11.999976 -4.499864 180)
		(property "Reference" "H2"
			(at 0.696976 10.713466 0)
			(unlocked yes)
			(layer "F.SilkS")
			(effects
				(font
					(size 0.7874 0.5842)
					(thickness 0.1524)
				)
				(justify left)
			)
		)
		(property "Value" ""
			(at 0 0 180)
			(layer "F.Fab")
			(effects
				(font
					(size 1.27 1.27)
				)
			)
		)
		(duplicate_pad_numbers_are_jumpers no)
		(pad "1" thru_hole oval
			(at 0 0 180)
			(size 9.017 14.0208)
			(drill 3.0226
				(offset 0 2.499868)
			)
			(layers "*.Cu" "*.Mask")
			(remove_unused_layers no)
			(net "GND")
			(clearance -1.500378)
			(padstack
				(mode front_inner_back)
				(layer "Inner"
					(shape circle)
					(size 0 0)
					(clearance 0)
				)
				(layer "B.Cu"
					(shape oval)
					(size 9.017 14.0208)
					(offset 0 2.499868)
					(clearance -1.500378)
				)
			)
		)
	)
	(footprint ""
		(layer "F.Cu")
		(at 447.00952 -73.62698 -90)
		(property "Reference" "PL2"
			(at -4.85902 -7.32155 90)
			(unlocked yes)
			(layer "F.SilkS")
			(effects
				(font
					(size 0.7874 0.5842)
					(thickness 0.1524)
				)
				(justify left)
			)
		)
		(property "Value" ""
			(at 0 0 270)
			(layer "F.Fab")
			(effects
				(font
					(size 1.27 1.27)
				)
			)
		)
		(duplicate_pad_numbers_are_jumpers no)
		(fp_line
			(start -6.999986 6.400038)
			(end -6.999986 1.8923)
			(stroke
				(width 0.1524)
				(type default)
			)
			(layer "F.SilkS")
		)
		(fp_line
			(start 6.999986 6.400038)
			(end -6.999986 6.400038)
			(stroke
				(width 0.1524)
				(type default)
			)
			(layer "F.SilkS")
		)
		(fp_line
			(start 6.999986 1.8923)
			(end 6.999986 6.400038)
			(stroke
				(width 0.1524)
				(type default)
			)
			(layer "F.SilkS")
		)
		(fp_line
			(start -6.999986 -1.8923)
			(end -6.999986 -6.400038)
			(stroke
				(width 0.1524)
				(type default)
			)
			(layer "F.SilkS")
		)
		(fp_line
			(start -6.999986 -6.400038)
			(end 6.999986 -6.400038)
			(stroke
				(width 0.1524)
				(type default)
			)
			(layer "F.SilkS")
		)
		(fp_line
			(start 6.999986 -6.400038)
			(end 6.999986 -1.8923)
			(stroke
				(width 0.1524)
				(type default)
			)
			(layer "F.SilkS")
		)
		(fp_line
			(start -6.999986 6.400038)
			(end 6.999986 6.400038)
			(stroke
				(width 0.1)
				(type default)
			)
			(layer "F.Fab")
		)
		(fp_line
			(start 6.999986 6.400038)
			(end 6.999986 -6.400038)
			(stroke
				(width 0.1)
				(type default)
			)
			(layer "F.Fab")
		)
		(fp_line
			(start -6.999986 2.5146)
			(end -6.999986 6.400038)
			(stroke
				(width 0.1)
				(type default)
			)
			(layer "F.Fab")
		)
		(fp_line
			(start -6.999986 -6.400038)
			(end -6.999986 2.5146)
			(stroke
				(width 0.1)
				(type default)
			)
			(layer "F.Fab")
		)
		(fp_line
			(start 6.999986 -6.400038)
			(end -6.999986 -6.400038)
			(stroke
				(width 0.1)
				(type default)
			)
			(layer "F.Fab")
		)
		(pad "1" smd rect
			(at -5.625084 0 270)
			(size 3.2512 3.5052)
			(layers "F.Cu" "F.Mask" "F.Paste")
			(net "SW_P3V3_HPDB_PH")
		)
		(pad "2" smd rect
			(at 5.625084 0 270)
			(size 3.2512 3.5052)
			(layers "F.Cu" "F.Mask" "F.Paste")
			(net "P3V3_AUX")
		)
	)
	(footprint ""
		(layer "F.Cu")
		(at 94.6404 -34.417)
		(property "Reference" "ME5"
			(at 0 0 0)
			(layer "F.SilkS")
			(hide yes)
			(effects
				(font
					(size 1.27 1.27)
				)
			)
		)
		(property "Value" ""
			(at 0 0 0)
			(layer "F.Fab")
			(effects
				(font
					(size 1.27 1.27)
				)
			)
		)
		(duplicate_pad_numbers_are_jumpers no)
	)
	(footprint ""
		(layer "F.Cu")
		(at 52.832 -26.543 -90)
		(property "Reference" "PR103"
			(at 0 0 270)
			(layer "F.SilkS")
			(hide yes)
			(effects
				(font
					(size 1.27 1.27)
				)
			)
		)
		(property "Value" ""
			(at 0 0 270)
			(layer "F.Fab")
			(effects
				(font
					(size 1.27 1.27)
				)
			)
		)
		(duplicate_pad_numbers_are_jumpers no)
		(fp_line
			(start -0.7874 0.4064)
			(end -0.7874 -0.4064)
			(stroke
				(width 0.1524)
				(type default)
			)
			(layer "F.SilkS")
		)
		(fp_line
			(start 0.7874 0.4064)
			(end -0.7874 0.4064)
			(stroke
				(width 0.1524)
				(type default)
			)
			(layer "F.SilkS")
		)
		(fp_line
			(start -0.7874 -0.4064)
			(end 0.7874 -0.4064)
			(stroke
				(width 0.1524)
				(type default)
			)
			(layer "F.SilkS")
		)
		(fp_line
			(start 0.7874 -0.4064)
			(end 0.7874 0.4064)
			(stroke
				(width 0.1524)
				(type default)
			)
			(layer "F.SilkS")
		)
		(fp_line
			(start -0.67945 0.3048)
			(end -0.67945 -0.305054)
			(stroke
				(width 0.1)
				(type default)
			)
			(layer "F.Fab")
		)
		(fp_line
			(start -0.12065 0.3048)
			(end -0.67945 0.3048)
			(stroke
				(width 0.1)
				(type default)
			)
			(layer "F.Fab")
		)
		(fp_line
			(start 0.120396 0.3048)
			(end 0.120396 0.2794)
			(stroke
				(width 0.1)
				(type default)
			)
			(layer "F.Fab")
		)
		(fp_line
			(start 0.67945 0.3048)
			(end 0.120396 0.3048)
			(stroke
				(width 0.1)
				(type default)
			)
			(layer "F.Fab")
		)
		(fp_line
			(start -0.12065 0.2794)
			(end -0.12065 0.3048)
			(stroke
				(width 0.1)
				(type default)
			)
			(layer "F.Fab")
		)
		(fp_line
			(start 0.120396 0.2794)
			(end -0.12065 0.2794)
			(stroke
				(width 0.1)
				(type default)
			)
			(layer "F.Fab")
		)
		(fp_line
			(start -0.12065 -0.2794)
			(end 0.12065 -0.2794)
			(stroke
				(width 0.1)
				(type default)
			)
			(layer "F.Fab")
		)
		(fp_line
			(start 0.12065 -0.2794)
			(end 0.12065 -0.3048)
			(stroke
				(width 0.1)
				(type default)
			)
			(layer "F.Fab")
		)
		(fp_line
			(start 0.12065 -0.3048)
			(end 0.67945 -0.3048)
			(stroke
				(width 0.1)
				(type default)
			)
			(layer "F.Fab")
		)
		(fp_line
			(start 0.67945 -0.3048)
			(end 0.67945 0.3048)
			(stroke
				(width 0.1)
				(type default)
			)
			(layer "F.Fab")
		)
		(fp_line
			(start -0.67945 -0.305054)
			(end -0.12065 -0.305054)
			(stroke
				(width 0.1)
				(type default)
			)
			(layer "F.Fab")
		)
		(fp_line
			(start -0.12065 -0.305054)
			(end -0.12065 -0.2794)
			(stroke
				(width 0.1)
				(type default)
			)
			(layer "F.Fab")
		)
		(pad "1" smd circle
			(at -0.40005 0 270)
			(size 0 0)
			(layers "F.Cu" "F.Mask" "F.Paste")
			(net "P52V_HS2_EN")
		)
		(pad "2" smd circle
			(at 0.40005 0 270)
			(size 0 0)
			(layers "F.Cu" "F.Mask" "F.Paste")
			(net "P52V_HS2_EN_DISCHARGE")
		)
	)
	(footprint ""
		(layer "F.Cu")
		(at 306.7304 -69.977)
		(property "Reference" "PR6958"
			(at 0 0 0)
			(layer "F.SilkS")
			(hide yes)
			(effects
				(font
					(size 1.27 1.27)
				)
			)
		)
		(property "Value" ""
			(at 0 0 0)
			(layer "F.Fab")
			(effects
				(font
					(size 1.27 1.27)
				)
			)
		)
		(duplicate_pad_numbers_are_jumpers no)
		(fp_line
			(start -1.2954 -0.5842)
			(end 1.2954 -0.5842)
			(stroke
				(width 0.1524)
				(type default)
			)
			(layer "F.SilkS")
		)
		(fp_line
			(start -1.2954 0.5842)
			(end -1.2954 -0.5842)
			(stroke
				(width 0.1524)
				(type default)
			)
			(layer "F.SilkS")
		)
		(fp_line
			(start 1.2954 -0.5842)
			(end 1.2954 0.5842)
			(stroke
				(width 0.1524)
				(type default)
			)
			(layer "F.SilkS")
		)
		(fp_line
			(start 1.2954 0.5842)
			(end -1.2954 0.5842)
			(stroke
				(width 0.1524)
				(type default)
			)
			(layer "F.SilkS")
		)
		(fp_line
			(start -1.1938 -0.406654)
			(end -0.8636 -0.406654)
			(stroke
				(width 0.1)
				(type default)
			)
			(layer "F.Fab")
		)
		(fp_line
			(start -1.1938 0.4064)
			(end -1.1938 -0.406654)
			(stroke
				(width 0.1)
				(type default)
			)
			(layer "F.Fab")
		)
		(fp_line
			(start -0.8636 -0.4572)
			(end 0.8636 -0.4572)
			(stroke
				(width 0.1)
				(type default)
			)
			(layer "F.Fab")
		)
		(fp_line
			(start -0.8636 -0.406654)
			(end -0.8636 -0.4572)
			(stroke
				(width 0.1)
				(type default)
			)
			(layer "F.Fab")
		)
		(fp_line
			(start -0.8636 0.4064)
			(end -1.1938 0.4064)
			(stroke
				(width 0.1)
				(type default)
			)
			(layer "F.Fab")
		)
		(fp_line
			(start -0.8636 0.4318)
			(end -0.8636 0.4064)
			(stroke
				(width 0.1)
				(type default)
			)
			(layer "F.Fab")
		)
		(fp_line
			(start -0.8636 0.4572)
			(end -0.8636 0.4318)
			(stroke
				(width 0.1)
				(type default)
			)
			(layer "F.Fab")
		)
		(fp_line
			(start 0.8636 -0.4572)
			(end 0.8636 -0.406654)
			(stroke
				(width 0.1)
				(type default)
			)
			(layer "F.Fab")
		)
		(fp_line
			(start 0.8636 -0.406654)
			(end 1.1938 -0.406654)
			(stroke
				(width 0.1)
				(type default)
			)
			(layer "F.Fab")
		)
		(fp_line
			(start 0.8636 0.4064)
			(end 0.8636 0.4572)
			(stroke
				(width 0.1)
				(type default)
			)
			(layer "F.Fab")
		)
		(fp_line
			(start 0.8636 0.4572)
			(end -0.8636 0.4572)
			(stroke
				(width 0.1)
				(type default)
			)
			(layer "F.Fab")
		)
		(fp_line
			(start 1.1938 -0.406654)
			(end 1.1938 0.4064)
			(stroke
				(width 0.1)
				(type default)
			)
			(layer "F.Fab")
		)
		(fp_line
			(start 1.1938 0.4064)
			(end 0.8636 0.4064)
			(stroke
				(width 0.1)
				(type default)
			)
			(layer "F.Fab")
		)
		(pad "1" smd rect
			(at -0.7366 0 270)
			(size 0.7112 0.8128)
			(layers "F.Cu" "F.Mask" "F.Paste")
			(net "P52V_HS_1272_S_N")
		)
		(pad "2" smd rect
			(at 0.7366 0 270)
			(size 0.7112 0.8128)
			(layers "F.Cu" "F.Mask" "F.Paste")
			(net "P52V_HS1_SENSE_N_R1")
		)
	)
	(footprint ""
		(layer "F.Cu")
		(at 166.543736 -65.024 180)
		(property "Reference" "PR7036"
			(at 0 0 180)
			(layer "F.SilkS")
			(hide yes)
			(effects
				(font
					(size 1.27 1.27)
				)
			)
		)
		(property "Value" ""
			(at 0 0 180)
			(layer "F.Fab")
			(effects
				(font
					(size 1.27 1.27)
				)
			)
		)
		(duplicate_pad_numbers_are_jumpers no)
		(fp_line
			(start 0.7874 0.4064)
			(end -0.7874 0.4064)
			(stroke
				(width 0.1524)
				(type default)
			)
			(layer "F.SilkS")
		)
		(fp_line
			(start 0.7874 -0.4064)
			(end 0.7874 0.4064)
			(stroke
				(width 0.1524)
				(type default)
			)
			(layer "F.SilkS")
		)
		(fp_line
			(start -0.7874 0.4064)
			(end -0.7874 -0.4064)
			(stroke
				(width 0.1524)
				(type default)
			)
			(layer "F.SilkS")
		)
		(fp_line
			(start -0.7874 -0.4064)
			(end 0.7874 -0.4064)
			(stroke
				(width 0.1524)
				(type default)
			)
			(layer "F.SilkS")
		)
		(fp_line
			(start 0.67945 0.3048)
			(end 0.120396 0.3048)
			(stroke
				(width 0.1)
				(type default)
			)
			(layer "F.Fab")
		)
		(fp_line
			(start 0.67945 -0.3048)
			(end 0.67945 0.3048)
			(stroke
				(width 0.1)
				(type default)
			)
			(layer "F.Fab")
		)
		(fp_line
			(start 0.12065 -0.2794)
			(end 0.12065 -0.3048)
			(stroke
				(width 0.1)
				(type default)
			)
			(layer "F.Fab")
		)
		(fp_line
			(start 0.12065 -0.3048)
			(end 0.67945 -0.3048)
			(stroke
				(width 0.1)
				(type default)
			)
			(layer "F.Fab")
		)
		(fp_line
			(start 0.120396 0.3048)
			(end 0.120396 0.2794)
			(stroke
				(width 0.1)
				(type default)
			)
			(layer "F.Fab")
		)
		(fp_line
			(start 0.120396 0.2794)
			(end -0.12065 0.2794)
			(stroke
				(width 0.1)
				(type default)
			)
			(layer "F.Fab")
		)
		(fp_line
			(start -0.12065 0.3048)
			(end -0.67945 0.3048)
			(stroke
				(width 0.1)
				(type default)
			)
			(layer "F.Fab")
		)
		(fp_line
			(start -0.12065 0.2794)
			(end -0.12065 0.3048)
			(stroke
				(width 0.1)
				(type default)
			)
			(layer "F.Fab")
		)
		(fp_line
			(start -0.12065 -0.2794)
			(end 0.12065 -0.2794)
			(stroke
				(width 0.1)
				(type default)
			)
			(layer "F.Fab")
		)
		(fp_line
			(start -0.12065 -0.305054)
			(end -0.12065 -0.2794)
			(stroke
				(width 0.1)
				(type default)
			)
			(layer "F.Fab")
		)
		(fp_line
			(start -0.67945 0.3048)
			(end -0.67945 -0.305054)
			(stroke
				(width 0.1)
				(type default)
			)
			(layer "F.Fab")
		)
		(fp_line
			(start -0.67945 -0.305054)
			(end -0.12065 -0.305054)
			(stroke
				(width 0.1)
				(type default)
			)
			(layer "F.Fab")
		)
		(pad "1" smd circle
			(at -0.40005 0 180)
			(size 0 0)
			(layers "F.Cu" "F.Mask" "F.Paste")
			(net "P52V_HS2_EFAULT")
		)
		(pad "2" smd circle
			(at 0.40005 0 180)
			(size 0 0)
			(layers "F.Cu" "F.Mask" "F.Paste")
			(net "GND1_FIELD_SIGNAL")
		)
	)
	(footprint ""
		(layer "F.Cu")
		(at 413.512 -45.212 180)
		(property "Reference" "R55"
			(at 0 0 180)
			(layer "F.SilkS")
			(hide yes)
			(effects
				(font
					(size 1.27 1.27)
				)
			)
		)
		(property "Value" ""
			(at 0 0 180)
			(layer "F.Fab")
			(effects
				(font
					(size 1.27 1.27)
				)
			)
		)
		(duplicate_pad_numbers_are_jumpers no)
		(fp_line
			(start 0.7874 0.4064)
			(end -0.7874 0.4064)
			(stroke
				(width 0.1524)
				(type default)
			)
			(layer "F.SilkS")
		)
		(fp_line
			(start 0.7874 -0.4064)
			(end 0.7874 0.4064)
			(stroke
				(width 0.1524)
				(type default)
			)
			(layer "F.SilkS")
		)
		(fp_line
			(start -0.7874 0.4064)
			(end -0.7874 -0.4064)
			(stroke
				(width 0.1524)
				(type default)
			)
			(layer "F.SilkS")
		)
		(fp_line
			(start -0.7874 -0.4064)
			(end 0.7874 -0.4064)
			(stroke
				(width 0.1524)
				(type default)
			)
			(layer "F.SilkS")
		)
		(fp_line
			(start 0.67945 0.3048)
			(end 0.120396 0.3048)
			(stroke
				(width 0.1)
				(type default)
			)
			(layer "F.Fab")
		)
		(fp_line
			(start 0.67945 -0.3048)
			(end 0.67945 0.3048)
			(stroke
				(width 0.1)
				(type default)
			)
			(layer "F.Fab")
		)
		(fp_line
			(start 0.12065 -0.2794)
			(end 0.12065 -0.3048)
			(stroke
				(width 0.1)
				(type default)
			)
			(layer "F.Fab")
		)
		(fp_line
			(start 0.12065 -0.3048)
			(end 0.67945 -0.3048)
			(stroke
				(width 0.1)
				(type default)
			)
			(layer "F.Fab")
		)
		(fp_line
			(start 0.120396 0.3048)
			(end 0.120396 0.2794)
			(stroke
				(width 0.1)
				(type default)
			)
			(layer "F.Fab")
		)
		(fp_line
			(start 0.120396 0.2794)
			(end -0.12065 0.2794)
			(stroke
				(width 0.1)
				(type default)
			)
			(layer "F.Fab")
		)
		(fp_line
			(start -0.12065 0.3048)
			(end -0.67945 0.3048)
			(stroke
				(width 0.1)
				(type default)
			)
			(layer "F.Fab")
		)
		(fp_line
			(start -0.12065 0.2794)
			(end -0.12065 0.3048)
			(stroke
				(width 0.1)
				(type default)
			)
			(layer "F.Fab")
		)
		(fp_line
			(start -0.12065 -0.2794)
			(end 0.12065 -0.2794)
			(stroke
				(width 0.1)
				(type default)
			)
			(layer "F.Fab")
		)
		(fp_line
			(start -0.12065 -0.305054)
			(end -0.12065 -0.2794)
			(stroke
				(width 0.1)
				(type default)
			)
			(layer "F.Fab")
		)
		(fp_line
			(start -0.67945 0.3048)
			(end -0.67945 -0.305054)
			(stroke
				(width 0.1)
				(type default)
			)
			(layer "F.Fab")
		)
		(fp_line
			(start -0.67945 -0.305054)
			(end -0.12065 -0.305054)
			(stroke
				(width 0.1)
				(type default)
			)
			(layer "F.Fab")
		)
		(pad "1" smd circle
			(at -0.40005 0 180)
			(size 0 0)
			(layers "F.Cu" "F.Mask" "F.Paste")
			(net "PCA9555_A1")
		)
		(pad "2" smd circle
			(at 0.40005 0 180)
			(size 0 0)
			(layers "F.Cu" "F.Mask" "F.Paste")
			(net "GND")
		)
	)
	(footprint ""
		(layer "F.Cu")
		(at 153.162 -76.2 180)
		(property "Reference" "PC599"
			(at 0 0 180)
			(layer "F.SilkS")
			(hide yes)
			(effects
				(font
					(size 1.27 1.27)
				)
			)
		)
		(property "Value" ""
			(at 0 0 180)
			(layer "F.Fab")
			(effects
				(font
					(size 1.27 1.27)
				)
			)
		)
		(duplicate_pad_numbers_are_jumpers no)
		(fp_line
			(start 0.7874 0.4064)
			(end -0.7874 0.4064)
			(stroke
				(width 0.1524)
				(type default)
			)
			(layer "F.SilkS")
		)
		(fp_line
			(start 0.7874 -0.4064)
			(end 0.7874 0.4064)
			(stroke
				(width 0.1524)
				(type default)
			)
			(layer "F.SilkS")
		)
		(fp_line
			(start -0.7874 0.4064)
			(end -0.7874 -0.4064)
			(stroke
				(width 0.1524)
				(type default)
			)
			(layer "F.SilkS")
		)
		(fp_line
			(start -0.7874 -0.4064)
			(end 0.7874 -0.4064)
			(stroke
				(width 0.1524)
				(type default)
			)
			(layer "F.SilkS")
		)
		(fp_line
			(start 0.67945 0.3048)
			(end 0.120396 0.3048)
			(stroke
				(width 0.1)
				(type default)
			)
			(layer "F.Fab")
		)
		(fp_line
			(start 0.67945 -0.3048)
			(end 0.67945 0.3048)
			(stroke
				(width 0.1)
				(type default)
			)
			(layer "F.Fab")
		)
		(fp_line
			(start 0.12065 -0.2794)
			(end 0.12065 -0.3048)
			(stroke
				(width 0.1)
				(type default)
			)
			(layer "F.Fab")
		)
		(fp_line
			(start 0.12065 -0.3048)
			(end 0.67945 -0.3048)
			(stroke
				(width 0.1)
				(type default)
			)
			(layer "F.Fab")
		)
		(fp_line
			(start 0.120396 0.3048)
			(end 0.120396 0.2794)
			(stroke
				(width 0.1)
				(type default)
			)
			(layer "F.Fab")
		)
		(fp_line
			(start 0.120396 0.2794)
			(end -0.12065 0.2794)
			(stroke
				(width 0.1)
				(type default)
			)
			(layer "F.Fab")
		)
		(fp_line
			(start -0.12065 0.3048)
			(end -0.67945 0.3048)
			(stroke
				(width 0.1)
				(type default)
			)
			(layer "F.Fab")
		)
		(fp_line
			(start -0.12065 0.2794)
			(end -0.12065 0.3048)
			(stroke
				(width 0.1)
				(type default)
			)
			(layer "F.Fab")
		)
		(fp_line
			(start -0.12065 -0.2794)
			(end 0.12065 -0.2794)
			(stroke
				(width 0.1)
				(type default)
			)
			(layer "F.Fab")
		)
		(fp_line
			(start -0.12065 -0.305054)
			(end -0.12065 -0.2794)
			(stroke
				(width 0.1)
				(type default)
			)
			(layer "F.Fab")
		)
		(fp_line
			(start -0.67945 0.3048)
			(end -0.67945 -0.305054)
			(stroke
				(width 0.1)
				(type default)
			)
			(layer "F.Fab")
		)
		(fp_line
			(start -0.67945 -0.305054)
			(end -0.12065 -0.305054)
			(stroke
				(width 0.1)
				(type default)
			)
			(layer "F.Fab")
		)
		(pad "1" smd circle
			(at -0.40005 0 180)
			(size 0 0)
			(layers "F.Cu" "F.Mask" "F.Paste")
			(net "P52V_HS2_INTVCC")
		)
		(pad "2" smd circle
			(at 0.40005 0 180)
			(size 0 0)
			(layers "F.Cu" "F.Mask" "F.Paste")
			(net "GND")
		)
	)
	(footprint ""
		(layer "F.Cu")
		(at 442.595 -45.085)
		(property "Reference" "U21"
			(at 2.69367 0.381 90)
			(unlocked yes)
			(layer "F.SilkS")
			(effects
				(font
					(size 0.7874 0.5842)
					(thickness 0.1524)
				)
				(justify left)
			)
		)
		(property "Value" ""
			(at 0 0 0)
			(layer "F.Fab")
			(effects
				(font
					(size 1.27 1.27)
				)
			)
		)
		(duplicate_pad_numbers_are_jumpers no)
		(fp_line
			(start -2.032 -1.549908)
			(end 2.032 -1.549908)
			(stroke
				(width 0.1524)
				(type default)
			)
			(layer "F.SilkS")
		)
		(fp_line
			(start -2.032 1.549908)
			(end -2.032 -1.549908)
			(stroke
				(width 0.1524)
				(type default)
			)
			(layer "F.SilkS")
		)
		(fp_line
			(start 2.032 -1.549908)
			(end 2.032 1.549908)
			(stroke
				(width 0.1524)
				(type default)
			)
			(layer "F.SilkS")
		)
		(fp_line
			(start 2.032 1.549908)
			(end -2.032 1.549908)
			(stroke
				(width 0.1524)
				(type default)
			)
			(layer "F.SilkS")
		)
		(fp_poly
			(pts
				(xy -2.9718 -1.1176) (xy -2.9718 -0.6096) (xy -2.2098 -0.8636)
			)
			(stroke
				(width 0)
				(type default)
			)
			(fill yes)
			(layer "F.SilkS")
		)
		(fp_line
			(start -0.849884 -1.549908)
			(end -0.849884 1.549908)
			(stroke
				(width 0.1)
				(type default)
			)
			(layer "F.Fab")
		)
		(fp_line
			(start -0.849884 1.549908)
			(end 0.849884 1.549908)
			(stroke
				(width 0.1)
				(type default)
			)
			(layer "F.Fab")
		)
		(fp_line
			(start 0.849884 -1.549908)
			(end -0.849884 -1.549908)
			(stroke
				(width 0.1)
				(type default)
			)
			(layer "F.Fab")
		)
		(fp_line
			(start 0.849884 1.549908)
			(end 0.849884 -1.549908)
			(stroke
				(width 0.1)
				(type default)
			)
			(layer "F.Fab")
		)
		(fp_poly
			(pts
				(xy -2.9464 -1.2192) (xy -2.9464 -0.7112) (xy -2.1844 -0.9652)
			)
			(stroke
				(width 0)
				(type default)
			)
			(fill yes)
			(layer "F.Fab")
		)
		(pad "1" smd rect
			(at -1.225042 -0.94996 270)
			(size 0.4572 1.3208)
			(layers "F.Cu" "F.Mask" "F.Paste")
			(net "PWRGD_P3V3_AUX_MB_BUF_N")
		)
		(pad "2" smd rect
			(at -1.225042 0 270)
			(size 0.4572 1.3208)
			(layers "F.Cu" "F.Mask" "F.Paste")
			(net "GPU_HSC_EN")
		)
		(pad "3" smd rect
			(at -1.225042 0.94996 270)
			(size 0.4572 1.3208)
			(layers "F.Cu" "F.Mask" "F.Paste")
			(net "GND")
		)
		(pad "4" smd rect
			(at 1.225042 0.94996 270)
			(size 0.4572 1.3208)
			(layers "F.Cu" "F.Mask" "F.Paste")
			(net "GPU_HSC_BUF_R_EN")
		)
		(pad "5" smd rect
			(at 1.225042 -0.94996 270)
			(size 0.4572 1.3208)
			(layers "F.Cu" "F.Mask" "F.Paste")
			(net "P3V3_AUX")
		)
	)
	(footprint ""
		(layer "F.Cu")
		(at 448.437 -42.799)
		(property "Reference" "C1"
			(at 0 0 0)
			(layer "F.SilkS")
			(hide yes)
			(effects
				(font
					(size 1.27 1.27)
				)
			)
		)
		(property "Value" ""
			(at 0 0 0)
			(layer "F.Fab")
			(effects
				(font
					(size 1.27 1.27)
				)
			)
		)
		(duplicate_pad_numbers_are_jumpers no)
		(fp_line
			(start -0.7874 -0.4064)
			(end 0.7874 -0.4064)
			(stroke
				(width 0.1524)
				(type default)
			)
			(layer "F.SilkS")
		)
		(fp_line
			(start -0.7874 0.4064)
			(end -0.7874 -0.4064)
			(stroke
				(width 0.1524)
				(type default)
			)
			(layer "F.SilkS")
		)
		(fp_line
			(start 0.7874 -0.4064)
			(end 0.7874 0.4064)
			(stroke
				(width 0.1524)
				(type default)
			)
			(layer "F.SilkS")
		)
		(fp_line
			(start 0.7874 0.4064)
			(end -0.7874 0.4064)
			(stroke
				(width 0.1524)
				(type default)
			)
			(layer "F.SilkS")
		)
		(fp_line
			(start -0.67945 -0.305054)
			(end -0.12065 -0.305054)
			(stroke
				(width 0.1)
				(type default)
			)
			(layer "F.Fab")
		)
		(fp_line
			(start -0.67945 0.3048)
			(end -0.67945 -0.305054)
			(stroke
				(width 0.1)
				(type default)
			)
			(layer "F.Fab")
		)
		(fp_line
			(start -0.12065 -0.305054)
			(end -0.12065 -0.2794)
			(stroke
				(width 0.1)
				(type default)
			)
			(layer "F.Fab")
		)
		(fp_line
			(start -0.12065 -0.2794)
			(end 0.12065 -0.2794)
			(stroke
				(width 0.1)
				(type default)
			)
			(layer "F.Fab")
		)
		(fp_line
			(start -0.12065 0.2794)
			(end -0.12065 0.3048)
			(stroke
				(width 0.1)
				(type default)
			)
			(layer "F.Fab")
		)
		(fp_line
			(start -0.12065 0.3048)
			(end -0.67945 0.3048)
			(stroke
				(width 0.1)
				(type default)
			)
			(layer "F.Fab")
		)
		(fp_line
			(start 0.120396 0.2794)
			(end -0.12065 0.2794)
			(stroke
				(width 0.1)
				(type default)
			)
			(layer "F.Fab")
		)
		(fp_line
			(start 0.120396 0.3048)
			(end 0.120396 0.2794)
			(stroke
				(width 0.1)
				(type default)
			)
			(layer "F.Fab")
		)
		(fp_line
			(start 0.12065 -0.3048)
			(end 0.67945 -0.3048)
			(stroke
				(width 0.1)
				(type default)
			)
			(layer "F.Fab")
		)
		(fp_line
			(start 0.12065 -0.2794)
			(end 0.12065 -0.3048)
			(stroke
				(width 0.1)
				(type default)
			)
			(layer "F.Fab")
		)
		(fp_line
			(start 0.67945 -0.3048)
			(end 0.67945 0.3048)
			(stroke
				(width 0.1)
				(type default)
			)
			(layer "F.Fab")
		)
		(fp_line
			(start 0.67945 0.3048)
			(end 0.120396 0.3048)
			(stroke
				(width 0.1)
				(type default)
			)
			(layer "F.Fab")
		)
		(pad "1" smd circle
			(at -0.40005 0)
			(size 0 0)
			(layers "F.Cu" "F.Mask" "F.Paste")
			(net "P3V3_AUX")
		)
		(pad "2" smd circle
			(at 0.40005 0)
			(size 0 0)
			(layers "F.Cu" "F.Mask" "F.Paste")
			(net "GND")
		)
	)
	(footprint ""
		(layer "F.Cu")
		(at 413.512 -43.815 180)
		(property "Reference" "R54"
			(at 0 0 180)
			(layer "F.SilkS")
			(hide yes)
			(effects
				(font
					(size 1.27 1.27)
				)
			)
		)
		(property "Value" ""
			(at 0 0 180)
			(layer "F.Fab")
			(effects
				(font
					(size 1.27 1.27)
				)
			)
		)
		(duplicate_pad_numbers_are_jumpers no)
		(fp_line
			(start 0.7874 0.4064)
			(end -0.7874 0.4064)
			(stroke
				(width 0.1524)
				(type default)
			)
			(layer "F.SilkS")
		)
		(fp_line
			(start 0.7874 -0.4064)
			(end 0.7874 0.4064)
			(stroke
				(width 0.1524)
				(type default)
			)
			(layer "F.SilkS")
		)
		(fp_line
			(start -0.7874 0.4064)
			(end -0.7874 -0.4064)
			(stroke
				(width 0.1524)
				(type default)
			)
			(layer "F.SilkS")
		)
		(fp_line
			(start -0.7874 -0.4064)
			(end 0.7874 -0.4064)
			(stroke
				(width 0.1524)
				(type default)
			)
			(layer "F.SilkS")
		)
		(fp_line
			(start 0.67945 0.3048)
			(end 0.120396 0.3048)
			(stroke
				(width 0.1)
				(type default)
			)
			(layer "F.Fab")
		)
		(fp_line
			(start 0.67945 -0.3048)
			(end 0.67945 0.3048)
			(stroke
				(width 0.1)
				(type default)
			)
			(layer "F.Fab")
		)
		(fp_line
			(start 0.12065 -0.2794)
			(end 0.12065 -0.3048)
			(stroke
				(width 0.1)
				(type default)
			)
			(layer "F.Fab")
		)
		(fp_line
			(start 0.12065 -0.3048)
			(end 0.67945 -0.3048)
			(stroke
				(width 0.1)
				(type default)
			)
			(layer "F.Fab")
		)
		(fp_line
			(start 0.120396 0.3048)
			(end 0.120396 0.2794)
			(stroke
				(width 0.1)
				(type default)
			)
			(layer "F.Fab")
		)
		(fp_line
			(start 0.120396 0.2794)
			(end -0.12065 0.2794)
			(stroke
				(width 0.1)
				(type default)
			)
			(layer "F.Fab")
		)
		(fp_line
			(start -0.12065 0.3048)
			(end -0.67945 0.3048)
			(stroke
				(width 0.1)
				(type default)
			)
			(layer "F.Fab")
		)
		(fp_line
			(start -0.12065 0.2794)
			(end -0.12065 0.3048)
			(stroke
				(width 0.1)
				(type default)
			)
			(layer "F.Fab")
		)
		(fp_line
			(start -0.12065 -0.2794)
			(end 0.12065 -0.2794)
			(stroke
				(width 0.1)
				(type default)
			)
			(layer "F.Fab")
		)
		(fp_line
			(start -0.12065 -0.305054)
			(end -0.12065 -0.2794)
			(stroke
				(width 0.1)
				(type default)
			)
			(layer "F.Fab")
		)
		(fp_line
			(start -0.67945 0.3048)
			(end -0.67945 -0.305054)
			(stroke
				(width 0.1)
				(type default)
			)
			(layer "F.Fab")
		)
		(fp_line
			(start -0.67945 -0.305054)
			(end -0.12065 -0.305054)
			(stroke
				(width 0.1)
				(type default)
			)
			(layer "F.Fab")
		)
		(pad "1" smd circle
			(at -0.40005 0 180)
			(size 0 0)
			(layers "F.Cu" "F.Mask" "F.Paste")
			(net "PCA9555_A2")
		)
		(pad "2" smd circle
			(at 0.40005 0 180)
			(size 0 0)
			(layers "F.Cu" "F.Mask" "F.Paste")
			(net "GND")
		)
	)
	(footprint ""
		(layer "F.Cu")
		(at 413.07258 -29.24556)
		(property "Reference" "R5916"
			(at 0 0 0)
			(layer "F.SilkS")
			(hide yes)
			(effects
				(font
					(size 1.27 1.27)
				)
			)
		)
		(property "Value" ""
			(at 0 0 0)
			(layer "F.Fab")
			(effects
				(font
					(size 1.27 1.27)
				)
			)
		)
		(duplicate_pad_numbers_are_jumpers no)
		(fp_line
			(start -0.7874 -0.4064)
			(end 0.7874 -0.4064)
			(stroke
				(width 0.1524)
				(type default)
			)
			(layer "F.SilkS")
		)
		(fp_line
			(start -0.7874 0.4064)
			(end -0.7874 -0.4064)
			(stroke
				(width 0.1524)
				(type default)
			)
			(layer "F.SilkS")
		)
		(fp_line
			(start 0.7874 -0.4064)
			(end 0.7874 0.4064)
			(stroke
				(width 0.1524)
				(type default)
			)
			(layer "F.SilkS")
		)
		(fp_line
			(start 0.7874 0.4064)
			(end -0.7874 0.4064)
			(stroke
				(width 0.1524)
				(type default)
			)
			(layer "F.SilkS")
		)
		(fp_line
			(start -0.67945 -0.305054)
			(end -0.12065 -0.305054)
			(stroke
				(width 0.1)
				(type default)
			)
			(layer "F.Fab")
		)
		(fp_line
			(start -0.67945 0.3048)
			(end -0.67945 -0.305054)
			(stroke
				(width 0.1)
				(type default)
			)
			(layer "F.Fab")
		)
		(fp_line
			(start -0.12065 -0.305054)
			(end -0.12065 -0.2794)
			(stroke
				(width 0.1)
				(type default)
			)
			(layer "F.Fab")
		)
		(fp_line
			(start -0.12065 -0.2794)
			(end 0.12065 -0.2794)
			(stroke
				(width 0.1)
				(type default)
			)
			(layer "F.Fab")
		)
		(fp_line
			(start -0.12065 0.2794)
			(end -0.12065 0.3048)
			(stroke
				(width 0.1)
				(type default)
			)
			(layer "F.Fab")
		)
		(fp_line
			(start -0.12065 0.3048)
			(end -0.67945 0.3048)
			(stroke
				(width 0.1)
				(type default)
			)
			(layer "F.Fab")
		)
		(fp_line
			(start 0.120396 0.2794)
			(end -0.12065 0.2794)
			(stroke
				(width 0.1)
				(type default)
			)
			(layer "F.Fab")
		)
		(fp_line
			(start 0.120396 0.3048)
			(end 0.120396 0.2794)
			(stroke
				(width 0.1)
				(type default)
			)
			(layer "F.Fab")
		)
		(fp_line
			(start 0.12065 -0.3048)
			(end 0.67945 -0.3048)
			(stroke
				(width 0.1)
				(type default)
			)
			(layer "F.Fab")
		)
		(fp_line
			(start 0.12065 -0.2794)
			(end 0.12065 -0.3048)
			(stroke
				(width 0.1)
				(type default)
			)
			(layer "F.Fab")
		)
		(fp_line
			(start 0.67945 -0.3048)
			(end 0.67945 0.3048)
			(stroke
				(width 0.1)
				(type default)
			)
			(layer "F.Fab")
		)
		(fp_line
			(start 0.67945 0.3048)
			(end 0.120396 0.3048)
			(stroke
				(width 0.1)
				(type default)
			)
			(layer "F.Fab")
		)
		(pad "1" smd circle
			(at -0.40005 0)
			(size 0 0)
			(layers "F.Cu" "F.Mask" "F.Paste")
			(net "P3V3_AUX")
		)
		(pad "2" smd circle
			(at 0.40005 0)
			(size 0 0)
			(layers "F.Cu" "F.Mask" "F.Paste")
			(net "PWRGD_P12V_FAN_LED_R")
		)
	)
	(footprint ""
		(layer "F.Cu")
		(at 418.91458 -32.75076 90)
		(property "Reference" "C97"
			(at 0 0 90)
			(layer "F.SilkS")
			(hide yes)
			(effects
				(font
					(size 1.27 1.27)
				)
			)
		)
		(property "Value" ""
			(at 0 0 90)
			(layer "F.Fab")
			(effects
				(font
					(size 1.27 1.27)
				)
			)
		)
		(duplicate_pad_numbers_are_jumpers no)
		(fp_line
			(start 0.7874 -0.4064)
			(end 0.7874 0.4064)
			(stroke
				(width 0.1524)
				(type default)
			)
			(layer "F.SilkS")
		)
		(fp_line
			(start -0.7874 -0.4064)
			(end 0.7874 -0.4064)
			(stroke
				(width 0.1524)
				(type default)
			)
			(layer "F.SilkS")
		)
		(fp_line
			(start 0.7874 0.4064)
			(end -0.7874 0.4064)
			(stroke
				(width 0.1524)
				(type default)
			)
			(layer "F.SilkS")
		)
		(fp_line
			(start -0.7874 0.4064)
			(end -0.7874 -0.4064)
			(stroke
				(width 0.1524)
				(type default)
			)
			(layer "F.SilkS")
		)
		(fp_line
			(start -0.12065 -0.305054)
			(end -0.12065 -0.2794)
			(stroke
				(width 0.1)
				(type default)
			)
			(layer "F.Fab")
		)
		(fp_line
			(start -0.67945 -0.305054)
			(end -0.12065 -0.305054)
			(stroke
				(width 0.1)
				(type default)
			)
			(layer "F.Fab")
		)
		(fp_line
			(start 0.67945 -0.3048)
			(end 0.67945 0.3048)
			(stroke
				(width 0.1)
				(type default)
			)
			(layer "F.Fab")
		)
		(fp_line
			(start 0.12065 -0.3048)
			(end 0.67945 -0.3048)
			(stroke
				(width 0.1)
				(type default)
			)
			(layer "F.Fab")
		)
		(fp_line
			(start 0.12065 -0.2794)
			(end 0.12065 -0.3048)
			(stroke
				(width 0.1)
				(type default)
			)
			(layer "F.Fab")
		)
		(fp_line
			(start -0.12065 -0.2794)
			(end 0.12065 -0.2794)
			(stroke
				(width 0.1)
				(type default)
			)
			(layer "F.Fab")
		)
		(fp_line
			(start 0.120396 0.2794)
			(end -0.12065 0.2794)
			(stroke
				(width 0.1)
				(type default)
			)
			(layer "F.Fab")
		)
		(fp_line
			(start -0.12065 0.2794)
			(end -0.12065 0.3048)
			(stroke
				(width 0.1)
				(type default)
			)
			(layer "F.Fab")
		)
		(fp_line
			(start 0.67945 0.3048)
			(end 0.120396 0.3048)
			(stroke
				(width 0.1)
				(type default)
			)
			(layer "F.Fab")
		)
		(fp_line
			(start 0.120396 0.3048)
			(end 0.120396 0.2794)
			(stroke
				(width 0.1)
				(type default)
			)
			(layer "F.Fab")
		)
		(fp_line
			(start -0.12065 0.3048)
			(end -0.67945 0.3048)
			(stroke
				(width 0.1)
				(type default)
			)
			(layer "F.Fab")
		)
		(fp_line
			(start -0.67945 0.3048)
			(end -0.67945 -0.305054)
			(stroke
				(width 0.1)
				(type default)
			)
			(layer "F.Fab")
		)
		(pad "1" smd circle
			(at -0.40005 0 90)
			(size 0 0)
			(layers "F.Cu" "F.Mask" "F.Paste")
			(net "P12V_LED_TIMER")
		)
		(pad "2" smd circle
			(at 0.40005 0 90)
			(size 0 0)
			(layers "F.Cu" "F.Mask" "F.Paste")
			(net "GND")
		)
	)
	(footprint ""
		(layer "F.Cu")
		(at 33.85439 -41.529 180)
		(property "Reference" "R39"
			(at 0 0 180)
			(layer "F.SilkS")
			(hide yes)
			(effects
				(font
					(size 1.27 1.27)
				)
			)
		)
		(property "Value" ""
			(at 0 0 180)
			(layer "F.Fab")
			(effects
				(font
					(size 1.27 1.27)
				)
			)
		)
		(duplicate_pad_numbers_are_jumpers no)
		(fp_line
			(start 2.234946 0.9271)
			(end -2.234946 0.9271)
			(stroke
				(width 0.1524)
				(type default)
			)
			(layer "F.SilkS")
		)
		(fp_line
			(start 2.234946 -0.9271)
			(end 2.234946 0.9271)
			(stroke
				(width 0.1524)
				(type default)
			)
			(layer "F.SilkS")
		)
		(fp_line
			(start -2.234946 0.9271)
			(end -2.234946 -0.9271)
			(stroke
				(width 0.1524)
				(type default)
			)
			(layer "F.SilkS")
		)
		(fp_line
			(start -2.234946 -0.9271)
			(end 2.234946 -0.9271)
			(stroke
				(width 0.1524)
				(type default)
			)
			(layer "F.SilkS")
		)
		(fp_line
			(start 1.575054 0.824992)
			(end 1.575054 -0.824992)
			(stroke
				(width 0.1)
				(type default)
			)
			(layer "F.Fab")
		)
		(fp_line
			(start 1.575054 -0.824992)
			(end -1.575054 -0.824992)
			(stroke
				(width 0.1)
				(type default)
			)
			(layer "F.Fab")
		)
		(fp_line
			(start -1.575054 0.824992)
			(end 1.575054 0.824992)
			(stroke
				(width 0.1)
				(type default)
			)
			(layer "F.Fab")
		)
		(fp_line
			(start -1.575054 -0.824992)
			(end -1.575054 0.824992)
			(stroke
				(width 0.1)
				(type default)
			)
			(layer "F.Fab")
		)
		(pad "1" smd rect
			(at -1.599946 0 180)
			(size 1.016 1.6002)
			(layers "F.Cu" "F.Mask" "F.Paste")
			(net "P52V_HS2")
		)
		(pad "2" smd rect
			(at 1.599946 0 180)
			(size 1.016 1.6002)
			(layers "F.Cu" "F.Mask" "F.Paste")
			(net "LED_D2_R1")
		)
	)
	(footprint ""
		(layer "F.Cu")
		(at 420.116 -50.546)
		(property "Reference" "R419"
			(at 0 0 0)
			(layer "F.SilkS")
			(hide yes)
			(effects
				(font
					(size 1.27 1.27)
				)
			)
		)
		(property "Value" ""
			(at 0 0 0)
			(layer "F.Fab")
			(effects
				(font
					(size 1.27 1.27)
				)
			)
		)
		(duplicate_pad_numbers_are_jumpers no)
		(fp_line
			(start -0.7874 -0.4064)
			(end 0.7874 -0.4064)
			(stroke
				(width 0.1524)
				(type default)
			)
			(layer "F.SilkS")
		)
		(fp_line
			(start -0.7874 0.4064)
			(end -0.7874 -0.4064)
			(stroke
				(width 0.1524)
				(type default)
			)
			(layer "F.SilkS")
		)
		(fp_line
			(start 0.7874 -0.4064)
			(end 0.7874 0.4064)
			(stroke
				(width 0.1524)
				(type default)
			)
			(layer "F.SilkS")
		)
		(fp_line
			(start 0.7874 0.4064)
			(end -0.7874 0.4064)
			(stroke
				(width 0.1524)
				(type default)
			)
			(layer "F.SilkS")
		)
		(fp_line
			(start -0.67945 -0.305054)
			(end -0.12065 -0.305054)
			(stroke
				(width 0.1)
				(type default)
			)
			(layer "F.Fab")
		)
		(fp_line
			(start -0.67945 0.3048)
			(end -0.67945 -0.305054)
			(stroke
				(width 0.1)
				(type default)
			)
			(layer "F.Fab")
		)
		(fp_line
			(start -0.12065 -0.305054)
			(end -0.12065 -0.2794)
			(stroke
				(width 0.1)
				(type default)
			)
			(layer "F.Fab")
		)
		(fp_line
			(start -0.12065 -0.2794)
			(end 0.12065 -0.2794)
			(stroke
				(width 0.1)
				(type default)
			)
			(layer "F.Fab")
		)
		(fp_line
			(start -0.12065 0.2794)
			(end -0.12065 0.3048)
			(stroke
				(width 0.1)
				(type default)
			)
			(layer "F.Fab")
		)
		(fp_line
			(start -0.12065 0.3048)
			(end -0.67945 0.3048)
			(stroke
				(width 0.1)
				(type default)
			)
			(layer "F.Fab")
		)
		(fp_line
			(start 0.120396 0.2794)
			(end -0.12065 0.2794)
			(stroke
				(width 0.1)
				(type default)
			)
			(layer "F.Fab")
		)
		(fp_line
			(start 0.120396 0.3048)
			(end 0.120396 0.2794)
			(stroke
				(width 0.1)
				(type default)
			)
			(layer "F.Fab")
		)
		(fp_line
			(start 0.12065 -0.3048)
			(end 0.67945 -0.3048)
			(stroke
				(width 0.1)
				(type default)
			)
			(layer "F.Fab")
		)
		(fp_line
			(start 0.12065 -0.2794)
			(end 0.12065 -0.3048)
			(stroke
				(width 0.1)
				(type default)
			)
			(layer "F.Fab")
		)
		(fp_line
			(start 0.67945 -0.3048)
			(end 0.67945 0.3048)
			(stroke
				(width 0.1)
				(type default)
			)
			(layer "F.Fab")
		)
		(fp_line
			(start 0.67945 0.3048)
			(end 0.120396 0.3048)
			(stroke
				(width 0.1)
				(type default)
			)
			(layer "F.Fab")
		)
		(pad "1" smd circle
			(at -0.40005 0)
			(size 0 0)
			(layers "F.Cu" "F.Mask" "F.Paste")
			(net "PWRGD_P52V_HS1_4287_PG")
		)
		(pad "2" smd circle
			(at 0.40005 0)
			(size 0 0)
			(layers "F.Cu" "F.Mask" "F.Paste")
			(net "PWRGD_P52V_HS1_PG")
		)
	)
	(footprint ""
		(layer "F.Cu")
		(at 208.810098 -79.624936)
		(property "Reference" "H32"
			(at -1.9812 -4.079748 0)
			(unlocked yes)
			(layer "B.SilkS")
			(effects
				(font
					(size 0.7874 0.5842)
					(thickness 0.1524)
				)
				(justify left mirror)
			)
		)
		(property "Value" ""
			(at 0 0 0)
			(layer "F.Fab")
			(effects
				(font
					(size 1.27 1.27)
				)
			)
		)
		(duplicate_pad_numbers_are_jumpers no)
		(pad "1" thru_hole circle
			(at 0 0)
			(size 8.001 8.001)
			(drill 4.2418)
			(layers "*.Cu" "*.Mask")
			(remove_unused_layers no)
			(net "TP_H32")
			(clearance -1.6256)
			(padstack
				(mode front_inner_back)
				(layer "Inner"
					(shape circle)
					(size 6.0198 6.0198)
					(clearance -0.635)
				)
				(layer "B.Cu"
					(shape circle)
					(size 8.001 8.001)
					(clearance -1.6256)
				)
			)
		)
		(zone
			(layers "F.Cu" "B.Cu" "In1.Cu" "In2.Cu" "In3.Cu" "In4.Cu" "In5.Cu" "In6.Cu"
				"In7.Cu" "In8.Cu"
			)
			(hatch none 0.5)
			(connect_pads
				(clearance 0)
			)
			(min_thickness 0.25)
			(keepout
				(tracks not_allowed)
				(vias allowed)
				(pads allowed)
				(copperpour not_allowed)
				(footprints allowed)
			)
			(placement
				(enabled no)
				(sheetname "")
			)
			(fill
				(thermal_gap 0.5)
				(thermal_bridge_width 0.5)
				(island_removal_mode 0)
			)
			(polygon
				(pts
					(arc
						(start 212.320124 -79.624936)
						(mid 205.300072 -79.624936)
						(end 212.320124 -79.624936)
					)
				)
			)
		)
	)
	(footprint ""
		(layer "F.Cu")
		(at 77.851 -45.4406)
		(property "Reference" "ME4"
			(at 0 0 0)
			(layer "F.SilkS")
			(hide yes)
			(effects
				(font
					(size 1.27 1.27)
				)
			)
		)
		(property "Value" ""
			(at 0 0 0)
			(layer "F.Fab")
			(effects
				(font
					(size 1.27 1.27)
				)
			)
		)
		(duplicate_pad_numbers_are_jumpers no)
		(fp_line
			(start 0 -6.999986)
			(end 0 -5.475986)
			(stroke
				(width 0.1524)
				(type default)
			)
			(layer "F.SilkS")
		)
		(fp_line
			(start 0 -1.524)
			(end 0 0)
			(stroke
				(width 0.1524)
				(type default)
			)
			(layer "F.SilkS")
		)
		(fp_line
			(start 0 0)
			(end 1.524 0)
			(stroke
				(width 0.1524)
				(type default)
			)
			(layer "F.SilkS")
		)
		(fp_line
			(start 1.524 -6.999986)
			(end 0 -6.999986)
			(stroke
				(width 0.1524)
				(type default)
			)
			(layer "F.SilkS")
		)
		(fp_line
			(start 5.475986 -6.999986)
			(end 6.999986 -6.999986)
			(stroke
				(width 0.1524)
				(type default)
			)
			(layer "F.SilkS")
		)
		(fp_line
			(start 6.999986 -6.999986)
			(end 6.999986 -5.475986)
			(stroke
				(width 0.1524)
				(type default)
			)
			(layer "F.SilkS")
		)
		(fp_line
			(start 6.999986 -1.524)
			(end 6.999986 0)
			(stroke
				(width 0.1524)
				(type default)
			)
			(layer "F.SilkS")
		)
		(fp_line
			(start 6.999986 0)
			(end 5.475986 0)
			(stroke
				(width 0.1524)
				(type default)
			)
			(layer "F.SilkS")
		)
		(fp_text user "S/N"
			(at 0.361188 -5.450078 0)
			(unlocked yes)
			(layer "F.SilkS")
			(effects
				(font
					(size 1.905 1.4224)
					(thickness 0.1524)
				)
				(justify left)
			)
		)
	)
	(footprint ""
		(layer "F.Cu")
		(at 436.245 -32.893)
		(property "Reference" "R22"
			(at 0 0 0)
			(layer "F.SilkS")
			(hide yes)
			(effects
				(font
					(size 1.27 1.27)
				)
			)
		)
		(property "Value" ""
			(at 0 0 0)
			(layer "F.Fab")
			(effects
				(font
					(size 1.27 1.27)
				)
			)
		)
		(duplicate_pad_numbers_are_jumpers no)
		(fp_line
			(start -0.7874 -0.4064)
			(end 0.7874 -0.4064)
			(stroke
				(width 0.1524)
				(type default)
			)
			(layer "F.SilkS")
		)
		(fp_line
			(start -0.7874 0.4064)
			(end -0.7874 -0.4064)
			(stroke
				(width 0.1524)
				(type default)
			)
			(layer "F.SilkS")
		)
		(fp_line
			(start 0.7874 -0.4064)
			(end 0.7874 0.4064)
			(stroke
				(width 0.1524)
				(type default)
			)
			(layer "F.SilkS")
		)
		(fp_line
			(start 0.7874 0.4064)
			(end -0.7874 0.4064)
			(stroke
				(width 0.1524)
				(type default)
			)
			(layer "F.SilkS")
		)
		(fp_line
			(start -0.67945 -0.305054)
			(end -0.12065 -0.305054)
			(stroke
				(width 0.1)
				(type default)
			)
			(layer "F.Fab")
		)
		(fp_line
			(start -0.67945 0.3048)
			(end -0.67945 -0.305054)
			(stroke
				(width 0.1)
				(type default)
			)
			(layer "F.Fab")
		)
		(fp_line
			(start -0.12065 -0.305054)
			(end -0.12065 -0.2794)
			(stroke
				(width 0.1)
				(type default)
			)
			(layer "F.Fab")
		)
		(fp_line
			(start -0.12065 -0.2794)
			(end 0.12065 -0.2794)
			(stroke
				(width 0.1)
				(type default)
			)
			(layer "F.Fab")
		)
		(fp_line
			(start -0.12065 0.2794)
			(end -0.12065 0.3048)
			(stroke
				(width 0.1)
				(type default)
			)
			(layer "F.Fab")
		)
		(fp_line
			(start -0.12065 0.3048)
			(end -0.67945 0.3048)
			(stroke
				(width 0.1)
				(type default)
			)
			(layer "F.Fab")
		)
		(fp_line
			(start 0.120396 0.2794)
			(end -0.12065 0.2794)
			(stroke
				(width 0.1)
				(type default)
			)
			(layer "F.Fab")
		)
		(fp_line
			(start 0.120396 0.3048)
			(end 0.120396 0.2794)
			(stroke
				(width 0.1)
				(type default)
			)
			(layer "F.Fab")
		)
		(fp_line
			(start 0.12065 -0.3048)
			(end 0.67945 -0.3048)
			(stroke
				(width 0.1)
				(type default)
			)
			(layer "F.Fab")
		)
		(fp_line
			(start 0.12065 -0.2794)
			(end 0.12065 -0.3048)
			(stroke
				(width 0.1)
				(type default)
			)
			(layer "F.Fab")
		)
		(fp_line
			(start 0.67945 -0.3048)
			(end 0.67945 0.3048)
			(stroke
				(width 0.1)
				(type default)
			)
			(layer "F.Fab")
		)
		(fp_line
			(start 0.67945 0.3048)
			(end 0.120396 0.3048)
			(stroke
				(width 0.1)
				(type default)
			)
			(layer "F.Fab")
		)
		(pad "1" smd circle
			(at -0.40005 0)
			(size 0 0)
			(layers "F.Cu" "F.Mask" "F.Paste")
			(net "P3V3_AUX")
		)
		(pad "2" smd circle
			(at 0.40005 0)
			(size 0 0)
			(layers "F.Cu" "F.Mask" "F.Paste")
			(net "PD_9543_FAN_A1")
		)
	)
	(footprint ""
		(layer "F.Cu")
		(at 380.803912 -17.907254 90)
		(property "Reference" "R74"
			(at 0 0 90)
			(layer "F.SilkS")
			(hide yes)
			(effects
				(font
					(size 1.27 1.27)
				)
			)
		)
		(property "Value" ""
			(at 0 0 90)
			(layer "F.Fab")
			(effects
				(font
					(size 1.27 1.27)
				)
			)
		)
		(duplicate_pad_numbers_are_jumpers no)
		(fp_line
			(start 0.7874 -0.4064)
			(end 0.7874 0.4064)
			(stroke
				(width 0.1524)
				(type default)
			)
			(layer "F.SilkS")
		)
		(fp_line
			(start -0.7874 -0.4064)
			(end 0.7874 -0.4064)
			(stroke
				(width 0.1524)
				(type default)
			)
			(layer "F.SilkS")
		)
		(fp_line
			(start 0.7874 0.4064)
			(end -0.7874 0.4064)
			(stroke
				(width 0.1524)
				(type default)
			)
			(layer "F.SilkS")
		)
		(fp_line
			(start -0.7874 0.4064)
			(end -0.7874 -0.4064)
			(stroke
				(width 0.1524)
				(type default)
			)
			(layer "F.SilkS")
		)
		(fp_line
			(start -0.12065 -0.305054)
			(end -0.12065 -0.2794)
			(stroke
				(width 0.1)
				(type default)
			)
			(layer "F.Fab")
		)
		(fp_line
			(start -0.67945 -0.305054)
			(end -0.12065 -0.305054)
			(stroke
				(width 0.1)
				(type default)
			)
			(layer "F.Fab")
		)
		(fp_line
			(start 0.67945 -0.3048)
			(end 0.67945 0.3048)
			(stroke
				(width 0.1)
				(type default)
			)
			(layer "F.Fab")
		)
		(fp_line
			(start 0.12065 -0.3048)
			(end 0.67945 -0.3048)
			(stroke
				(width 0.1)
				(type default)
			)
			(layer "F.Fab")
		)
		(fp_line
			(start 0.12065 -0.2794)
			(end 0.12065 -0.3048)
			(stroke
				(width 0.1)
				(type default)
			)
			(layer "F.Fab")
		)
		(fp_line
			(start -0.12065 -0.2794)
			(end 0.12065 -0.2794)
			(stroke
				(width 0.1)
				(type default)
			)
			(layer "F.Fab")
		)
		(fp_line
			(start 0.120396 0.2794)
			(end -0.12065 0.2794)
			(stroke
				(width 0.1)
				(type default)
			)
			(layer "F.Fab")
		)
		(fp_line
			(start -0.12065 0.2794)
			(end -0.12065 0.3048)
			(stroke
				(width 0.1)
				(type default)
			)
			(layer "F.Fab")
		)
		(fp_line
			(start 0.67945 0.3048)
			(end 0.120396 0.3048)
			(stroke
				(width 0.1)
				(type default)
			)
			(layer "F.Fab")
		)
		(fp_line
			(start 0.120396 0.3048)
			(end 0.120396 0.2794)
			(stroke
				(width 0.1)
				(type default)
			)
			(layer "F.Fab")
		)
		(fp_line
			(start -0.12065 0.3048)
			(end -0.67945 0.3048)
			(stroke
				(width 0.1)
				(type default)
			)
			(layer "F.Fab")
		)
		(fp_line
			(start -0.67945 0.3048)
			(end -0.67945 -0.305054)
			(stroke
				(width 0.1)
				(type default)
			)
			(layer "F.Fab")
		)
		(pad "1" smd circle
			(at -0.40005 0 90)
			(size 0 0)
			(layers "F.Cu" "F.Mask" "F.Paste")
			(net "RST_SMB_FAN_0_R_N")
		)
		(pad "2" smd circle
			(at 0.40005 0 90)
			(size 0 0)
			(layers "F.Cu" "F.Mask" "F.Paste")
			(net "RST_SMB_PDB_BUF_N")
		)
	)
	(footprint ""
		(layer "F.Cu")
		(at 281.0764 -75.184 180)
		(property "Reference" "PR37"
			(at 0 0 180)
			(layer "F.SilkS")
			(hide yes)
			(effects
				(font
					(size 1.27 1.27)
				)
			)
		)
		(property "Value" ""
			(at 0 0 180)
			(layer "F.Fab")
			(effects
				(font
					(size 1.27 1.27)
				)
			)
		)
		(duplicate_pad_numbers_are_jumpers no)
		(fp_line
			(start 0.7874 0.4064)
			(end -0.7874 0.4064)
			(stroke
				(width 0.1524)
				(type default)
			)
			(layer "F.SilkS")
		)
		(fp_line
			(start 0.7874 -0.4064)
			(end 0.7874 0.4064)
			(stroke
				(width 0.1524)
				(type default)
			)
			(layer "F.SilkS")
		)
		(fp_line
			(start -0.7874 0.4064)
			(end -0.7874 -0.4064)
			(stroke
				(width 0.1524)
				(type default)
			)
			(layer "F.SilkS")
		)
		(fp_line
			(start -0.7874 -0.4064)
			(end 0.7874 -0.4064)
			(stroke
				(width 0.1524)
				(type default)
			)
			(layer "F.SilkS")
		)
		(fp_line
			(start 0.67945 0.3048)
			(end 0.120396 0.3048)
			(stroke
				(width 0.1)
				(type default)
			)
			(layer "F.Fab")
		)
		(fp_line
			(start 0.67945 -0.3048)
			(end 0.67945 0.3048)
			(stroke
				(width 0.1)
				(type default)
			)
			(layer "F.Fab")
		)
		(fp_line
			(start 0.12065 -0.2794)
			(end 0.12065 -0.3048)
			(stroke
				(width 0.1)
				(type default)
			)
			(layer "F.Fab")
		)
		(fp_line
			(start 0.12065 -0.3048)
			(end 0.67945 -0.3048)
			(stroke
				(width 0.1)
				(type default)
			)
			(layer "F.Fab")
		)
		(fp_line
			(start 0.120396 0.3048)
			(end 0.120396 0.2794)
			(stroke
				(width 0.1)
				(type default)
			)
			(layer "F.Fab")
		)
		(fp_line
			(start 0.120396 0.2794)
			(end -0.12065 0.2794)
			(stroke
				(width 0.1)
				(type default)
			)
			(layer "F.Fab")
		)
		(fp_line
			(start -0.12065 0.3048)
			(end -0.67945 0.3048)
			(stroke
				(width 0.1)
				(type default)
			)
			(layer "F.Fab")
		)
		(fp_line
			(start -0.12065 0.2794)
			(end -0.12065 0.3048)
			(stroke
				(width 0.1)
				(type default)
			)
			(layer "F.Fab")
		)
		(fp_line
			(start -0.12065 -0.2794)
			(end 0.12065 -0.2794)
			(stroke
				(width 0.1)
				(type default)
			)
			(layer "F.Fab")
		)
		(fp_line
			(start -0.12065 -0.305054)
			(end -0.12065 -0.2794)
			(stroke
				(width 0.1)
				(type default)
			)
			(layer "F.Fab")
		)
		(fp_line
			(start -0.67945 0.3048)
			(end -0.67945 -0.305054)
			(stroke
				(width 0.1)
				(type default)
			)
			(layer "F.Fab")
		)
		(fp_line
			(start -0.67945 -0.305054)
			(end -0.12065 -0.305054)
			(stroke
				(width 0.1)
				(type default)
			)
			(layer "F.Fab")
		)
		(pad "1" smd circle
			(at -0.40005 0 180)
			(size 0 0)
			(layers "F.Cu" "F.Mask" "F.Paste")
			(net "P52V_HS1_EFAULT")
		)
		(pad "2" smd circle
			(at 0.40005 0 180)
			(size 0 0)
			(layers "F.Cu" "F.Mask" "F.Paste")
			(net "GND_FIELD_SIGNAL")
		)
	)
	(footprint ""
		(layer "F.Cu")
		(at 427.228 -43.18)
		(property "Reference" "R100"
			(at 0 0 0)
			(layer "F.SilkS")
			(hide yes)
			(effects
				(font
					(size 1.27 1.27)
				)
			)
		)
		(property "Value" ""
			(at 0 0 0)
			(layer "F.Fab")
			(effects
				(font
					(size 1.27 1.27)
				)
			)
		)
		(duplicate_pad_numbers_are_jumpers no)
		(fp_line
			(start -0.7874 -0.4064)
			(end 0.7874 -0.4064)
			(stroke
				(width 0.1524)
				(type default)
			)
			(layer "F.SilkS")
		)
		(fp_line
			(start -0.7874 0.4064)
			(end -0.7874 -0.4064)
			(stroke
				(width 0.1524)
				(type default)
			)
			(layer "F.SilkS")
		)
		(fp_line
			(start 0.7874 -0.4064)
			(end 0.7874 0.4064)
			(stroke
				(width 0.1524)
				(type default)
			)
			(layer "F.SilkS")
		)
		(fp_line
			(start 0.7874 0.4064)
			(end -0.7874 0.4064)
			(stroke
				(width 0.1524)
				(type default)
			)
			(layer "F.SilkS")
		)
		(fp_line
			(start -0.67945 -0.305054)
			(end -0.12065 -0.305054)
			(stroke
				(width 0.1)
				(type default)
			)
			(layer "F.Fab")
		)
		(fp_line
			(start -0.67945 0.3048)
			(end -0.67945 -0.305054)
			(stroke
				(width 0.1)
				(type default)
			)
			(layer "F.Fab")
		)
		(fp_line
			(start -0.12065 -0.305054)
			(end -0.12065 -0.2794)
			(stroke
				(width 0.1)
				(type default)
			)
			(layer "F.Fab")
		)
		(fp_line
			(start -0.12065 -0.2794)
			(end 0.12065 -0.2794)
			(stroke
				(width 0.1)
				(type default)
			)
			(layer "F.Fab")
		)
		(fp_line
			(start -0.12065 0.2794)
			(end -0.12065 0.3048)
			(stroke
				(width 0.1)
				(type default)
			)
			(layer "F.Fab")
		)
		(fp_line
			(start -0.12065 0.3048)
			(end -0.67945 0.3048)
			(stroke
				(width 0.1)
				(type default)
			)
			(layer "F.Fab")
		)
		(fp_line
			(start 0.120396 0.2794)
			(end -0.12065 0.2794)
			(stroke
				(width 0.1)
				(type default)
			)
			(layer "F.Fab")
		)
		(fp_line
			(start 0.120396 0.3048)
			(end 0.120396 0.2794)
			(stroke
				(width 0.1)
				(type default)
			)
			(layer "F.Fab")
		)
		(fp_line
			(start 0.12065 -0.3048)
			(end 0.67945 -0.3048)
			(stroke
				(width 0.1)
				(type default)
			)
			(layer "F.Fab")
		)
		(fp_line
			(start 0.12065 -0.2794)
			(end 0.12065 -0.3048)
			(stroke
				(width 0.1)
				(type default)
			)
			(layer "F.Fab")
		)
		(fp_line
			(start 0.67945 -0.3048)
			(end 0.67945 0.3048)
			(stroke
				(width 0.1)
				(type default)
			)
			(layer "F.Fab")
		)
		(fp_line
			(start 0.67945 0.3048)
			(end 0.120396 0.3048)
			(stroke
				(width 0.1)
				(type default)
			)
			(layer "F.Fab")
		)
		(pad "1" smd circle
			(at -0.40005 0)
			(size 0 0)
			(layers "F.Cu" "F.Mask" "F.Paste")
			(net "SKU_ID_1")
		)
		(pad "2" smd circle
			(at 0.40005 0)
			(size 0 0)
			(layers "F.Cu" "F.Mask" "F.Paste")
			(net "GND")
		)
	)
	(footprint ""
		(layer "F.Cu")
		(at 11.999976 -83.999832 180)
		(property "Reference" "H1"
			(at 0.569976 -5.413502 0)
			(unlocked yes)
			(layer "F.SilkS")
			(effects
				(font
					(size 0.7874 0.5842)
					(thickness 0.1524)
				)
				(justify left)
			)
		)
		(property "Value" ""
			(at 0 0 180)
			(layer "F.Fab")
			(effects
				(font
					(size 1.27 1.27)
				)
			)
		)
		(duplicate_pad_numbers_are_jumpers no)
		(pad "1" thru_hole oval
			(at 0 0 180)
			(size 9.017 14.0208)
			(drill 3.0226
				(offset 0 2.499868)
			)
			(layers "*.Cu" "*.Mask")
			(remove_unused_layers no)
			(net "GND")
			(clearance -1.500378)
			(padstack
				(mode front_inner_back)
				(layer "Inner"
					(shape circle)
					(size 0 0)
					(clearance 0)
				)
				(layer "B.Cu"
					(shape oval)
					(size 9.017 14.0208)
					(offset 0 2.499868)
					(clearance -1.500378)
				)
			)
		)
	)
	(footprint ""
		(layer "F.Cu")
		(at 409.956 -43.053)
		(property "Reference" "R5911"
			(at 0 0 0)
			(layer "F.SilkS")
			(hide yes)
			(effects
				(font
					(size 1.27 1.27)
				)
			)
		)
		(property "Value" ""
			(at 0 0 0)
			(layer "F.Fab")
			(effects
				(font
					(size 1.27 1.27)
				)
			)
		)
		(duplicate_pad_numbers_are_jumpers no)
		(fp_line
			(start -0.7874 -0.4064)
			(end 0.7874 -0.4064)
			(stroke
				(width 0.1524)
				(type default)
			)
			(layer "F.SilkS")
		)
		(fp_line
			(start -0.7874 0.4064)
			(end -0.7874 -0.4064)
			(stroke
				(width 0.1524)
				(type default)
			)
			(layer "F.SilkS")
		)
		(fp_line
			(start 0.7874 -0.4064)
			(end 0.7874 0.4064)
			(stroke
				(width 0.1524)
				(type default)
			)
			(layer "F.SilkS")
		)
		(fp_line
			(start 0.7874 0.4064)
			(end -0.7874 0.4064)
			(stroke
				(width 0.1524)
				(type default)
			)
			(layer "F.SilkS")
		)
		(fp_line
			(start -0.67945 -0.305054)
			(end -0.12065 -0.305054)
			(stroke
				(width 0.1)
				(type default)
			)
			(layer "F.Fab")
		)
		(fp_line
			(start -0.67945 0.3048)
			(end -0.67945 -0.305054)
			(stroke
				(width 0.1)
				(type default)
			)
			(layer "F.Fab")
		)
		(fp_line
			(start -0.12065 -0.305054)
			(end -0.12065 -0.2794)
			(stroke
				(width 0.1)
				(type default)
			)
			(layer "F.Fab")
		)
		(fp_line
			(start -0.12065 -0.2794)
			(end 0.12065 -0.2794)
			(stroke
				(width 0.1)
				(type default)
			)
			(layer "F.Fab")
		)
		(fp_line
			(start -0.12065 0.2794)
			(end -0.12065 0.3048)
			(stroke
				(width 0.1)
				(type default)
			)
			(layer "F.Fab")
		)
		(fp_line
			(start -0.12065 0.3048)
			(end -0.67945 0.3048)
			(stroke
				(width 0.1)
				(type default)
			)
			(layer "F.Fab")
		)
		(fp_line
			(start 0.120396 0.2794)
			(end -0.12065 0.2794)
			(stroke
				(width 0.1)
				(type default)
			)
			(layer "F.Fab")
		)
		(fp_line
			(start 0.120396 0.3048)
			(end 0.120396 0.2794)
			(stroke
				(width 0.1)
				(type default)
			)
			(layer "F.Fab")
		)
		(fp_line
			(start 0.12065 -0.3048)
			(end 0.67945 -0.3048)
			(stroke
				(width 0.1)
				(type default)
			)
			(layer "F.Fab")
		)
		(fp_line
			(start 0.12065 -0.2794)
			(end 0.12065 -0.3048)
			(stroke
				(width 0.1)
				(type default)
			)
			(layer "F.Fab")
		)
		(fp_line
			(start 0.67945 -0.3048)
			(end 0.67945 0.3048)
			(stroke
				(width 0.1)
				(type default)
			)
			(layer "F.Fab")
		)
		(fp_line
			(start 0.67945 0.3048)
			(end 0.120396 0.3048)
			(stroke
				(width 0.1)
				(type default)
			)
			(layer "F.Fab")
		)
		(pad "1" smd circle
			(at -0.40005 0)
			(size 0 0)
			(layers "F.Cu" "F.Mask" "F.Paste")
			(net "P3V3_AUX")
		)
		(pad "2" smd circle
			(at 0.40005 0)
			(size 0 0)
			(layers "F.Cu" "F.Mask" "F.Paste")
			(net "PRSNT_FAN_BP0_R_N")
		)
	)
	(footprint ""
		(layer "F.Cu")
		(at 177.927 -45.212 180)
		(property "Reference" "R384"
			(at 0 0 180)
			(layer "F.SilkS")
			(hide yes)
			(effects
				(font
					(size 1.27 1.27)
				)
			)
		)
		(property "Value" ""
			(at 0 0 180)
			(layer "F.Fab")
			(effects
				(font
					(size 1.27 1.27)
				)
			)
		)
		(duplicate_pad_numbers_are_jumpers no)
		(fp_line
			(start 1.651 0.8382)
			(end -1.651 0.8382)
			(stroke
				(width 0.1524)
				(type default)
			)
			(layer "F.SilkS")
		)
		(fp_line
			(start 1.651 -0.8382)
			(end 1.651 0.8382)
			(stroke
				(width 0.1524)
				(type default)
			)
			(layer "F.SilkS")
		)
		(fp_line
			(start -1.651 0.8382)
			(end -1.651 -0.8382)
			(stroke
				(width 0.1524)
				(type default)
			)
			(layer "F.SilkS")
		)
		(fp_line
			(start -1.651 -0.8382)
			(end 1.651 -0.8382)
			(stroke
				(width 0.1524)
				(type default)
			)
			(layer "F.SilkS")
		)
		(fp_line
			(start 1.560576 0.7366)
			(end 1.560576 -0.7366)
			(stroke
				(width 0.1)
				(type default)
			)
			(layer "F.Fab")
		)
		(fp_line
			(start 1.560576 -0.7366)
			(end 1.524 -0.7366)
			(stroke
				(width 0.1)
				(type default)
			)
			(layer "F.Fab")
		)
		(fp_line
			(start 1.524 0.7366)
			(end 1.560576 0.7366)
			(stroke
				(width 0.1)
				(type default)
			)
			(layer "F.Fab")
		)
		(fp_line
			(start 1.524 -0.7366)
			(end -1.524 -0.7366)
			(stroke
				(width 0.1)
				(type default)
			)
			(layer "F.Fab")
		)
		(fp_line
			(start -1.524 0.7366)
			(end 1.524 0.7366)
			(stroke
				(width 0.1)
				(type default)
			)
			(layer "F.Fab")
		)
		(fp_line
			(start -1.524 -0.7366)
			(end -1.559814 -0.7366)
			(stroke
				(width 0.1)
				(type default)
			)
			(layer "F.Fab")
		)
		(fp_line
			(start -1.559814 0.7366)
			(end -1.524 0.7366)
			(stroke
				(width 0.1)
				(type default)
			)
			(layer "F.Fab")
		)
		(fp_line
			(start -1.559814 -0.7366)
			(end -1.559814 0.7366)
			(stroke
				(width 0.1)
				(type default)
			)
			(layer "F.Fab")
		)
		(pad "1" smd rect
			(at -0.94996 0)
			(size 1.1176 1.3716)
			(layers "F.Cu" "F.Mask" "F.Paste")
			(net "P52V_2_FUSE_1")
		)
		(pad "2" smd rect
			(at 0.94996 0)
			(size 1.1176 1.3716)
			(layers "F.Cu" "F.Mask" "F.Paste")
			(net "GPU_HSC2_BUF_EN_N")
		)
	)
	(footprint ""
		(layer "F.Cu")
		(at 430.276 -45.974 180)
		(property "Reference" "R53"
			(at 0 0 180)
			(layer "F.SilkS")
			(hide yes)
			(effects
				(font
					(size 1.27 1.27)
				)
			)
		)
		(property "Value" ""
			(at 0 0 180)
			(layer "F.Fab")
			(effects
				(font
					(size 1.27 1.27)
				)
			)
		)
		(duplicate_pad_numbers_are_jumpers no)
		(fp_line
			(start 0.7874 0.4064)
			(end -0.7874 0.4064)
			(stroke
				(width 0.1524)
				(type default)
			)
			(layer "F.SilkS")
		)
		(fp_line
			(start 0.7874 -0.4064)
			(end 0.7874 0.4064)
			(stroke
				(width 0.1524)
				(type default)
			)
			(layer "F.SilkS")
		)
		(fp_line
			(start -0.7874 0.4064)
			(end -0.7874 -0.4064)
			(stroke
				(width 0.1524)
				(type default)
			)
			(layer "F.SilkS")
		)
		(fp_line
			(start -0.7874 -0.4064)
			(end 0.7874 -0.4064)
			(stroke
				(width 0.1524)
				(type default)
			)
			(layer "F.SilkS")
		)
		(fp_line
			(start 0.67945 0.3048)
			(end 0.120396 0.3048)
			(stroke
				(width 0.1)
				(type default)
			)
			(layer "F.Fab")
		)
		(fp_line
			(start 0.67945 -0.3048)
			(end 0.67945 0.3048)
			(stroke
				(width 0.1)
				(type default)
			)
			(layer "F.Fab")
		)
		(fp_line
			(start 0.12065 -0.2794)
			(end 0.12065 -0.3048)
			(stroke
				(width 0.1)
				(type default)
			)
			(layer "F.Fab")
		)
		(fp_line
			(start 0.12065 -0.3048)
			(end 0.67945 -0.3048)
			(stroke
				(width 0.1)
				(type default)
			)
			(layer "F.Fab")
		)
		(fp_line
			(start 0.120396 0.3048)
			(end 0.120396 0.2794)
			(stroke
				(width 0.1)
				(type default)
			)
			(layer "F.Fab")
		)
		(fp_line
			(start 0.120396 0.2794)
			(end -0.12065 0.2794)
			(stroke
				(width 0.1)
				(type default)
			)
			(layer "F.Fab")
		)
		(fp_line
			(start -0.12065 0.3048)
			(end -0.67945 0.3048)
			(stroke
				(width 0.1)
				(type default)
			)
			(layer "F.Fab")
		)
		(fp_line
			(start -0.12065 0.2794)
			(end -0.12065 0.3048)
			(stroke
				(width 0.1)
				(type default)
			)
			(layer "F.Fab")
		)
		(fp_line
			(start -0.12065 -0.2794)
			(end 0.12065 -0.2794)
			(stroke
				(width 0.1)
				(type default)
			)
			(layer "F.Fab")
		)
		(fp_line
			(start -0.12065 -0.305054)
			(end -0.12065 -0.2794)
			(stroke
				(width 0.1)
				(type default)
			)
			(layer "F.Fab")
		)
		(fp_line
			(start -0.67945 0.3048)
			(end -0.67945 -0.305054)
			(stroke
				(width 0.1)
				(type default)
			)
			(layer "F.Fab")
		)
		(fp_line
			(start -0.67945 -0.305054)
			(end -0.12065 -0.305054)
			(stroke
				(width 0.1)
				(type default)
			)
			(layer "F.Fab")
		)
		(pad "1" smd circle
			(at -0.40005 0 180)
			(size 0 0)
			(layers "F.Cu" "F.Mask" "F.Paste")
			(net "P3V3_AUX")
		)
		(pad "2" smd circle
			(at 0.40005 0 180)
			(size 0 0)
			(layers "F.Cu" "F.Mask" "F.Paste")
			(net "PCA9555_A0")
		)
	)
	(footprint ""
		(layer "F.Cu")
		(at 283.845 -76.327)
		(property "Reference" "PC11"
			(at 0 0 0)
			(layer "F.SilkS")
			(hide yes)
			(effects
				(font
					(size 1.27 1.27)
				)
			)
		)
		(property "Value" ""
			(at 0 0 0)
			(layer "F.Fab")
			(effects
				(font
					(size 1.27 1.27)
				)
			)
		)
		(duplicate_pad_numbers_are_jumpers no)
		(fp_line
			(start -1.2954 -0.5842)
			(end 1.2954 -0.5842)
			(stroke
				(width 0.1524)
				(type default)
			)
			(layer "F.SilkS")
		)
		(fp_line
			(start -1.2954 0.5842)
			(end -1.2954 -0.5842)
			(stroke
				(width 0.1524)
				(type default)
			)
			(layer "F.SilkS")
		)
		(fp_line
			(start 1.2954 -0.5842)
			(end 1.2954 0.5842)
			(stroke
				(width 0.1524)
				(type default)
			)
			(layer "F.SilkS")
		)
		(fp_line
			(start 1.2954 0.5842)
			(end -1.2954 0.5842)
			(stroke
				(width 0.1524)
				(type default)
			)
			(layer "F.SilkS")
		)
		(fp_line
			(start -1.1938 -0.4064)
			(end -0.8636 -0.4064)
			(stroke
				(width 0.1)
				(type default)
			)
			(layer "F.Fab")
		)
		(fp_line
			(start -1.1938 0.4064)
			(end -1.1938 -0.4064)
			(stroke
				(width 0.1)
				(type default)
			)
			(layer "F.Fab")
		)
		(fp_line
			(start -0.8636 -0.4572)
			(end 0.8636 -0.4572)
			(stroke
				(width 0.1)
				(type default)
			)
			(layer "F.Fab")
		)
		(fp_line
			(start -0.8636 -0.4064)
			(end -0.8636 -0.4572)
			(stroke
				(width 0.1)
				(type default)
			)
			(layer "F.Fab")
		)
		(fp_line
			(start -0.8636 0.4064)
			(end -1.1938 0.4064)
			(stroke
				(width 0.1)
				(type default)
			)
			(layer "F.Fab")
		)
		(fp_line
			(start -0.8636 0.4572)
			(end -0.8636 0.4064)
			(stroke
				(width 0.1)
				(type default)
			)
			(layer "F.Fab")
		)
		(fp_line
			(start 0.8636 -0.4572)
			(end 0.8636 -0.4064)
			(stroke
				(width 0.1)
				(type default)
			)
			(layer "F.Fab")
		)
		(fp_line
			(start 0.8636 -0.4064)
			(end 1.1938 -0.4064)
			(stroke
				(width 0.1)
				(type default)
			)
			(layer "F.Fab")
		)
		(fp_line
			(start 0.8636 0.4064)
			(end 0.8636 0.4572)
			(stroke
				(width 0.1)
				(type default)
			)
			(layer "F.Fab")
		)
		(fp_line
			(start 0.8636 0.4572)
			(end -0.8636 0.4572)
			(stroke
				(width 0.1)
				(type default)
			)
			(layer "F.Fab")
		)
		(fp_line
			(start 1.1938 -0.4064)
			(end 1.1938 0.4064)
			(stroke
				(width 0.1)
				(type default)
			)
			(layer "F.Fab")
		)
		(fp_line
			(start 1.1938 0.4064)
			(end 0.8636 0.4064)
			(stroke
				(width 0.1)
				(type default)
			)
			(layer "F.Fab")
		)
		(pad "1" smd rect
			(at -0.7366 0 270)
			(size 0.7112 0.8128)
			(layers "F.Cu" "F.Mask" "F.Paste")
			(net "P52V_HS1_ESTART")
		)
		(pad "2" smd rect
			(at 0.7366 0 270)
			(size 0.7112 0.8128)
			(layers "F.Cu" "F.Mask" "F.Paste")
			(net "GND_FIELD_SIGNAL")
		)
	)
	(footprint ""
		(layer "F.Cu")
		(at 306.7304 -71.755)
		(property "Reference" "PR6957"
			(at 0 0 0)
			(layer "F.SilkS")
			(hide yes)
			(effects
				(font
					(size 1.27 1.27)
				)
			)
		)
		(property "Value" ""
			(at 0 0 0)
			(layer "F.Fab")
			(effects
				(font
					(size 1.27 1.27)
				)
			)
		)
		(duplicate_pad_numbers_are_jumpers no)
		(fp_line
			(start -1.2954 -0.5842)
			(end 1.2954 -0.5842)
			(stroke
				(width 0.1524)
				(type default)
			)
			(layer "F.SilkS")
		)
		(fp_line
			(start -1.2954 0.5842)
			(end -1.2954 -0.5842)
			(stroke
				(width 0.1524)
				(type default)
			)
			(layer "F.SilkS")
		)
		(fp_line
			(start 1.2954 -0.5842)
			(end 1.2954 0.5842)
			(stroke
				(width 0.1524)
				(type default)
			)
			(layer "F.SilkS")
		)
		(fp_line
			(start 1.2954 0.5842)
			(end -1.2954 0.5842)
			(stroke
				(width 0.1524)
				(type default)
			)
			(layer "F.SilkS")
		)
		(fp_line
			(start -1.1938 -0.406654)
			(end -0.8636 -0.406654)
			(stroke
				(width 0.1)
				(type default)
			)
			(layer "F.Fab")
		)
		(fp_line
			(start -1.1938 0.4064)
			(end -1.1938 -0.406654)
			(stroke
				(width 0.1)
				(type default)
			)
			(layer "F.Fab")
		)
		(fp_line
			(start -0.8636 -0.4572)
			(end 0.8636 -0.4572)
			(stroke
				(width 0.1)
				(type default)
			)
			(layer "F.Fab")
		)
		(fp_line
			(start -0.8636 -0.406654)
			(end -0.8636 -0.4572)
			(stroke
				(width 0.1)
				(type default)
			)
			(layer "F.Fab")
		)
		(fp_line
			(start -0.8636 0.4064)
			(end -1.1938 0.4064)
			(stroke
				(width 0.1)
				(type default)
			)
			(layer "F.Fab")
		)
		(fp_line
			(start -0.8636 0.4318)
			(end -0.8636 0.4064)
			(stroke
				(width 0.1)
				(type default)
			)
			(layer "F.Fab")
		)
		(fp_line
			(start -0.8636 0.4572)
			(end -0.8636 0.4318)
			(stroke
				(width 0.1)
				(type default)
			)
			(layer "F.Fab")
		)
		(fp_line
			(start 0.8636 -0.4572)
			(end 0.8636 -0.406654)
			(stroke
				(width 0.1)
				(type default)
			)
			(layer "F.Fab")
		)
		(fp_line
			(start 0.8636 -0.406654)
			(end 1.1938 -0.406654)
			(stroke
				(width 0.1)
				(type default)
			)
			(layer "F.Fab")
		)
		(fp_line
			(start 0.8636 0.4064)
			(end 0.8636 0.4572)
			(stroke
				(width 0.1)
				(type default)
			)
			(layer "F.Fab")
		)
		(fp_line
			(start 0.8636 0.4572)
			(end -0.8636 0.4572)
			(stroke
				(width 0.1)
				(type default)
			)
			(layer "F.Fab")
		)
		(fp_line
			(start 1.1938 -0.406654)
			(end 1.1938 0.4064)
			(stroke
				(width 0.1)
				(type default)
			)
			(layer "F.Fab")
		)
		(fp_line
			(start 1.1938 0.4064)
			(end 0.8636 0.4064)
			(stroke
				(width 0.1)
				(type default)
			)
			(layer "F.Fab")
		)
		(pad "1" smd rect
			(at -0.7366 0 270)
			(size 0.7112 0.8128)
			(layers "F.Cu" "F.Mask" "F.Paste")
			(net "P52V_HS_4287_S1N")
		)
		(pad "2" smd rect
			(at 0.7366 0 270)
			(size 0.7112 0.8128)
			(layers "F.Cu" "F.Mask" "F.Paste")
			(net "P52V_HS1_SENSE_N_R1")
		)
	)
	(footprint ""
		(layer "F.Cu")
		(at 424.999912 -104.549956)
		(property "Reference" "H23"
			(at -0.794512 8.818626 0)
			(unlocked yes)
			(layer "F.SilkS")
			(effects
				(font
					(size 0.7874 0.5842)
					(thickness 0.1524)
				)
				(justify left)
			)
		)
		(property "Value" ""
			(at 0 0 0)
			(layer "F.Fab")
			(effects
				(font
					(size 1.27 1.27)
				)
			)
		)
		(duplicate_pad_numbers_are_jumpers no)
		(fp_circle
			(center 0 0)
			(end 7.999984 0)
			(stroke
				(width 0.1524)
				(type default)
			)
			(fill no)
			(layer "F.SilkS")
		)
		(fp_circle
			(center 0 0)
			(end 7.999984 0)
			(stroke
				(width 0.1524)
				(type default)
			)
			(fill no)
			(layer "B.SilkS")
		)
		(fp_circle
			(center 0 0)
			(end 7.999984 0)
			(stroke
				(width 0.1)
				(type default)
			)
			(fill no)
			(layer "B.Fab")
		)
		(fp_circle
			(center 0 0)
			(end 7.999984 0)
			(stroke
				(width 0.1)
				(type default)
			)
			(fill no)
			(layer "F.Fab")
		)
		(pad "" np_thru_hole circle
			(at 0 0)
			(size 4.0132 4.0132)
			(drill 4.0132)
			(layers "*.Cu" "*.Mask")
			(clearance 0.381)
			(thermal_gap 0.381)
		)
		(pad "2" thru_hole circle
			(at 0 -3.50012)
			(size 0.762 0.762)
			(drill 0.5588)
			(layers "*.Cu" "*.Mask")
			(remove_unused_layers no)
			(net "GND")
			(clearance 0.1524)
			(thermal_gap 0.1524)
		)
		(pad "3" thru_hole circle
			(at -2.500122 -2.500122)
			(size 0.762 0.762)
			(drill 0.5588)
			(layers "*.Cu" "*.Mask")
			(remove_unused_layers no)
			(net "GND")
			(clearance 0.1524)
			(thermal_gap 0.1524)
		)
		(pad "4" thru_hole circle
			(at -3.50012 0)
			(size 0.762 0.762)
			(drill 0.5588)
			(layers "*.Cu" "*.Mask")
			(remove_unused_layers no)
			(net "GND")
			(clearance 0.1524)
			(thermal_gap 0.1524)
		)
		(pad "5" thru_hole circle
			(at -2.500122 2.500122)
			(size 0.762 0.762)
			(drill 0.5588)
			(layers "*.Cu" "*.Mask")
			(remove_unused_layers no)
			(net "GND")
			(clearance 0.1524)
			(thermal_gap 0.1524)
		)
		(pad "6" thru_hole circle
			(at 0 3.50012)
			(size 0.762 0.762)
			(drill 0.5588)
			(layers "*.Cu" "*.Mask")
			(remove_unused_layers no)
			(net "GND")
			(clearance 0.1524)
			(thermal_gap 0.1524)
		)
		(pad "7" thru_hole circle
			(at 2.500122 2.500122)
			(size 0.762 0.762)
			(drill 0.5588)
			(layers "*.Cu" "*.Mask")
			(remove_unused_layers no)
			(net "GND")
			(clearance 0.1524)
			(thermal_gap 0.1524)
		)
		(pad "8" thru_hole circle
			(at 3.50012 0)
			(size 0.762 0.762)
			(drill 0.5588)
			(layers "*.Cu" "*.Mask")
			(remove_unused_layers no)
			(net "GND")
			(clearance 0.1524)
			(thermal_gap 0.1524)
		)
		(pad "9" thru_hole circle
			(at 2.500122 -2.500122)
			(size 0.762 0.762)
			(drill 0.5588)
			(layers "*.Cu" "*.Mask")
			(remove_unused_layers no)
			(net "GND")
			(clearance 0.1524)
			(thermal_gap 0.1524)
		)
		(zone
			(layers "F.Cu" "B.Cu" "In1.Cu" "In2.Cu" "In3.Cu" "In4.Cu" "In5.Cu" "In6.Cu"
				"In7.Cu" "In8.Cu"
			)
			(hatch none 0.5)
			(connect_pads
				(clearance 0)
			)
			(min_thickness 0.25)
			(keepout
				(tracks not_allowed)
				(vias allowed)
				(pads allowed)
				(copperpour not_allowed)
				(footprints allowed)
			)
			(placement
				(enabled no)
				(sheetname "")
			)
			(fill
				(thermal_gap 0.5)
				(thermal_bridge_width 0.5)
				(island_removal_mode 0)
			)
			(polygon
				(pts
					(arc
						(start 427.514512 -104.549956)
						(mid 422.485312 -104.549956)
						(end 427.514512 -104.549956)
					)
				)
			)
		)
	)
	(footprint ""
		(layer "F.Cu")
		(at 414.02 -41.529 180)
		(property "Reference" "R5928"
			(at 0 0 180)
			(layer "F.SilkS")
			(hide yes)
			(effects
				(font
					(size 1.27 1.27)
				)
			)
		)
		(property "Value" ""
			(at 0 0 180)
			(layer "F.Fab")
			(effects
				(font
					(size 1.27 1.27)
				)
			)
		)
		(duplicate_pad_numbers_are_jumpers no)
		(fp_line
			(start 0.7874 0.4064)
			(end -0.7874 0.4064)
			(stroke
				(width 0.1524)
				(type default)
			)
			(layer "F.SilkS")
		)
		(fp_line
			(start 0.7874 -0.4064)
			(end 0.7874 0.4064)
			(stroke
				(width 0.1524)
				(type default)
			)
			(layer "F.SilkS")
		)
		(fp_line
			(start -0.7874 0.4064)
			(end -0.7874 -0.4064)
			(stroke
				(width 0.1524)
				(type default)
			)
			(layer "F.SilkS")
		)
		(fp_line
			(start -0.7874 -0.4064)
			(end 0.7874 -0.4064)
			(stroke
				(width 0.1524)
				(type default)
			)
			(layer "F.SilkS")
		)
		(fp_line
			(start 0.67945 0.3048)
			(end 0.120396 0.3048)
			(stroke
				(width 0.1)
				(type default)
			)
			(layer "F.Fab")
		)
		(fp_line
			(start 0.67945 -0.3048)
			(end 0.67945 0.3048)
			(stroke
				(width 0.1)
				(type default)
			)
			(layer "F.Fab")
		)
		(fp_line
			(start 0.12065 -0.2794)
			(end 0.12065 -0.3048)
			(stroke
				(width 0.1)
				(type default)
			)
			(layer "F.Fab")
		)
		(fp_line
			(start 0.12065 -0.3048)
			(end 0.67945 -0.3048)
			(stroke
				(width 0.1)
				(type default)
			)
			(layer "F.Fab")
		)
		(fp_line
			(start 0.120396 0.3048)
			(end 0.120396 0.2794)
			(stroke
				(width 0.1)
				(type default)
			)
			(layer "F.Fab")
		)
		(fp_line
			(start 0.120396 0.2794)
			(end -0.12065 0.2794)
			(stroke
				(width 0.1)
				(type default)
			)
			(layer "F.Fab")
		)
		(fp_line
			(start -0.12065 0.3048)
			(end -0.67945 0.3048)
			(stroke
				(width 0.1)
				(type default)
			)
			(layer "F.Fab")
		)
		(fp_line
			(start -0.12065 0.2794)
			(end -0.12065 0.3048)
			(stroke
				(width 0.1)
				(type default)
			)
			(layer "F.Fab")
		)
		(fp_line
			(start -0.12065 -0.2794)
			(end 0.12065 -0.2794)
			(stroke
				(width 0.1)
				(type default)
			)
			(layer "F.Fab")
		)
		(fp_line
			(start -0.12065 -0.305054)
			(end -0.12065 -0.2794)
			(stroke
				(width 0.1)
				(type default)
			)
			(layer "F.Fab")
		)
		(fp_line
			(start -0.67945 0.3048)
			(end -0.67945 -0.305054)
			(stroke
				(width 0.1)
				(type default)
			)
			(layer "F.Fab")
		)
		(fp_line
			(start -0.67945 -0.305054)
			(end -0.12065 -0.305054)
			(stroke
				(width 0.1)
				(type default)
			)
			(layer "F.Fab")
		)
		(pad "1" smd circle
			(at -0.40005 0 180)
			(size 0 0)
			(layers "F.Cu" "F.Mask" "F.Paste")
			(net "PRSNT_FAN_BP1_N")
		)
		(pad "2" smd circle
			(at 0.40005 0 180)
			(size 0 0)
			(layers "F.Cu" "F.Mask" "F.Paste")
			(net "PRSNT_FAN_BP1_R_N")
		)
	)
	(footprint ""
		(layer "F.Cu")
		(at 450.41312 -87.36838 180)
		(property "Reference" "R394"
			(at 0 0 180)
			(layer "F.SilkS")
			(hide yes)
			(effects
				(font
					(size 1.27 1.27)
				)
			)
		)
		(property "Value" ""
			(at 0 0 180)
			(layer "F.Fab")
			(effects
				(font
					(size 1.27 1.27)
				)
			)
		)
		(duplicate_pad_numbers_are_jumpers no)
		(fp_line
			(start 0.7874 0.4064)
			(end -0.7874 0.4064)
			(stroke
				(width 0.1524)
				(type default)
			)
			(layer "F.SilkS")
		)
		(fp_line
			(start 0.7874 -0.4064)
			(end 0.7874 0.4064)
			(stroke
				(width 0.1524)
				(type default)
			)
			(layer "F.SilkS")
		)
		(fp_line
			(start -0.7874 0.4064)
			(end -0.7874 -0.4064)
			(stroke
				(width 0.1524)
				(type default)
			)
			(layer "F.SilkS")
		)
		(fp_line
			(start -0.7874 -0.4064)
			(end 0.7874 -0.4064)
			(stroke
				(width 0.1524)
				(type default)
			)
			(layer "F.SilkS")
		)
		(fp_line
			(start 0.67945 0.3048)
			(end 0.120396 0.3048)
			(stroke
				(width 0.1)
				(type default)
			)
			(layer "F.Fab")
		)
		(fp_line
			(start 0.67945 -0.3048)
			(end 0.67945 0.3048)
			(stroke
				(width 0.1)
				(type default)
			)
			(layer "F.Fab")
		)
		(fp_line
			(start 0.12065 -0.2794)
			(end 0.12065 -0.3048)
			(stroke
				(width 0.1)
				(type default)
			)
			(layer "F.Fab")
		)
		(fp_line
			(start 0.12065 -0.3048)
			(end 0.67945 -0.3048)
			(stroke
				(width 0.1)
				(type default)
			)
			(layer "F.Fab")
		)
		(fp_line
			(start 0.120396 0.3048)
			(end 0.120396 0.2794)
			(stroke
				(width 0.1)
				(type default)
			)
			(layer "F.Fab")
		)
		(fp_line
			(start 0.120396 0.2794)
			(end -0.12065 0.2794)
			(stroke
				(width 0.1)
				(type default)
			)
			(layer "F.Fab")
		)
		(fp_line
			(start -0.12065 0.3048)
			(end -0.67945 0.3048)
			(stroke
				(width 0.1)
				(type default)
			)
			(layer "F.Fab")
		)
		(fp_line
			(start -0.12065 0.2794)
			(end -0.12065 0.3048)
			(stroke
				(width 0.1)
				(type default)
			)
			(layer "F.Fab")
		)
		(fp_line
			(start -0.12065 -0.2794)
			(end 0.12065 -0.2794)
			(stroke
				(width 0.1)
				(type default)
			)
			(layer "F.Fab")
		)
		(fp_line
			(start -0.12065 -0.305054)
			(end -0.12065 -0.2794)
			(stroke
				(width 0.1)
				(type default)
			)
			(layer "F.Fab")
		)
		(fp_line
			(start -0.67945 0.3048)
			(end -0.67945 -0.305054)
			(stroke
				(width 0.1)
				(type default)
			)
			(layer "F.Fab")
		)
		(fp_line
			(start -0.67945 -0.305054)
			(end -0.12065 -0.305054)
			(stroke
				(width 0.1)
				(type default)
			)
			(layer "F.Fab")
		)
		(pad "1" smd circle
			(at -0.40005 0 180)
			(size 0 0)
			(layers "F.Cu" "F.Mask" "F.Paste")
			(net "P12V_HPDB_PWRGD")
		)
		(pad "2" smd circle
			(at 0.40005 0 180)
			(size 0 0)
			(layers "F.Cu" "F.Mask" "F.Paste")
			(net "P3V3_HPDB_EN")
		)
	)
	(footprint ""
		(layer "F.Cu")
		(at 397.637 -99.06)
		(property "Reference" "PC33"
			(at -8.1026 -4.79933 0)
			(unlocked yes)
			(layer "F.SilkS")
			(effects
				(font
					(size 0.7874 0.5842)
					(thickness 0.1524)
				)
				(justify left)
			)
		)
		(property "Value" ""
			(at 0 0 0)
			(layer "F.Fab")
			(effects
				(font
					(size 1.27 1.27)
				)
			)
		)
		(duplicate_pad_numbers_are_jumpers no)
		(fp_line
			(start -9.253728 3.750056)
			(end 9.249918 3.750056)
			(stroke
				(width 0.1524)
				(type default)
			)
			(layer "F.SilkS")
		)
		(fp_line
			(start 0 3.750056)
			(end -9.253728 3.750056)
			(stroke
				(width 0.1524)
				(type default)
			)
			(layer "F.SilkS")
		)
		(fp_circle
			(center 0 3.750056)
			(end 9.249918 3.750056)
			(stroke
				(width 0.1524)
				(type default)
			)
			(fill no)
			(layer "F.SilkS")
		)
		(fp_poly
			(pts
				(arc
					(start 9.249918 3.750056)
					(mid 0 12.999974)
					(end -9.249918 3.750056)
				)
			)
			(stroke
				(width 0)
				(type default)
			)
			(fill yes)
			(layer "F.SilkS")
		)
		(fp_circle
			(center 0 3.750056)
			(end 9.249918 3.750056)
			(stroke
				(width 0.1)
				(type default)
			)
			(fill no)
			(layer "F.Fab")
		)
		(pad "1" thru_hole rect
			(at 0 0)
			(size 1.778 1.778)
			(drill 1.27)
			(layers "*.Cu" "*.Mask")
			(remove_unused_layers no)
			(net "P52V_HS1")
			(clearance 0)
			(padstack
				(mode front_inner_back)
				(layer "Inner"
					(shape circle)
					(size 1.778 1.778)
					(clearance 0)
				)
				(layer "B.Cu"
					(shape rect)
					(size 1.778 1.778)
					(clearance 0)
				)
			)
		)
		(pad "2" thru_hole circle
			(at 0 7.500112)
			(size 1.778 1.778)
			(drill 1.27)
			(layers "*.Cu" "*.Mask")
			(remove_unused_layers no)
			(net "GND")
			(clearance 0)
		)
	)
	(footprint ""
		(layer "F.Cu")
		(at 42.36339 -139.7)
		(property "Reference" "PC34"
			(at 6.104128 -4.407408 0)
			(unlocked yes)
			(layer "F.SilkS")
			(effects
				(font
					(size 0.7874 0.5842)
					(thickness 0.1524)
				)
				(justify left)
			)
		)
		(property "Value" ""
			(at 0 0 0)
			(layer "F.Fab")
			(effects
				(font
					(size 1.27 1.27)
				)
			)
		)
		(duplicate_pad_numbers_are_jumpers no)
		(fp_line
			(start -9.253728 3.750056)
			(end 9.249918 3.750056)
			(stroke
				(width 0.1524)
				(type default)
			)
			(layer "F.SilkS")
		)
		(fp_line
			(start 0 3.750056)
			(end -9.253728 3.750056)
			(stroke
				(width 0.1524)
				(type default)
			)
			(layer "F.SilkS")
		)
		(fp_circle
			(center 0 3.750056)
			(end 9.249918 3.750056)
			(stroke
				(width 0.1524)
				(type default)
			)
			(fill no)
			(layer "F.SilkS")
		)
		(fp_poly
			(pts
				(arc
					(start 9.249918 3.750056)
					(mid 0 12.999974)
					(end -9.249918 3.750056)
				)
			)
			(stroke
				(width 0)
				(type default)
			)
			(fill yes)
			(layer "F.SilkS")
		)
		(fp_circle
			(center 0 3.750056)
			(end 9.249918 3.750056)
			(stroke
				(width 0.1)
				(type default)
			)
			(fill no)
			(layer "F.Fab")
		)
		(pad "1" thru_hole rect
			(at 0 0)
			(size 1.778 1.778)
			(drill 1.27)
			(layers "*.Cu" "*.Mask")
			(remove_unused_layers no)
			(net "P52V_HS2")
			(clearance 0)
			(padstack
				(mode front_inner_back)
				(layer "Inner"
					(shape circle)
					(size 1.778 1.778)
					(clearance 0)
				)
				(layer "B.Cu"
					(shape rect)
					(size 1.778 1.778)
					(clearance 0)
				)
			)
		)
		(pad "2" thru_hole circle
			(at 0 7.500112)
			(size 1.778 1.778)
			(drill 1.27)
			(layers "*.Cu" "*.Mask")
			(remove_unused_layers no)
			(net "GND")
			(clearance 0)
		)
	)
	(footprint ""
		(layer "F.Cu")
		(at 80.000094 -142.499842 180)
		(property "Reference" "H3"
			(at 0.752094 -5.366512 0)
			(unlocked yes)
			(layer "F.SilkS")
			(effects
				(font
					(size 0.7874 0.5842)
					(thickness 0.1524)
				)
				(justify left)
			)
		)
		(property "Value" ""
			(at 0 0 180)
			(layer "F.Fab")
			(effects
				(font
					(size 1.27 1.27)
				)
			)
		)
		(duplicate_pad_numbers_are_jumpers no)
		(pad "1" thru_hole oval
			(at 0 0 180)
			(size 9.017 14.0208)
			(drill 3.0226
				(offset 0 2.499868)
			)
			(layers "*.Cu" "*.Mask")
			(remove_unused_layers no)
			(net "GND")
			(clearance -1.500378)
			(padstack
				(mode front_inner_back)
				(layer "Inner"
					(shape circle)
					(size 0 0)
					(clearance 0)
				)
				(layer "B.Cu"
					(shape oval)
					(size 9.017 14.0208)
					(offset 0 2.499868)
					(clearance -1.500378)
				)
			)
		)
	)
	(footprint ""
		(layer "F.Cu")
		(at 262.382 -51.181 180)
		(property "Reference" "U24"
			(at 4.0894 -1.04267 0)
			(unlocked yes)
			(layer "F.SilkS")
			(effects
				(font
					(size 0.7874 0.5842)
					(thickness 0.1524)
				)
				(justify left)
			)
		)
		(property "Value" ""
			(at 0 0 180)
			(layer "F.Fab")
			(effects
				(font
					(size 1.27 1.27)
				)
			)
		)
		(duplicate_pad_numbers_are_jumpers no)
		(fp_line
			(start 1.603248 1.500124)
			(end -1.603248 1.500124)
			(stroke
				(width 0.1524)
				(type default)
			)
			(layer "F.SilkS")
		)
		(fp_line
			(start 1.603248 -1.500124)
			(end 1.603248 1.500124)
			(stroke
				(width 0.1524)
				(type default)
			)
			(layer "F.SilkS")
		)
		(fp_line
			(start -1.603248 1.500124)
			(end -1.603248 -1.500124)
			(stroke
				(width 0.1524)
				(type default)
			)
			(layer "F.SilkS")
		)
		(fp_line
			(start -1.603248 -1.500124)
			(end 1.603248 -1.500124)
			(stroke
				(width 0.1524)
				(type default)
			)
			(layer "F.SilkS")
		)
		(fp_line
			(start 1.249934 0.219964)
			(end 1.249934 -0.219964)
			(stroke
				(width 0.1)
				(type default)
			)
			(layer "F.Fab")
		)
		(fp_line
			(start 1.249934 -0.219964)
			(end 0.700024 -0.219964)
			(stroke
				(width 0.1)
				(type default)
			)
			(layer "F.Fab")
		)
		(fp_line
			(start 0.700024 1.500124)
			(end 0.700024 0.219964)
			(stroke
				(width 0.1)
				(type default)
			)
			(layer "F.Fab")
		)
		(fp_line
			(start 0.700024 0.219964)
			(end 1.249934 0.219964)
			(stroke
				(width 0.1)
				(type default)
			)
			(layer "F.Fab")
		)
		(fp_line
			(start 0.700024 -0.219964)
			(end 0.700024 -1.500124)
			(stroke
				(width 0.1)
				(type default)
			)
			(layer "F.Fab")
		)
		(fp_line
			(start 0.700024 -1.500124)
			(end -0.700024 -1.500124)
			(stroke
				(width 0.1)
				(type default)
			)
			(layer "F.Fab")
		)
		(fp_line
			(start -0.6985 0.729996)
			(end -1.249934 0.729996)
			(stroke
				(width 0.1)
				(type default)
			)
			(layer "F.Fab")
		)
		(fp_line
			(start -0.6985 -0.729996)
			(end -0.6985 0.729996)
			(stroke
				(width 0.1)
				(type default)
			)
			(layer "F.Fab")
		)
		(fp_line
			(start -0.700024 1.500124)
			(end 0.700024 1.500124)
			(stroke
				(width 0.1)
				(type default)
			)
			(layer "F.Fab")
		)
		(fp_line
			(start -0.700024 1.169924)
			(end -0.700024 1.500124)
			(stroke
				(width 0.1)
				(type default)
			)
			(layer "F.Fab")
		)
		(fp_line
			(start -0.700024 -1.169924)
			(end -1.249934 -1.169924)
			(stroke
				(width 0.1)
				(type default)
			)
			(layer "F.Fab")
		)
		(fp_line
			(start -0.700024 -1.500124)
			(end -0.700024 -1.169924)
			(stroke
				(width 0.1)
				(type default)
			)
			(layer "F.Fab")
		)
		(fp_line
			(start -1.249934 1.169924)
			(end -0.700024 1.169924)
			(stroke
				(width 0.1)
				(type default)
			)
			(layer "F.Fab")
		)
		(fp_line
			(start -1.249934 0.729996)
			(end -1.249934 1.169924)
			(stroke
				(width 0.1)
				(type default)
			)
			(layer "F.Fab")
		)
		(fp_line
			(start -1.249934 -0.729996)
			(end -0.6985 -0.729996)
			(stroke
				(width 0.1)
				(type default)
			)
			(layer "F.Fab")
		)
		(fp_line
			(start -1.249934 -1.169924)
			(end -1.249934 -0.729996)
			(stroke
				(width 0.1)
				(type default)
			)
			(layer "F.Fab")
		)
		(fp_rect
			(start -0.700024 1.500124)
			(end 0.700024 -1.500124)
			(stroke
				(width 0)
				(type default)
			)
			(fill no)
			(layer "F.Fab")
		)
		(pad "D" smd rect
			(at 0.999998 0 90)
			(size 0.8128 0.9144)
			(layers "F.Cu" "F.Mask" "F.Paste")
			(net "GPU_HSC1_BUF_EN")
		)
		(pad "G" smd rect
			(at -0.999998 -0.94996 90)
			(size 0.8128 0.9144)
			(layers "F.Cu" "F.Mask" "F.Paste")
			(net "GPU_HSC1_BUF_EN_N")
		)
		(pad "S" smd rect
			(at -0.999998 0.94996 90)
			(size 0.8128 0.9144)
			(layers "F.Cu" "F.Mask" "F.Paste")
			(net "GND")
		)
	)
	(footprint ""
		(layer "F.Cu")
		(at 451.1802 -81.9658)
		(property "Reference" "PC52"
			(at 0 0 0)
			(layer "F.SilkS")
			(hide yes)
			(effects
				(font
					(size 1.27 1.27)
				)
			)
		)
		(property "Value" ""
			(at 0 0 0)
			(layer "F.Fab")
			(effects
				(font
					(size 1.27 1.27)
				)
			)
		)
		(duplicate_pad_numbers_are_jumpers no)
		(fp_line
			(start -0.7874 -0.4064)
			(end 0.7874 -0.4064)
			(stroke
				(width 0.1524)
				(type default)
			)
			(layer "F.SilkS")
		)
		(fp_line
			(start -0.7874 0.4064)
			(end -0.7874 -0.4064)
			(stroke
				(width 0.1524)
				(type default)
			)
			(layer "F.SilkS")
		)
		(fp_line
			(start 0.7874 -0.4064)
			(end 0.7874 0.4064)
			(stroke
				(width 0.1524)
				(type default)
			)
			(layer "F.SilkS")
		)
		(fp_line
			(start 0.7874 0.4064)
			(end -0.7874 0.4064)
			(stroke
				(width 0.1524)
				(type default)
			)
			(layer "F.SilkS")
		)
		(fp_line
			(start -0.67945 -0.305054)
			(end -0.12065 -0.305054)
			(stroke
				(width 0.1)
				(type default)
			)
			(layer "F.Fab")
		)
		(fp_line
			(start -0.67945 0.3048)
			(end -0.67945 -0.305054)
			(stroke
				(width 0.1)
				(type default)
			)
			(layer "F.Fab")
		)
		(fp_line
			(start -0.12065 -0.305054)
			(end -0.12065 -0.2794)
			(stroke
				(width 0.1)
				(type default)
			)
			(layer "F.Fab")
		)
		(fp_line
			(start -0.12065 -0.2794)
			(end 0.12065 -0.2794)
			(stroke
				(width 0.1)
				(type default)
			)
			(layer "F.Fab")
		)
		(fp_line
			(start -0.12065 0.2794)
			(end -0.12065 0.3048)
			(stroke
				(width 0.1)
				(type default)
			)
			(layer "F.Fab")
		)
		(fp_line
			(start -0.12065 0.3048)
			(end -0.67945 0.3048)
			(stroke
				(width 0.1)
				(type default)
			)
			(layer "F.Fab")
		)
		(fp_line
			(start 0.120396 0.2794)
			(end -0.12065 0.2794)
			(stroke
				(width 0.1)
				(type default)
			)
			(layer "F.Fab")
		)
		(fp_line
			(start 0.120396 0.3048)
			(end 0.120396 0.2794)
			(stroke
				(width 0.1)
				(type default)
			)
			(layer "F.Fab")
		)
		(fp_line
			(start 0.12065 -0.3048)
			(end 0.67945 -0.3048)
			(stroke
				(width 0.1)
				(type default)
			)
			(layer "F.Fab")
		)
		(fp_line
			(start 0.12065 -0.2794)
			(end 0.12065 -0.3048)
			(stroke
				(width 0.1)
				(type default)
			)
			(layer "F.Fab")
		)
		(fp_line
			(start 0.67945 -0.3048)
			(end 0.67945 0.3048)
			(stroke
				(width 0.1)
				(type default)
			)
			(layer "F.Fab")
		)
		(fp_line
			(start 0.67945 0.3048)
			(end 0.120396 0.3048)
			(stroke
				(width 0.1)
				(type default)
			)
			(layer "F.Fab")
		)
		(pad "1" smd circle
			(at -0.40005 0)
			(size 0 0)
			(layers "F.Cu" "F.Mask" "F.Paste")
			(net "SW_P3V3_HPDB_BT_R")
		)
		(pad "2" smd circle
			(at 0.40005 0)
			(size 0 0)
			(layers "F.Cu" "F.Mask" "F.Paste")
			(net "SW_P3V3_HPDB_PH")
		)
	)
	(footprint ""
		(layer "F.Cu")
		(at 306.7304 -68.199)
		(property "Reference" "PR6962"
			(at 0 0 0)
			(layer "F.SilkS")
			(hide yes)
			(effects
				(font
					(size 1.27 1.27)
				)
			)
		)
		(property "Value" ""
			(at 0 0 0)
			(layer "F.Fab")
			(effects
				(font
					(size 1.27 1.27)
				)
			)
		)
		(duplicate_pad_numbers_are_jumpers no)
		(fp_line
			(start -1.2954 -0.5842)
			(end 1.2954 -0.5842)
			(stroke
				(width 0.1524)
				(type default)
			)
			(layer "F.SilkS")
		)
		(fp_line
			(start -1.2954 0.5842)
			(end -1.2954 -0.5842)
			(stroke
				(width 0.1524)
				(type default)
			)
			(layer "F.SilkS")
		)
		(fp_line
			(start 1.2954 -0.5842)
			(end 1.2954 0.5842)
			(stroke
				(width 0.1524)
				(type default)
			)
			(layer "F.SilkS")
		)
		(fp_line
			(start 1.2954 0.5842)
			(end -1.2954 0.5842)
			(stroke
				(width 0.1524)
				(type default)
			)
			(layer "F.SilkS")
		)
		(fp_line
			(start -1.1938 -0.406654)
			(end -0.8636 -0.406654)
			(stroke
				(width 0.1)
				(type default)
			)
			(layer "F.Fab")
		)
		(fp_line
			(start -1.1938 0.4064)
			(end -1.1938 -0.406654)
			(stroke
				(width 0.1)
				(type default)
			)
			(layer "F.Fab")
		)
		(fp_line
			(start -0.8636 -0.4572)
			(end 0.8636 -0.4572)
			(stroke
				(width 0.1)
				(type default)
			)
			(layer "F.Fab")
		)
		(fp_line
			(start -0.8636 -0.406654)
			(end -0.8636 -0.4572)
			(stroke
				(width 0.1)
				(type default)
			)
			(layer "F.Fab")
		)
		(fp_line
			(start -0.8636 0.4064)
			(end -1.1938 0.4064)
			(stroke
				(width 0.1)
				(type default)
			)
			(layer "F.Fab")
		)
		(fp_line
			(start -0.8636 0.4318)
			(end -0.8636 0.4064)
			(stroke
				(width 0.1)
				(type default)
			)
			(layer "F.Fab")
		)
		(fp_line
			(start -0.8636 0.4572)
			(end -0.8636 0.4318)
			(stroke
				(width 0.1)
				(type default)
			)
			(layer "F.Fab")
		)
		(fp_line
			(start 0.8636 -0.4572)
			(end 0.8636 -0.406654)
			(stroke
				(width 0.1)
				(type default)
			)
			(layer "F.Fab")
		)
		(fp_line
			(start 0.8636 -0.406654)
			(end 1.1938 -0.406654)
			(stroke
				(width 0.1)
				(type default)
			)
			(layer "F.Fab")
		)
		(fp_line
			(start 0.8636 0.4064)
			(end 0.8636 0.4572)
			(stroke
				(width 0.1)
				(type default)
			)
			(layer "F.Fab")
		)
		(fp_line
			(start 0.8636 0.4572)
			(end -0.8636 0.4572)
			(stroke
				(width 0.1)
				(type default)
			)
			(layer "F.Fab")
		)
		(fp_line
			(start 1.1938 -0.406654)
			(end 1.1938 0.4064)
			(stroke
				(width 0.1)
				(type default)
			)
			(layer "F.Fab")
		)
		(fp_line
			(start 1.1938 0.4064)
			(end 0.8636 0.4064)
			(stroke
				(width 0.1)
				(type default)
			)
			(layer "F.Fab")
		)
		(pad "1" smd rect
			(at -0.7366 0 270)
			(size 0.7112 0.8128)
			(layers "F.Cu" "F.Mask" "F.Paste")
			(net "P52V_HS_4287_ADC_N")
		)
		(pad "2" smd rect
			(at 0.7366 0 270)
			(size 0.7112 0.8128)
			(layers "F.Cu" "F.Mask" "F.Paste")
			(net "P52V_HS1_SENSE_N_R1")
		)
	)
	(footprint ""
		(layer "F.Cu")
		(at 323.13626 -52.0954 180)
		(property "Reference" "PQ34"
			(at -9.628886 -3.917188 0)
			(unlocked yes)
			(layer "F.SilkS")
			(effects
				(font
					(size 0.7874 0.5842)
					(thickness 0.1524)
				)
				(justify left)
			)
		)
		(property "Value" ""
			(at 0 0 180)
			(layer "F.Fab")
			(effects
				(font
					(size 1.27 1.27)
				)
			)
		)
		(duplicate_pad_numbers_are_jumpers no)
		(fp_line
			(start 7.649972 4.99999)
			(end 7.649972 -4.99999)
			(stroke
				(width 0.1524)
				(type default)
			)
			(layer "F.SilkS")
		)
		(fp_line
			(start 7.649972 -4.99999)
			(end 7.630414 -4.99999)
			(stroke
				(width 0.1524)
				(type default)
			)
			(layer "F.SilkS")
		)
		(fp_line
			(start 7.630414 4.99999)
			(end 7.649972 4.99999)
			(stroke
				(width 0.1524)
				(type default)
			)
			(layer "F.SilkS")
		)
		(fp_line
			(start 5.115814 -4.99999)
			(end -7.649972 -4.99999)
			(stroke
				(width 0.1524)
				(type default)
			)
			(layer "F.SilkS")
		)
		(fp_line
			(start -7.649972 4.99999)
			(end 5.115814 4.99999)
			(stroke
				(width 0.1524)
				(type default)
			)
			(layer "F.SilkS")
		)
		(fp_line
			(start -7.649972 3.3274)
			(end -7.649972 4.99999)
			(stroke
				(width 0.1524)
				(type default)
			)
			(layer "F.SilkS")
		)
		(fp_line
			(start -7.649972 -1.7526)
			(end -7.649972 1.7526)
			(stroke
				(width 0.1524)
				(type default)
			)
			(layer "F.SilkS")
		)
		(fp_line
			(start -7.649972 -4.99999)
			(end -7.649972 -3.3274)
			(stroke
				(width 0.1524)
				(type default)
			)
			(layer "F.SilkS")
		)
		(fp_line
			(start 7.649972 4.99999)
			(end 7.649972 -4.99999)
			(stroke
				(width 0.1)
				(type default)
			)
			(layer "F.Fab")
		)
		(fp_line
			(start 7.649972 -4.99999)
			(end -7.649972 -4.99999)
			(stroke
				(width 0.1)
				(type default)
			)
			(layer "F.Fab")
		)
		(fp_line
			(start -7.649972 4.99999)
			(end 7.649972 4.99999)
			(stroke
				(width 0.1)
				(type default)
			)
			(layer "F.Fab")
		)
		(fp_line
			(start -7.649972 -4.99999)
			(end -7.649972 4.99999)
			(stroke
				(width 0.1)
				(type default)
			)
			(layer "F.Fab")
		)
		(pad "D" smd circle
			(at 2.15011 0 180)
			(size 0 0)
			(layers "F.Cu" "F.Mask" "F.Paste")
			(net "P52V_HS1_DRAIN_1")
		)
		(pad "G" smd rect
			(at -7.050024 -2.54 90)
			(size 1.3208 3.0988)
			(layers "F.Cu" "F.Mask" "F.Paste")
			(net "P52V_HS1_GATE3")
		)
		(pad "S" smd rect
			(at -7.050024 2.54 90)
			(size 1.3208 3.0988)
			(layers "F.Cu" "F.Mask" "F.Paste")
			(net "P52V_HS1")
		)
		(zone
			(layer "F.Cu")
			(hatch none 0.5)
			(connect_pads
				(clearance 0)
			)
			(min_thickness 0.25)
			(keepout
				(tracks not_allowed)
				(vias allowed)
				(pads allowed)
				(copperpour not_allowed)
				(footprints allowed)
			)
			(placement
				(enabled no)
				(sheetname "")
			)
			(fill
				(thermal_gap 0.5)
				(thermal_bridge_width 0.5)
				(island_removal_mode 0)
			)
			(polygon
				(pts
					(xy 317.95466 -47.117) (xy 330.78166 -47.117) (xy 330.78166 -48.8442) (xy 328.57186 -48.8442) (xy 328.57186 -50.2666)
					(xy 330.78166 -50.2666) (xy 330.78166 -53.9242) (xy 328.57186 -53.9242) (xy 328.57186 -55.3466)
					(xy 330.78166 -55.3466) (xy 330.78166 -57.0738) (xy 317.95466 -57.0738) (xy 317.95466 -55.9054)
					(xy 324.15226 -55.9054) (xy 324.15226 -48.2854) (xy 317.95466 -48.2854)
				)
			)
		)
	)
	(footprint ""
		(layer "F.Cu")
		(at 402.717 -17.018)
		(property "Reference" "PR101"
			(at -7.5946 1.29667 0)
			(unlocked yes)
			(layer "F.SilkS")
			(effects
				(font
					(size 0.7874 0.5842)
					(thickness 0.1524)
				)
				(justify left)
			)
		)
		(property "Value" ""
			(at 0 0 0)
			(layer "F.Fab")
			(effects
				(font
					(size 1.27 1.27)
				)
			)
		)
		(duplicate_pad_numbers_are_jumpers no)
		(fp_line
			(start -3.62712 -1.8796)
			(end -3.62712 1.8796)
			(stroke
				(width 0.1524)
				(type default)
			)
			(layer "F.SilkS")
		)
		(fp_line
			(start -3.62712 1.8796)
			(end 3.62712 1.8796)
			(stroke
				(width 0.1524)
				(type default)
			)
			(layer "F.SilkS")
		)
		(fp_line
			(start 3.62712 -1.8796)
			(end -3.62712 -1.8796)
			(stroke
				(width 0.1524)
				(type default)
			)
			(layer "F.SilkS")
		)
		(fp_line
			(start 3.62712 1.8796)
			(end 3.62712 -1.8796)
			(stroke
				(width 0.1524)
				(type default)
			)
			(layer "F.SilkS")
		)
		(fp_line
			(start -3.299968 -1.700022)
			(end -3.299968 1.700022)
			(stroke
				(width 0.1)
				(type default)
			)
			(layer "F.Fab")
		)
		(fp_line
			(start -3.299968 1.700022)
			(end 3.299968 1.700022)
			(stroke
				(width 0.1)
				(type default)
			)
			(layer "F.Fab")
		)
		(fp_line
			(start 3.299968 -1.700022)
			(end -3.299968 -1.700022)
			(stroke
				(width 0.1)
				(type default)
			)
			(layer "F.Fab")
		)
		(fp_line
			(start 3.299968 1.700022)
			(end 3.299968 -1.700022)
			(stroke
				(width 0.1)
				(type default)
			)
			(layer "F.Fab")
		)
		(pad "1" smd rect
			(at -2.70002 0)
			(size 1.6002 3.5052)
			(layers "F.Cu" "F.Mask" "F.Paste")
			(net "P52V_HS1_EN_DISCHARGE_VBE_R")
		)
		(pad "2" smd rect
			(at 2.70002 0)
			(size 1.6002 3.5052)
			(layers "F.Cu" "F.Mask" "F.Paste")
			(net "GND")
		)
	)
	(footprint ""
		(layer "F.Cu")
		(at 469.179656 -107.502452 90)
		(property "Reference" "R85"
			(at 0 0 90)
			(layer "F.SilkS")
			(hide yes)
			(effects
				(font
					(size 1.27 1.27)
				)
			)
		)
		(property "Value" ""
			(at 0 0 90)
			(layer "F.Fab")
			(effects
				(font
					(size 1.27 1.27)
				)
			)
		)
		(duplicate_pad_numbers_are_jumpers no)
		(fp_line
			(start 0.7874 -0.4064)
			(end 0.7874 0.4064)
			(stroke
				(width 0.1524)
				(type default)
			)
			(layer "F.SilkS")
		)
		(fp_line
			(start -0.7874 -0.4064)
			(end 0.7874 -0.4064)
			(stroke
				(width 0.1524)
				(type default)
			)
			(layer "F.SilkS")
		)
		(fp_line
			(start 0.7874 0.4064)
			(end -0.7874 0.4064)
			(stroke
				(width 0.1524)
				(type default)
			)
			(layer "F.SilkS")
		)
		(fp_line
			(start -0.7874 0.4064)
			(end -0.7874 -0.4064)
			(stroke
				(width 0.1524)
				(type default)
			)
			(layer "F.SilkS")
		)
		(fp_line
			(start -0.12065 -0.305054)
			(end -0.12065 -0.2794)
			(stroke
				(width 0.1)
				(type default)
			)
			(layer "F.Fab")
		)
		(fp_line
			(start -0.67945 -0.305054)
			(end -0.12065 -0.305054)
			(stroke
				(width 0.1)
				(type default)
			)
			(layer "F.Fab")
		)
		(fp_line
			(start 0.67945 -0.3048)
			(end 0.67945 0.3048)
			(stroke
				(width 0.1)
				(type default)
			)
			(layer "F.Fab")
		)
		(fp_line
			(start 0.12065 -0.3048)
			(end 0.67945 -0.3048)
			(stroke
				(width 0.1)
				(type default)
			)
			(layer "F.Fab")
		)
		(fp_line
			(start 0.12065 -0.2794)
			(end 0.12065 -0.3048)
			(stroke
				(width 0.1)
				(type default)
			)
			(layer "F.Fab")
		)
		(fp_line
			(start -0.12065 -0.2794)
			(end 0.12065 -0.2794)
			(stroke
				(width 0.1)
				(type default)
			)
			(layer "F.Fab")
		)
		(fp_line
			(start 0.120396 0.2794)
			(end -0.12065 0.2794)
			(stroke
				(width 0.1)
				(type default)
			)
			(layer "F.Fab")
		)
		(fp_line
			(start -0.12065 0.2794)
			(end -0.12065 0.3048)
			(stroke
				(width 0.1)
				(type default)
			)
			(layer "F.Fab")
		)
		(fp_line
			(start 0.67945 0.3048)
			(end 0.120396 0.3048)
			(stroke
				(width 0.1)
				(type default)
			)
			(layer "F.Fab")
		)
		(fp_line
			(start 0.120396 0.3048)
			(end 0.120396 0.2794)
			(stroke
				(width 0.1)
				(type default)
			)
			(layer "F.Fab")
		)
		(fp_line
			(start -0.12065 0.3048)
			(end -0.67945 0.3048)
			(stroke
				(width 0.1)
				(type default)
			)
			(layer "F.Fab")
		)
		(fp_line
			(start -0.67945 0.3048)
			(end -0.67945 -0.305054)
			(stroke
				(width 0.1)
				(type default)
			)
			(layer "F.Fab")
		)
		(pad "1" smd circle
			(at -0.40005 0 90)
			(size 0 0)
			(layers "F.Cu" "F.Mask" "F.Paste")
			(net "SMB_PDB_SDA")
		)
		(pad "2" smd circle
			(at 0.40005 0 90)
			(size 0 0)
			(layers "F.Cu" "F.Mask" "F.Paste")
			(net "SMB_PDB_R_SDA")
		)
	)
	(footprint ""
		(layer "F.Cu")
		(at 412.0134 -38.227 -90)
		(property "Reference" "R424"
			(at 0 0 270)
			(layer "F.SilkS")
			(hide yes)
			(effects
				(font
					(size 1.27 1.27)
				)
			)
		)
		(property "Value" ""
			(at 0 0 270)
			(layer "F.Fab")
			(effects
				(font
					(size 1.27 1.27)
				)
			)
		)
		(duplicate_pad_numbers_are_jumpers no)
		(fp_line
			(start -0.7874 0.4064)
			(end -0.7874 -0.4064)
			(stroke
				(width 0.1524)
				(type default)
			)
			(layer "F.SilkS")
		)
		(fp_line
			(start 0.7874 0.4064)
			(end -0.7874 0.4064)
			(stroke
				(width 0.1524)
				(type default)
			)
			(layer "F.SilkS")
		)
		(fp_line
			(start -0.7874 -0.4064)
			(end 0.7874 -0.4064)
			(stroke
				(width 0.1524)
				(type default)
			)
			(layer "F.SilkS")
		)
		(fp_line
			(start 0.7874 -0.4064)
			(end 0.7874 0.4064)
			(stroke
				(width 0.1524)
				(type default)
			)
			(layer "F.SilkS")
		)
		(fp_line
			(start -0.67945 0.3048)
			(end -0.67945 -0.305054)
			(stroke
				(width 0.1)
				(type default)
			)
			(layer "F.Fab")
		)
		(fp_line
			(start -0.12065 0.3048)
			(end -0.67945 0.3048)
			(stroke
				(width 0.1)
				(type default)
			)
			(layer "F.Fab")
		)
		(fp_line
			(start 0.120396 0.3048)
			(end 0.120396 0.2794)
			(stroke
				(width 0.1)
				(type default)
			)
			(layer "F.Fab")
		)
		(fp_line
			(start 0.67945 0.3048)
			(end 0.120396 0.3048)
			(stroke
				(width 0.1)
				(type default)
			)
			(layer "F.Fab")
		)
		(fp_line
			(start -0.12065 0.2794)
			(end -0.12065 0.3048)
			(stroke
				(width 0.1)
				(type default)
			)
			(layer "F.Fab")
		)
		(fp_line
			(start 0.120396 0.2794)
			(end -0.12065 0.2794)
			(stroke
				(width 0.1)
				(type default)
			)
			(layer "F.Fab")
		)
		(fp_line
			(start -0.12065 -0.2794)
			(end 0.12065 -0.2794)
			(stroke
				(width 0.1)
				(type default)
			)
			(layer "F.Fab")
		)
		(fp_line
			(start 0.12065 -0.2794)
			(end 0.12065 -0.3048)
			(stroke
				(width 0.1)
				(type default)
			)
			(layer "F.Fab")
		)
		(fp_line
			(start 0.12065 -0.3048)
			(end 0.67945 -0.3048)
			(stroke
				(width 0.1)
				(type default)
			)
			(layer "F.Fab")
		)
		(fp_line
			(start 0.67945 -0.3048)
			(end 0.67945 0.3048)
			(stroke
				(width 0.1)
				(type default)
			)
			(layer "F.Fab")
		)
		(fp_line
			(start -0.67945 -0.305054)
			(end -0.12065 -0.305054)
			(stroke
				(width 0.1)
				(type default)
			)
			(layer "F.Fab")
		)
		(fp_line
			(start -0.12065 -0.305054)
			(end -0.12065 -0.2794)
			(stroke
				(width 0.1)
				(type default)
			)
			(layer "F.Fab")
		)
		(pad "1" smd circle
			(at -0.40005 0 270)
			(size 0 0)
			(layers "F.Cu" "F.Mask" "F.Paste")
			(net "PWRGD_P52V_HS2_4287_PG_N")
		)
		(pad "2" smd circle
			(at 0.40005 0 270)
			(size 0 0)
			(layers "F.Cu" "F.Mask" "F.Paste")
			(net "PWRGD_P52V_HS2_4287_PG_R_N")
		)
	)
	(footprint ""
		(layer "F.Cu")
		(at 449.3514 -92.202)
		(property "Reference" "PC59"
			(at 0 0 0)
			(layer "F.SilkS")
			(hide yes)
			(effects
				(font
					(size 1.27 1.27)
				)
			)
		)
		(property "Value" ""
			(at 0 0 0)
			(layer "F.Fab")
			(effects
				(font
					(size 1.27 1.27)
				)
			)
		)
		(duplicate_pad_numbers_are_jumpers no)
		(fp_line
			(start -1.524 -0.762)
			(end 1.524 -0.762)
			(stroke
				(width 0.1524)
				(type default)
			)
			(layer "F.SilkS")
		)
		(fp_line
			(start -1.524 0.762)
			(end -1.524 -0.762)
			(stroke
				(width 0.1524)
				(type default)
			)
			(layer "F.SilkS")
		)
		(fp_line
			(start 1.524 -0.762)
			(end 1.524 0.762)
			(stroke
				(width 0.1524)
				(type default)
			)
			(layer "F.SilkS")
		)
		(fp_line
			(start 1.524 0.762)
			(end -1.524 0.762)
			(stroke
				(width 0.1524)
				(type default)
			)
			(layer "F.SilkS")
		)
		(fp_line
			(start -1.1049 -0.724916)
			(end -1.1049 0.724916)
			(stroke
				(width 0.1)
				(type default)
			)
			(layer "F.Fab")
		)
		(fp_line
			(start -1.1049 0.724916)
			(end 1.1049 0.724916)
			(stroke
				(width 0.1)
				(type default)
			)
			(layer "F.Fab")
		)
		(fp_line
			(start 1.1049 -0.724916)
			(end -1.1049 -0.724916)
			(stroke
				(width 0.1)
				(type default)
			)
			(layer "F.Fab")
		)
		(fp_line
			(start 1.1049 0.724916)
			(end 1.1049 -0.724916)
			(stroke
				(width 0.1)
				(type default)
			)
			(layer "F.Fab")
		)
		(pad "1" smd rect
			(at -0.889 0 180)
			(size 1.016 1.27)
			(layers "F.Cu" "F.Mask" "F.Paste")
			(net "SW_P3V3_HPDB_FLT")
		)
		(pad "2" smd rect
			(at 0.889 0 180)
			(size 1.016 1.27)
			(layers "F.Cu" "F.Mask" "F.Paste")
			(net "GND")
		)
	)
	(footprint ""
		(layer "F.Cu")
		(at 409.956 -42.037)
		(property "Reference" "R5912"
			(at 0 0 0)
			(layer "F.SilkS")
			(hide yes)
			(effects
				(font
					(size 1.27 1.27)
				)
			)
		)
		(property "Value" ""
			(at 0 0 0)
			(layer "F.Fab")
			(effects
				(font
					(size 1.27 1.27)
				)
			)
		)
		(duplicate_pad_numbers_are_jumpers no)
		(fp_line
			(start -0.7874 -0.4064)
			(end 0.7874 -0.4064)
			(stroke
				(width 0.1524)
				(type default)
			)
			(layer "F.SilkS")
		)
		(fp_line
			(start -0.7874 0.4064)
			(end -0.7874 -0.4064)
			(stroke
				(width 0.1524)
				(type default)
			)
			(layer "F.SilkS")
		)
		(fp_line
			(start 0.7874 -0.4064)
			(end 0.7874 0.4064)
			(stroke
				(width 0.1524)
				(type default)
			)
			(layer "F.SilkS")
		)
		(fp_line
			(start 0.7874 0.4064)
			(end -0.7874 0.4064)
			(stroke
				(width 0.1524)
				(type default)
			)
			(layer "F.SilkS")
		)
		(fp_line
			(start -0.67945 -0.305054)
			(end -0.12065 -0.305054)
			(stroke
				(width 0.1)
				(type default)
			)
			(layer "F.Fab")
		)
		(fp_line
			(start -0.67945 0.3048)
			(end -0.67945 -0.305054)
			(stroke
				(width 0.1)
				(type default)
			)
			(layer "F.Fab")
		)
		(fp_line
			(start -0.12065 -0.305054)
			(end -0.12065 -0.2794)
			(stroke
				(width 0.1)
				(type default)
			)
			(layer "F.Fab")
		)
		(fp_line
			(start -0.12065 -0.2794)
			(end 0.12065 -0.2794)
			(stroke
				(width 0.1)
				(type default)
			)
			(layer "F.Fab")
		)
		(fp_line
			(start -0.12065 0.2794)
			(end -0.12065 0.3048)
			(stroke
				(width 0.1)
				(type default)
			)
			(layer "F.Fab")
		)
		(fp_line
			(start -0.12065 0.3048)
			(end -0.67945 0.3048)
			(stroke
				(width 0.1)
				(type default)
			)
			(layer "F.Fab")
		)
		(fp_line
			(start 0.120396 0.2794)
			(end -0.12065 0.2794)
			(stroke
				(width 0.1)
				(type default)
			)
			(layer "F.Fab")
		)
		(fp_line
			(start 0.120396 0.3048)
			(end 0.120396 0.2794)
			(stroke
				(width 0.1)
				(type default)
			)
			(layer "F.Fab")
		)
		(fp_line
			(start 0.12065 -0.3048)
			(end 0.67945 -0.3048)
			(stroke
				(width 0.1)
				(type default)
			)
			(layer "F.Fab")
		)
		(fp_line
			(start 0.12065 -0.2794)
			(end 0.12065 -0.3048)
			(stroke
				(width 0.1)
				(type default)
			)
			(layer "F.Fab")
		)
		(fp_line
			(start 0.67945 -0.3048)
			(end 0.67945 0.3048)
			(stroke
				(width 0.1)
				(type default)
			)
			(layer "F.Fab")
		)
		(fp_line
			(start 0.67945 0.3048)
			(end 0.120396 0.3048)
			(stroke
				(width 0.1)
				(type default)
			)
			(layer "F.Fab")
		)
		(pad "1" smd circle
			(at -0.40005 0)
			(size 0 0)
			(layers "F.Cu" "F.Mask" "F.Paste")
			(net "P3V3_AUX")
		)
		(pad "2" smd circle
			(at 0.40005 0)
			(size 0 0)
			(layers "F.Cu" "F.Mask" "F.Paste")
			(net "PRSNT_FAN_BP1_R_N")
		)
	)
	(footprint ""
		(layer "F.Cu")
		(at 469.539828 -122.350022 90)
		(property "Reference" "J15"
			(at -6.425692 -0.884428 0)
			(unlocked yes)
			(layer "F.SilkS")
			(effects
				(font
					(size 0.7874 0.5842)
					(thickness 0.1524)
				)
				(justify left)
			)
		)
		(property "Value" ""
			(at 0 0 90)
			(layer "F.Fab")
			(effects
				(font
					(size 1.27 1.27)
				)
			)
		)
		(duplicate_pad_numbers_are_jumpers no)
		(fp_circle
			(center 0 0)
			(end 0 5.3848)
			(stroke
				(width 0.1524)
				(type default)
			)
			(fill no)
			(layer "F.SilkS")
		)
		(fp_line
			(start 3.999992 -2.999994)
			(end 4.000246 2.999994)
			(stroke
				(width 0.1)
				(type default)
			)
			(layer "F.Fab")
		)
		(fp_line
			(start -3.999992 2.999994)
			(end -3.999738 -2.999994)
			(stroke
				(width 0.1)
				(type default)
			)
			(layer "F.Fab")
		)
		(fp_arc
			(start -3.999738 -2.999994)
			(mid 0.000178 -4.99999)
			(end 3.999992 -2.999994)
			(stroke
				(width 0.1)
				(type default)
			)
			(layer "F.Fab")
		)
		(fp_arc
			(start 4.000246 2.999994)
			(mid 0.000178 4.99999)
			(end -3.999992 2.999994)
			(stroke
				(width 0.1)
				(type default)
			)
			(layer "F.Fab")
		)
		(pad "G1" thru_hole oval
			(at 0 -3.262376 90)
			(size 1.8796 3.1242)
			(drill oval 1.6256 2.8702)
			(layers "*.Cu" "*.Mask")
			(remove_unused_layers no)
			(net "GND")
			(clearance 0.254)
			(thermal_gap 0.254)
		)
		(pad "SCR_G1" thru_hole circle
			(at 0 0 90)
			(size 10.5156 10.5156)
			(drill 5.1562)
			(layers "*.Cu" "*.Mask")
			(remove_unused_layers no)
			(net "GND")
			(clearance 0)
		)
		(zone
			(layers "F.Cu" "B.Cu" "In1.Cu" "In2.Cu" "In3.Cu" "In4.Cu" "In5.Cu" "In6.Cu"
				"In7.Cu" "In8.Cu"
			)
			(hatch none 0.5)
			(connect_pads
				(clearance 0)
			)
			(min_thickness 0.25)
			(keepout
				(tracks not_allowed)
				(vias allowed)
				(pads allowed)
				(copperpour not_allowed)
				(footprints allowed)
			)
			(placement
				(enabled no)
				(sheetname "")
			)
			(fill
				(thermal_gap 0.5)
				(thermal_bridge_width 0.5)
				(island_removal_mode 0)
			)
			(polygon
				(pts
					(arc
						(start 542.615628 -124.001022)
						(mid 532.100028 -124.001022)
						(end 542.615628 -124.001022)
					)
				)
			)
		)
	)
	(footprint ""
		(layer "F.Cu")
		(at 306.7304 -37.9222)
		(property "Reference" "PR6954"
			(at 0 0 0)
			(layer "F.SilkS")
			(hide yes)
			(effects
				(font
					(size 1.27 1.27)
				)
			)
		)
		(property "Value" ""
			(at 0 0 0)
			(layer "F.Fab")
			(effects
				(font
					(size 1.27 1.27)
				)
			)
		)
		(duplicate_pad_numbers_are_jumpers no)
		(fp_line
			(start -1.2954 -0.5842)
			(end 1.2954 -0.5842)
			(stroke
				(width 0.1524)
				(type default)
			)
			(layer "F.SilkS")
		)
		(fp_line
			(start -1.2954 0.5842)
			(end -1.2954 -0.5842)
			(stroke
				(width 0.1524)
				(type default)
			)
			(layer "F.SilkS")
		)
		(fp_line
			(start 1.2954 -0.5842)
			(end 1.2954 0.5842)
			(stroke
				(width 0.1524)
				(type default)
			)
			(layer "F.SilkS")
		)
		(fp_line
			(start 1.2954 0.5842)
			(end -1.2954 0.5842)
			(stroke
				(width 0.1524)
				(type default)
			)
			(layer "F.SilkS")
		)
		(fp_line
			(start -1.1938 -0.406654)
			(end -0.8636 -0.406654)
			(stroke
				(width 0.1)
				(type default)
			)
			(layer "F.Fab")
		)
		(fp_line
			(start -1.1938 0.4064)
			(end -1.1938 -0.406654)
			(stroke
				(width 0.1)
				(type default)
			)
			(layer "F.Fab")
		)
		(fp_line
			(start -0.8636 -0.4572)
			(end 0.8636 -0.4572)
			(stroke
				(width 0.1)
				(type default)
			)
			(layer "F.Fab")
		)
		(fp_line
			(start -0.8636 -0.406654)
			(end -0.8636 -0.4572)
			(stroke
				(width 0.1)
				(type default)
			)
			(layer "F.Fab")
		)
		(fp_line
			(start -0.8636 0.4064)
			(end -1.1938 0.4064)
			(stroke
				(width 0.1)
				(type default)
			)
			(layer "F.Fab")
		)
		(fp_line
			(start -0.8636 0.4318)
			(end -0.8636 0.4064)
			(stroke
				(width 0.1)
				(type default)
			)
			(layer "F.Fab")
		)
		(fp_line
			(start -0.8636 0.4572)
			(end -0.8636 0.4318)
			(stroke
				(width 0.1)
				(type default)
			)
			(layer "F.Fab")
		)
		(fp_line
			(start 0.8636 -0.4572)
			(end 0.8636 -0.406654)
			(stroke
				(width 0.1)
				(type default)
			)
			(layer "F.Fab")
		)
		(fp_line
			(start 0.8636 -0.406654)
			(end 1.1938 -0.406654)
			(stroke
				(width 0.1)
				(type default)
			)
			(layer "F.Fab")
		)
		(fp_line
			(start 0.8636 0.4064)
			(end 0.8636 0.4572)
			(stroke
				(width 0.1)
				(type default)
			)
			(layer "F.Fab")
		)
		(fp_line
			(start 0.8636 0.4572)
			(end -0.8636 0.4572)
			(stroke
				(width 0.1)
				(type default)
			)
			(layer "F.Fab")
		)
		(fp_line
			(start 1.1938 -0.406654)
			(end 1.1938 0.4064)
			(stroke
				(width 0.1)
				(type default)
			)
			(layer "F.Fab")
		)
		(fp_line
			(start 1.1938 0.4064)
			(end 0.8636 0.4064)
			(stroke
				(width 0.1)
				(type default)
			)
			(layer "F.Fab")
		)
		(pad "1" smd rect
			(at -0.7366 0 270)
			(size 0.7112 0.8128)
			(layers "F.Cu" "F.Mask" "F.Paste")
			(net "P52V_HS_4287_S2N")
		)
		(pad "2" smd rect
			(at 0.7366 0 270)
			(size 0.7112 0.8128)
			(layers "F.Cu" "F.Mask" "F.Paste")
			(net "P52V_HS1_SENSE_N_R2")
		)
	)
	(footprint ""
		(layer "F.Cu")
		(at 323.13626 -40.8178 180)
		(property "Reference" "PQ6"
			(at -9.628886 -3.917188 0)
			(unlocked yes)
			(layer "F.SilkS")
			(effects
				(font
					(size 0.7874 0.5842)
					(thickness 0.1524)
				)
				(justify left)
			)
		)
		(property "Value" ""
			(at 0 0 180)
			(layer "F.Fab")
			(effects
				(font
					(size 1.27 1.27)
				)
			)
		)
		(duplicate_pad_numbers_are_jumpers no)
		(fp_line
			(start 7.649972 4.99999)
			(end 7.649972 -4.99999)
			(stroke
				(width 0.1524)
				(type default)
			)
			(layer "F.SilkS")
		)
		(fp_line
			(start 7.649972 -4.99999)
			(end 7.630414 -4.99999)
			(stroke
				(width 0.1524)
				(type default)
			)
			(layer "F.SilkS")
		)
		(fp_line
			(start 7.630414 4.99999)
			(end 7.649972 4.99999)
			(stroke
				(width 0.1524)
				(type default)
			)
			(layer "F.SilkS")
		)
		(fp_line
			(start 5.115814 -4.99999)
			(end -7.649972 -4.99999)
			(stroke
				(width 0.1524)
				(type default)
			)
			(layer "F.SilkS")
		)
		(fp_line
			(start -7.649972 4.99999)
			(end 5.115814 4.99999)
			(stroke
				(width 0.1524)
				(type default)
			)
			(layer "F.SilkS")
		)
		(fp_line
			(start -7.649972 3.3274)
			(end -7.649972 4.99999)
			(stroke
				(width 0.1524)
				(type default)
			)
			(layer "F.SilkS")
		)
		(fp_line
			(start -7.649972 -1.7526)
			(end -7.649972 1.7526)
			(stroke
				(width 0.1524)
				(type default)
			)
			(layer "F.SilkS")
		)
		(fp_line
			(start -7.649972 -4.99999)
			(end -7.649972 -3.3274)
			(stroke
				(width 0.1524)
				(type default)
			)
			(layer "F.SilkS")
		)
		(fp_line
			(start 7.649972 4.99999)
			(end 7.649972 -4.99999)
			(stroke
				(width 0.1)
				(type default)
			)
			(layer "F.Fab")
		)
		(fp_line
			(start 7.649972 -4.99999)
			(end -7.649972 -4.99999)
			(stroke
				(width 0.1)
				(type default)
			)
			(layer "F.Fab")
		)
		(fp_line
			(start -7.649972 4.99999)
			(end 7.649972 4.99999)
			(stroke
				(width 0.1)
				(type default)
			)
			(layer "F.Fab")
		)
		(fp_line
			(start -7.649972 -4.99999)
			(end -7.649972 4.99999)
			(stroke
				(width 0.1)
				(type default)
			)
			(layer "F.Fab")
		)
		(pad "D" smd circle
			(at 2.15011 0 180)
			(size 0 0)
			(layers "F.Cu" "F.Mask" "F.Paste")
			(net "P52V_HS1_DRAIN_2")
		)
		(pad "G" smd rect
			(at -7.050024 -2.54 90)
			(size 1.3208 3.0988)
			(layers "F.Cu" "F.Mask" "F.Paste")
			(net "P52V_HS1_GATE6")
		)
		(pad "S" smd rect
			(at -7.050024 2.54 90)
			(size 1.3208 3.0988)
			(layers "F.Cu" "F.Mask" "F.Paste")
			(net "P52V_HS1")
		)
		(zone
			(layer "F.Cu")
			(hatch none 0.5)
			(connect_pads
				(clearance 0)
			)
			(min_thickness 0.25)
			(keepout
				(tracks not_allowed)
				(vias allowed)
				(pads allowed)
				(copperpour not_allowed)
				(footprints allowed)
			)
			(placement
				(enabled no)
				(sheetname "")
			)
			(fill
				(thermal_gap 0.5)
				(thermal_bridge_width 0.5)
				(island_removal_mode 0)
			)
			(polygon
				(pts
					(xy 317.95466 -35.8394) (xy 330.78166 -35.8394) (xy 330.78166 -37.5666) (xy 328.57186 -37.5666)
					(xy 328.57186 -38.989) (xy 330.78166 -38.989) (xy 330.78166 -42.6466) (xy 328.57186 -42.6466) (xy 328.57186 -44.069)
					(xy 330.78166 -44.069) (xy 330.78166 -45.7962) (xy 317.95466 -45.7962) (xy 317.95466 -44.6278)
					(xy 324.15226 -44.6278) (xy 324.15226 -37.0078) (xy 317.95466 -37.0078)
				)
			)
		)
	)
	(footprint ""
		(layer "F.Cu")
		(at 172.4914 -76.835)
		(property "Reference" "R5887"
			(at 0 0 0)
			(layer "F.SilkS")
			(hide yes)
			(effects
				(font
					(size 1.27 1.27)
				)
			)
		)
		(property "Value" ""
			(at 0 0 0)
			(layer "F.Fab")
			(effects
				(font
					(size 1.27 1.27)
				)
			)
		)
		(duplicate_pad_numbers_are_jumpers no)
		(fp_line
			(start -0.7874 -0.4064)
			(end 0.7874 -0.4064)
			(stroke
				(width 0.1524)
				(type default)
			)
			(layer "F.SilkS")
		)
		(fp_line
			(start -0.7874 0.4064)
			(end -0.7874 -0.4064)
			(stroke
				(width 0.1524)
				(type default)
			)
			(layer "F.SilkS")
		)
		(fp_line
			(start 0.7874 -0.4064)
			(end 0.7874 0.4064)
			(stroke
				(width 0.1524)
				(type default)
			)
			(layer "F.SilkS")
		)
		(fp_line
			(start 0.7874 0.4064)
			(end -0.7874 0.4064)
			(stroke
				(width 0.1524)
				(type default)
			)
			(layer "F.SilkS")
		)
		(fp_line
			(start -0.67945 -0.305054)
			(end -0.12065 -0.305054)
			(stroke
				(width 0.1)
				(type default)
			)
			(layer "F.Fab")
		)
		(fp_line
			(start -0.67945 0.3048)
			(end -0.67945 -0.305054)
			(stroke
				(width 0.1)
				(type default)
			)
			(layer "F.Fab")
		)
		(fp_line
			(start -0.12065 -0.305054)
			(end -0.12065 -0.2794)
			(stroke
				(width 0.1)
				(type default)
			)
			(layer "F.Fab")
		)
		(fp_line
			(start -0.12065 -0.2794)
			(end 0.12065 -0.2794)
			(stroke
				(width 0.1)
				(type default)
			)
			(layer "F.Fab")
		)
		(fp_line
			(start -0.12065 0.2794)
			(end -0.12065 0.3048)
			(stroke
				(width 0.1)
				(type default)
			)
			(layer "F.Fab")
		)
		(fp_line
			(start -0.12065 0.3048)
			(end -0.67945 0.3048)
			(stroke
				(width 0.1)
				(type default)
			)
			(layer "F.Fab")
		)
		(fp_line
			(start 0.120396 0.2794)
			(end -0.12065 0.2794)
			(stroke
				(width 0.1)
				(type default)
			)
			(layer "F.Fab")
		)
		(fp_line
			(start 0.120396 0.3048)
			(end 0.120396 0.2794)
			(stroke
				(width 0.1)
				(type default)
			)
			(layer "F.Fab")
		)
		(fp_line
			(start 0.12065 -0.3048)
			(end 0.67945 -0.3048)
			(stroke
				(width 0.1)
				(type default)
			)
			(layer "F.Fab")
		)
		(fp_line
			(start 0.12065 -0.2794)
			(end 0.12065 -0.3048)
			(stroke
				(width 0.1)
				(type default)
			)
			(layer "F.Fab")
		)
		(fp_line
			(start 0.67945 -0.3048)
			(end 0.67945 0.3048)
			(stroke
				(width 0.1)
				(type default)
			)
			(layer "F.Fab")
		)
		(fp_line
			(start 0.67945 0.3048)
			(end 0.120396 0.3048)
			(stroke
				(width 0.1)
				(type default)
			)
			(layer "F.Fab")
		)
		(pad "1" smd circle
			(at -0.40005 0)
			(size 0 0)
			(layers "F.Cu" "F.Mask" "F.Paste")
			(net "P3V3_AUX")
		)
		(pad "2" smd circle
			(at 0.40005 0)
			(size 0 0)
			(layers "F.Cu" "F.Mask" "F.Paste")
			(net "P52V_HS2_GPO2")
		)
	)
	(footprint ""
		(layer "F.Cu")
		(at 130.412236 -81.788 180)
		(property "Reference" "PR6994"
			(at 0 0 180)
			(layer "F.SilkS")
			(hide yes)
			(effects
				(font
					(size 1.27 1.27)
				)
			)
		)
		(property "Value" ""
			(at 0 0 180)
			(layer "F.Fab")
			(effects
				(font
					(size 1.27 1.27)
				)
			)
		)
		(duplicate_pad_numbers_are_jumpers no)
		(fp_line
			(start 0.7874 0.4064)
			(end -0.7874 0.4064)
			(stroke
				(width 0.1524)
				(type default)
			)
			(layer "F.SilkS")
		)
		(fp_line
			(start 0.7874 -0.4064)
			(end 0.7874 0.4064)
			(stroke
				(width 0.1524)
				(type default)
			)
			(layer "F.SilkS")
		)
		(fp_line
			(start -0.7874 0.4064)
			(end -0.7874 -0.4064)
			(stroke
				(width 0.1524)
				(type default)
			)
			(layer "F.SilkS")
		)
		(fp_line
			(start -0.7874 -0.4064)
			(end 0.7874 -0.4064)
			(stroke
				(width 0.1524)
				(type default)
			)
			(layer "F.SilkS")
		)
		(fp_line
			(start 0.67945 0.3048)
			(end 0.120396 0.3048)
			(stroke
				(width 0.1)
				(type default)
			)
			(layer "F.Fab")
		)
		(fp_line
			(start 0.67945 -0.3048)
			(end 0.67945 0.3048)
			(stroke
				(width 0.1)
				(type default)
			)
			(layer "F.Fab")
		)
		(fp_line
			(start 0.12065 -0.2794)
			(end 0.12065 -0.3048)
			(stroke
				(width 0.1)
				(type default)
			)
			(layer "F.Fab")
		)
		(fp_line
			(start 0.12065 -0.3048)
			(end 0.67945 -0.3048)
			(stroke
				(width 0.1)
				(type default)
			)
			(layer "F.Fab")
		)
		(fp_line
			(start 0.120396 0.3048)
			(end 0.120396 0.2794)
			(stroke
				(width 0.1)
				(type default)
			)
			(layer "F.Fab")
		)
		(fp_line
			(start 0.120396 0.2794)
			(end -0.12065 0.2794)
			(stroke
				(width 0.1)
				(type default)
			)
			(layer "F.Fab")
		)
		(fp_line
			(start -0.12065 0.3048)
			(end -0.67945 0.3048)
			(stroke
				(width 0.1)
				(type default)
			)
			(layer "F.Fab")
		)
		(fp_line
			(start -0.12065 0.2794)
			(end -0.12065 0.3048)
			(stroke
				(width 0.1)
				(type default)
			)
			(layer "F.Fab")
		)
		(fp_line
			(start -0.12065 -0.2794)
			(end 0.12065 -0.2794)
			(stroke
				(width 0.1)
				(type default)
			)
			(layer "F.Fab")
		)
		(fp_line
			(start -0.12065 -0.305054)
			(end -0.12065 -0.2794)
			(stroke
				(width 0.1)
				(type default)
			)
			(layer "F.Fab")
		)
		(fp_line
			(start -0.67945 0.3048)
			(end -0.67945 -0.305054)
			(stroke
				(width 0.1)
				(type default)
			)
			(layer "F.Fab")
		)
		(fp_line
			(start -0.67945 -0.305054)
			(end -0.12065 -0.305054)
			(stroke
				(width 0.1)
				(type default)
			)
			(layer "F.Fab")
		)
		(pad "1" smd rect
			(at -0.40005 0)
			(size 0.4572 0.508)
			(layers "F.Cu" "F.Mask" "F.Paste")
			(net "P52V_HS2_TEMP")
		)
		(pad "2" smd rect
			(at 0.40005 0)
			(size 0.4572 0.508)
			(layers "F.Cu" "F.Mask" "F.Paste")
			(net "P52V_HS2_TEMP_R")
		)
	)
	(footprint ""
		(layer "F.Cu")
		(at 414.46958 -32.75076 90)
		(property "Reference" "C100"
			(at 0 0 90)
			(layer "F.SilkS")
			(hide yes)
			(effects
				(font
					(size 1.27 1.27)
				)
			)
		)
		(property "Value" ""
			(at 0 0 90)
			(layer "F.Fab")
			(effects
				(font
					(size 1.27 1.27)
				)
			)
		)
		(duplicate_pad_numbers_are_jumpers no)
		(fp_line
			(start 0.7874 -0.4064)
			(end 0.7874 0.4064)
			(stroke
				(width 0.1524)
				(type default)
			)
			(layer "F.SilkS")
		)
		(fp_line
			(start -0.7874 -0.4064)
			(end 0.7874 -0.4064)
			(stroke
				(width 0.1524)
				(type default)
			)
			(layer "F.SilkS")
		)
		(fp_line
			(start 0.7874 0.4064)
			(end -0.7874 0.4064)
			(stroke
				(width 0.1524)
				(type default)
			)
			(layer "F.SilkS")
		)
		(fp_line
			(start -0.7874 0.4064)
			(end -0.7874 -0.4064)
			(stroke
				(width 0.1524)
				(type default)
			)
			(layer "F.SilkS")
		)
		(fp_line
			(start -0.12065 -0.305054)
			(end -0.12065 -0.2794)
			(stroke
				(width 0.1)
				(type default)
			)
			(layer "F.Fab")
		)
		(fp_line
			(start -0.67945 -0.305054)
			(end -0.12065 -0.305054)
			(stroke
				(width 0.1)
				(type default)
			)
			(layer "F.Fab")
		)
		(fp_line
			(start 0.67945 -0.3048)
			(end 0.67945 0.3048)
			(stroke
				(width 0.1)
				(type default)
			)
			(layer "F.Fab")
		)
		(fp_line
			(start 0.12065 -0.3048)
			(end 0.67945 -0.3048)
			(stroke
				(width 0.1)
				(type default)
			)
			(layer "F.Fab")
		)
		(fp_line
			(start 0.12065 -0.2794)
			(end 0.12065 -0.3048)
			(stroke
				(width 0.1)
				(type default)
			)
			(layer "F.Fab")
		)
		(fp_line
			(start -0.12065 -0.2794)
			(end 0.12065 -0.2794)
			(stroke
				(width 0.1)
				(type default)
			)
			(layer "F.Fab")
		)
		(fp_line
			(start 0.120396 0.2794)
			(end -0.12065 0.2794)
			(stroke
				(width 0.1)
				(type default)
			)
			(layer "F.Fab")
		)
		(fp_line
			(start -0.12065 0.2794)
			(end -0.12065 0.3048)
			(stroke
				(width 0.1)
				(type default)
			)
			(layer "F.Fab")
		)
		(fp_line
			(start 0.67945 0.3048)
			(end 0.120396 0.3048)
			(stroke
				(width 0.1)
				(type default)
			)
			(layer "F.Fab")
		)
		(fp_line
			(start 0.120396 0.3048)
			(end 0.120396 0.2794)
			(stroke
				(width 0.1)
				(type default)
			)
			(layer "F.Fab")
		)
		(fp_line
			(start -0.12065 0.3048)
			(end -0.67945 0.3048)
			(stroke
				(width 0.1)
				(type default)
			)
			(layer "F.Fab")
		)
		(fp_line
			(start -0.67945 0.3048)
			(end -0.67945 -0.305054)
			(stroke
				(width 0.1)
				(type default)
			)
			(layer "F.Fab")
		)
		(pad "1" smd circle
			(at -0.40005 0 90)
			(size 0 0)
			(layers "F.Cu" "F.Mask" "F.Paste")
			(net "P12V_LED_IMON")
		)
		(pad "2" smd circle
			(at 0.40005 0 90)
			(size 0 0)
			(layers "F.Cu" "F.Mask" "F.Paste")
			(net "GND")
		)
	)
	(footprint ""
		(layer "F.Cu")
		(at 83.947 -17.907 90)
		(property "Reference" "R78"
			(at 0 0 90)
			(layer "F.SilkS")
			(hide yes)
			(effects
				(font
					(size 1.27 1.27)
				)
			)
		)
		(property "Value" ""
			(at 0 0 90)
			(layer "F.Fab")
			(effects
				(font
					(size 1.27 1.27)
				)
			)
		)
		(duplicate_pad_numbers_are_jumpers no)
		(fp_line
			(start 0.7874 -0.4064)
			(end 0.7874 0.4064)
			(stroke
				(width 0.1524)
				(type default)
			)
			(layer "F.SilkS")
		)
		(fp_line
			(start -0.7874 -0.4064)
			(end 0.7874 -0.4064)
			(stroke
				(width 0.1524)
				(type default)
			)
			(layer "F.SilkS")
		)
		(fp_line
			(start 0.7874 0.4064)
			(end -0.7874 0.4064)
			(stroke
				(width 0.1524)
				(type default)
			)
			(layer "F.SilkS")
		)
		(fp_line
			(start -0.7874 0.4064)
			(end -0.7874 -0.4064)
			(stroke
				(width 0.1524)
				(type default)
			)
			(layer "F.SilkS")
		)
		(fp_line
			(start -0.12065 -0.305054)
			(end -0.12065 -0.2794)
			(stroke
				(width 0.1)
				(type default)
			)
			(layer "F.Fab")
		)
		(fp_line
			(start -0.67945 -0.305054)
			(end -0.12065 -0.305054)
			(stroke
				(width 0.1)
				(type default)
			)
			(layer "F.Fab")
		)
		(fp_line
			(start 0.67945 -0.3048)
			(end 0.67945 0.3048)
			(stroke
				(width 0.1)
				(type default)
			)
			(layer "F.Fab")
		)
		(fp_line
			(start 0.12065 -0.3048)
			(end 0.67945 -0.3048)
			(stroke
				(width 0.1)
				(type default)
			)
			(layer "F.Fab")
		)
		(fp_line
			(start 0.12065 -0.2794)
			(end 0.12065 -0.3048)
			(stroke
				(width 0.1)
				(type default)
			)
			(layer "F.Fab")
		)
		(fp_line
			(start -0.12065 -0.2794)
			(end 0.12065 -0.2794)
			(stroke
				(width 0.1)
				(type default)
			)
			(layer "F.Fab")
		)
		(fp_line
			(start 0.120396 0.2794)
			(end -0.12065 0.2794)
			(stroke
				(width 0.1)
				(type default)
			)
			(layer "F.Fab")
		)
		(fp_line
			(start -0.12065 0.2794)
			(end -0.12065 0.3048)
			(stroke
				(width 0.1)
				(type default)
			)
			(layer "F.Fab")
		)
		(fp_line
			(start 0.67945 0.3048)
			(end 0.120396 0.3048)
			(stroke
				(width 0.1)
				(type default)
			)
			(layer "F.Fab")
		)
		(fp_line
			(start 0.120396 0.3048)
			(end 0.120396 0.2794)
			(stroke
				(width 0.1)
				(type default)
			)
			(layer "F.Fab")
		)
		(fp_line
			(start -0.12065 0.3048)
			(end -0.67945 0.3048)
			(stroke
				(width 0.1)
				(type default)
			)
			(layer "F.Fab")
		)
		(fp_line
			(start -0.67945 0.3048)
			(end -0.67945 -0.305054)
			(stroke
				(width 0.1)
				(type default)
			)
			(layer "F.Fab")
		)
		(pad "1" smd circle
			(at -0.40005 0 90)
			(size 0 0)
			(layers "F.Cu" "F.Mask" "F.Paste")
			(net "RST_SMB_FAN_1_R_N")
		)
		(pad "2" smd circle
			(at 0.40005 0 90)
			(size 0 0)
			(layers "F.Cu" "F.Mask" "F.Paste")
			(net "RST_SMB_PDB_BUF_N")
		)
	)
	(footprint ""
		(layer "F.Cu")
		(at 372.160038 -2.035048 -90)
		(property "Reference" "J8"
			(at -9.495282 -10.363962 0)
			(unlocked yes)
			(layer "F.SilkS")
			(effects
				(font
					(size 0.7874 0.5842)
					(thickness 0.1524)
				)
			)
		)
		(property "Value" ""
			(at 0 0 270)
			(layer "F.Fab")
			(effects
				(font
					(size 1.27 1.27)
				)
			)
		)
		(duplicate_pad_numbers_are_jumpers no)
		(fp_line
			(start -8.530082 13.72489)
			(end -8.530082 7.492238)
			(stroke
				(width 0.1524)
				(type default)
			)
			(layer "F.SilkS")
		)
		(fp_line
			(start 1.273048 13.72489)
			(end -8.530082 13.72489)
			(stroke
				(width 0.1524)
				(type default)
			)
			(layer "F.SilkS")
		)
		(fp_line
			(start -5.530088 10.724896)
			(end 1.720088 10.724896)
			(stroke
				(width 0.1524)
				(type default)
			)
			(layer "F.SilkS")
		)
		(fp_line
			(start 1.720088 10.724896)
			(end 1.720088 -8.80491)
			(stroke
				(width 0.1524)
				(type default)
			)
			(layer "F.SilkS")
		)
		(fp_line
			(start -8.530082 -0.915162)
			(end -8.530082 -11.804904)
			(stroke
				(width 0.1524)
				(type default)
			)
			(layer "F.SilkS")
		)
		(fp_line
			(start -5.530088 -8.80491)
			(end -5.530088 10.724896)
			(stroke
				(width 0.1524)
				(type default)
			)
			(layer "F.SilkS")
		)
		(fp_line
			(start 1.720088 -8.80491)
			(end -5.530088 -8.80491)
			(stroke
				(width 0.1524)
				(type default)
			)
			(layer "F.SilkS")
		)
		(fp_line
			(start -8.530082 -11.804904)
			(end 1.654048 -11.804904)
			(stroke
				(width 0.1524)
				(type default)
			)
			(layer "F.SilkS")
		)
		(fp_poly
			(pts
				(xy 1.400048 0.30988) (xy 0.780288 0) (xy 1.400048 -0.30988)
			)
			(stroke
				(width 0)
				(type default)
			)
			(fill yes)
			(layer "F.SilkS")
		)
		(fp_line
			(start -8.530082 13.72489)
			(end -8.530082 -11.804904)
			(stroke
				(width 0.1524)
				(type default)
			)
			(layer "B.SilkS")
		)
		(fp_line
			(start 4.720082 13.72489)
			(end -8.530082 13.72489)
			(stroke
				(width 0.1524)
				(type default)
			)
			(layer "B.SilkS")
		)
		(fp_line
			(start -8.530082 -11.804904)
			(end 4.720082 -11.804904)
			(stroke
				(width 0.1524)
				(type default)
			)
			(layer "B.SilkS")
		)
		(fp_line
			(start 4.720082 -11.804904)
			(end 4.720082 13.72489)
			(stroke
				(width 0.1524)
				(type default)
			)
			(layer "B.SilkS")
		)
		(fp_line
			(start -8.530082 13.72489)
			(end -8.530082 -11.804904)
			(stroke
				(width 0.1)
				(type default)
			)
			(layer "B.Fab")
		)
		(fp_line
			(start 4.720082 13.72489)
			(end -8.530082 13.72489)
			(stroke
				(width 0.1)
				(type default)
			)
			(layer "B.Fab")
		)
		(fp_line
			(start -8.530082 -11.804904)
			(end 4.720082 -11.804904)
			(stroke
				(width 0.1)
				(type default)
			)
			(layer "B.Fab")
		)
		(fp_line
			(start 4.720082 -11.804904)
			(end 4.720082 13.72489)
			(stroke
				(width 0.1)
				(type default)
			)
			(layer "B.Fab")
		)
		(fp_line
			(start -5.530088 10.724896)
			(end 1.720088 10.724896)
			(stroke
				(width 0.1)
				(type default)
			)
			(layer "F.Fab")
		)
		(fp_line
			(start 1.720088 10.724896)
			(end 1.720088 -8.80491)
			(stroke
				(width 0.1)
				(type default)
			)
			(layer "F.Fab")
		)
		(fp_line
			(start -5.530088 -8.80491)
			(end -5.530088 10.724896)
			(stroke
				(width 0.1)
				(type default)
			)
			(layer "F.Fab")
		)
		(fp_line
			(start 1.720088 -8.80491)
			(end -5.530088 -8.80491)
			(stroke
				(width 0.1)
				(type default)
			)
			(layer "F.Fab")
		)
		(fp_poly
			(pts
				(xy 2.939288 0.508) (xy 2.939288 -0.508) (xy 1.923288 0)
			)
			(stroke
				(width 0)
				(type default)
			)
			(fill yes)
			(layer "F.Fab")
		)
		(fp_text user "PRESS-FIT"
			(at -6.918452 -0.203962 0)
			(unlocked yes)
			(layer "F.SilkS")
			(effects
				(font
					(size 1.27 0.9652)
					(thickness 0.1524)
				)
				(justify left)
			)
		)
		(fp_text user "PRESS-FIT"
			(at -5.680202 -6.960362 0)
			(unlocked yes)
			(layer "B.SilkS")
			(effects
				(font
					(size 1.905 1.4224)
					(thickness 0.1524)
				)
				(justify left mirror)
			)
		)
		(fp_text user "PRESS-FIT"
			(at -6.86435 -7.1501 0)
			(unlocked yes)
			(layer "B.Fab")
			(effects
				(font
					(size 1.905 1.4224)
					(thickness 0.1524)
				)
				(justify left mirror)
			)
		)
		(fp_text user "PRESS-FIT"
			(at -6.88975 9.5123 0)
			(unlocked yes)
			(layer "F.Fab")
			(effects
				(font
					(size 1.905 1.4224)
					(thickness 0.1524)
				)
				(justify left)
			)
		)
		(pad "" np_thru_hole circle
			(at -1.905 8.58012 270)
			(size 2.413 2.413)
			(drill 2.413)
			(layers "*.Cu" "*.Mask")
			(clearance 0.381)
			(thermal_gap 0.381)
		)
		(pad "" np_thru_hole circle
			(at -0.55499 -6.65988 270)
			(size 2.413 2.413)
			(drill 2.413)
			(layers "*.Cu" "*.Mask")
			(clearance 0.381)
			(thermal_gap 0.381)
		)
		(pad "P1" thru_hole circle
			(at -0.55499 6.04012 270)
			(size 1.156208 1.156208)
			(drill 0.749808)
			(layers "*.Cu" "*.Mask")
			(remove_unused_layers no)
			(net "P52V_FAN")
			(clearance 0.0508)
			(thermal_gap 0.0508)
		)
		(pad "P2" thru_hole circle
			(at -0.55499 3.50012 270)
			(size 1.156208 1.156208)
			(drill 0.749808)
			(layers "*.Cu" "*.Mask")
			(remove_unused_layers no)
			(net "P52V_FAN")
			(clearance 0.0508)
			(thermal_gap 0.0508)
		)
		(pad "P3" thru_hole circle
			(at -3.25501 3.50012 270)
			(size 1.156208 1.156208)
			(drill 0.749808)
			(layers "*.Cu" "*.Mask")
			(remove_unused_layers no)
			(net "GND")
			(clearance 0.0508)
			(thermal_gap 0.0508)
		)
		(pad "P4" thru_hole circle
			(at -3.25501 6.04012 270)
			(size 1.156208 1.156208)
			(drill 0.749808)
			(layers "*.Cu" "*.Mask")
			(remove_unused_layers no)
			(net "GND")
			(clearance 0.0508)
			(thermal_gap 0.0508)
		)
		(pad "S1" thru_hole rect
			(at 0 0 270)
			(size 1.156208 1.156208)
			(drill 0.749808)
			(layers "*.Cu" "*.Mask")
			(remove_unused_layers no)
			(net "RST_SMB_FAN_0_R_N")
			(clearance 0.0508)
			(thermal_gap 0.0508)
			(padstack
				(mode front_inner_back)
				(layer "Inner"
					(shape circle)
					(size 1.156208 1.156208)
					(clearance 0.0508)
				)
				(layer "B.Cu"
					(shape rect)
					(size 1.156208 1.156208)
					(clearance 0.0508)
				)
			)
		)
		(pad "S2" thru_hole circle
			(at -1.27 -1.27 270)
			(size 1.156208 1.156208)
			(drill 0.749808)
			(layers "*.Cu" "*.Mask")
			(remove_unused_layers no)
			(net "FAN_PWR_EN_0_R")
			(clearance 0.0508)
			(thermal_gap 0.0508)
		)
		(pad "S3" thru_hole circle
			(at 0 -2.54 270)
			(size 1.156208 1.156208)
			(drill 0.749808)
			(layers "*.Cu" "*.Mask")
			(remove_unused_layers no)
			(net "P12V_FAN_LED")
			(clearance 0.0508)
			(thermal_gap 0.0508)
		)
		(pad "S4" thru_hole circle
			(at -1.27 -3.81 270)
			(size 1.156208 1.156208)
			(drill 0.749808)
			(layers "*.Cu" "*.Mask")
			(remove_unused_layers no)
			(net "P3V3_AUX")
			(clearance 0.0508)
			(thermal_gap 0.0508)
		)
		(pad "S5" thru_hole circle
			(at -3.81 -3.81 270)
			(size 1.156208 1.156208)
			(drill 0.749808)
			(layers "*.Cu" "*.Mask")
			(remove_unused_layers no)
			(net "PRSNT_FAN_BP0_R_N")
			(clearance 0.0508)
			(thermal_gap 0.0508)
		)
		(pad "S6" thru_hole circle
			(at -2.54 -2.54 270)
			(size 1.156208 1.156208)
			(drill 0.749808)
			(layers "*.Cu" "*.Mask")
			(remove_unused_layers no)
			(net "GND")
			(clearance 0.0508)
			(thermal_gap 0.0508)
		)
		(pad "S7" thru_hole circle
			(at -3.81 -1.27 270)
			(size 1.156208 1.156208)
			(drill 0.749808)
			(layers "*.Cu" "*.Mask")
			(remove_unused_layers no)
			(net "SMB_PDB_FAN_0_R_SCL")
			(clearance 0.0508)
			(thermal_gap 0.0508)
		)
		(pad "S8" thru_hole circle
			(at -2.54 0 270)
			(size 1.156208 1.156208)
			(drill 0.749808)
			(layers "*.Cu" "*.Mask")
			(remove_unused_layers no)
			(net "SMB_PDB_FAN_0_R_SDA")
			(clearance 0.0508)
			(thermal_gap 0.0508)
		)
		(zone
			(layers "F.Cu" "B.Cu" "In1.Cu" "In2.Cu" "In3.Cu" "In4.Cu" "In5.Cu" "In6.Cu"
				"In7.Cu" "In8.Cu"
			)
			(hatch none 0.5)
			(connect_pads
				(clearance 0)
			)
			(min_thickness 0.25)
			(keepout
				(tracks not_allowed)
				(vias allowed)
				(pads allowed)
				(copperpour not_allowed)
				(footprints allowed)
			)
			(placement
				(enabled no)
				(sheetname "")
			)
			(fill
				(thermal_gap 0.5)
				(thermal_bridge_width 0.5)
				(island_removal_mode 0)
			)
			(polygon
				(pts
					(arc
						(start 365.294418 -3.940048)
						(mid 361.865418 -3.940048)
						(end 365.294418 -3.940048)
					)
				)
			)
		)
		(zone
			(layers "F.Cu" "B.Cu" "In1.Cu" "In2.Cu" "In3.Cu" "In4.Cu" "In5.Cu" "In6.Cu"
				"In7.Cu" "In8.Cu"
			)
			(hatch none 0.5)
			(connect_pads
				(clearance 0)
			)
			(min_thickness 0.25)
			(keepout
				(tracks not_allowed)
				(vias allowed)
				(pads allowed)
				(copperpour not_allowed)
				(footprints allowed)
			)
			(placement
				(enabled no)
				(sheetname "")
			)
			(fill
				(thermal_gap 0.5)
				(thermal_bridge_width 0.5)
				(island_removal_mode 0)
			)
			(polygon
				(pts
					(arc
						(start 380.534672 -2.590038)
						(mid 377.105164 -2.590038)
						(end 380.534672 -2.590038)
					)
				)
			)
		)
		(zone
			(layer "B.Cu")
			(hatch none 0.5)
			(connect_pads
				(clearance 0)
			)
			(min_thickness 0.25)
			(keepout
				(tracks allowed)
				(vias not_allowed)
				(pads allowed)
				(copperpour not_allowed)
				(footprints allowed)
			)
			(placement
				(enabled no)
				(sheetname "")
			)
			(fill
				(thermal_gap 0.5)
				(thermal_bridge_width 0.5)
				(island_removal_mode 0)
			)
			(polygon
				(pts
					(xy 369.301522 -5.931662) (xy 365.478314 -5.931662) (xy 365.478314 -1.948434) (xy 369.301522 -1.948434)
				)
			)
		)
		(zone
			(layer "B.Cu")
			(hatch none 0.5)
			(connect_pads
				(clearance 0)
			)
			(min_thickness 0.25)
			(keepout
				(tracks allowed)
				(vias not_allowed)
				(pads allowed)
				(copperpour not_allowed)
				(footprints allowed)
			)
			(placement
				(enabled no)
				(sheetname "")
			)
			(fill
				(thermal_gap 0.5)
				(thermal_bridge_width 0.5)
				(island_removal_mode 0)
			)
			(polygon
				(pts
					(xy 376.611642 -6.486652) (xy 371.518434 -6.486652) (xy 371.518434 -1.393444) (xy 376.611642 -1.393444)
				)
			)
		)
	)
	(footprint ""
		(layer "F.Cu")
		(at 435.5338 -25.146 180)
		(property "Reference" "R61"
			(at 0 0 180)
			(layer "F.SilkS")
			(hide yes)
			(effects
				(font
					(size 1.27 1.27)
				)
			)
		)
		(property "Value" ""
			(at 0 0 180)
			(layer "F.Fab")
			(effects
				(font
					(size 1.27 1.27)
				)
			)
		)
		(duplicate_pad_numbers_are_jumpers no)
		(fp_line
			(start 0.7874 0.4064)
			(end -0.7874 0.4064)
			(stroke
				(width 0.1524)
				(type default)
			)
			(layer "F.SilkS")
		)
		(fp_line
			(start 0.7874 -0.4064)
			(end 0.7874 0.4064)
			(stroke
				(width 0.1524)
				(type default)
			)
			(layer "F.SilkS")
		)
		(fp_line
			(start -0.7874 0.4064)
			(end -0.7874 -0.4064)
			(stroke
				(width 0.1524)
				(type default)
			)
			(layer "F.SilkS")
		)
		(fp_line
			(start -0.7874 -0.4064)
			(end 0.7874 -0.4064)
			(stroke
				(width 0.1524)
				(type default)
			)
			(layer "F.SilkS")
		)
		(fp_line
			(start 0.67945 0.3048)
			(end 0.120396 0.3048)
			(stroke
				(width 0.1)
				(type default)
			)
			(layer "F.Fab")
		)
		(fp_line
			(start 0.67945 -0.3048)
			(end 0.67945 0.3048)
			(stroke
				(width 0.1)
				(type default)
			)
			(layer "F.Fab")
		)
		(fp_line
			(start 0.12065 -0.2794)
			(end 0.12065 -0.3048)
			(stroke
				(width 0.1)
				(type default)
			)
			(layer "F.Fab")
		)
		(fp_line
			(start 0.12065 -0.3048)
			(end 0.67945 -0.3048)
			(stroke
				(width 0.1)
				(type default)
			)
			(layer "F.Fab")
		)
		(fp_line
			(start 0.120396 0.3048)
			(end 0.120396 0.2794)
			(stroke
				(width 0.1)
				(type default)
			)
			(layer "F.Fab")
		)
		(fp_line
			(start 0.120396 0.2794)
			(end -0.12065 0.2794)
			(stroke
				(width 0.1)
				(type default)
			)
			(layer "F.Fab")
		)
		(fp_line
			(start -0.12065 0.3048)
			(end -0.67945 0.3048)
			(stroke
				(width 0.1)
				(type default)
			)
			(layer "F.Fab")
		)
		(fp_line
			(start -0.12065 0.2794)
			(end -0.12065 0.3048)
			(stroke
				(width 0.1)
				(type default)
			)
			(layer "F.Fab")
		)
		(fp_line
			(start -0.12065 -0.2794)
			(end 0.12065 -0.2794)
			(stroke
				(width 0.1)
				(type default)
			)
			(layer "F.Fab")
		)
		(fp_line
			(start -0.12065 -0.305054)
			(end -0.12065 -0.2794)
			(stroke
				(width 0.1)
				(type default)
			)
			(layer "F.Fab")
		)
		(fp_line
			(start -0.67945 0.3048)
			(end -0.67945 -0.305054)
			(stroke
				(width 0.1)
				(type default)
			)
			(layer "F.Fab")
		)
		(fp_line
			(start -0.67945 -0.305054)
			(end -0.12065 -0.305054)
			(stroke
				(width 0.1)
				(type default)
			)
			(layer "F.Fab")
		)
		(pad "1" smd circle
			(at -0.40005 0 180)
			(size 0 0)
			(layers "F.Cu" "F.Mask" "F.Paste")
			(net "P3V3_AUX")
		)
		(pad "2" smd circle
			(at 0.40005 0 180)
			(size 0 0)
			(layers "F.Cu" "F.Mask" "F.Paste")
			(net "FRU_ADDR0")
		)
	)
	(footprint ""
		(layer "F.Cu")
		(at 250.000008 -87.499952 180)
		(property "Reference" "H8"
			(at 0.699008 -5.484622 0)
			(unlocked yes)
			(layer "F.SilkS")
			(effects
				(font
					(size 0.7874 0.5842)
					(thickness 0.1524)
				)
				(justify left)
			)
		)
		(property "Value" ""
			(at 0 0 180)
			(layer "F.Fab")
			(effects
				(font
					(size 1.27 1.27)
				)
			)
		)
		(duplicate_pad_numbers_are_jumpers no)
		(pad "1" thru_hole oval
			(at 0 0 180)
			(size 9.017 14.0208)
			(drill 3.0226
				(offset 0 2.499868)
			)
			(layers "*.Cu" "*.Mask")
			(remove_unused_layers no)
			(net "GND")
			(clearance -1.500378)
			(padstack
				(mode front_inner_back)
				(layer "Inner"
					(shape circle)
					(size 0 0)
					(clearance 0)
				)
				(layer "B.Cu"
					(shape oval)
					(size 9.017 14.0208)
					(offset 0 2.499868)
					(clearance -1.500378)
				)
			)
		)
	)
	(footprint ""
		(layer "F.Cu")
		(at 14.99997 -104.544876)
		(property "Reference" "H21"
			(at -1.02997 -8.839454 0)
			(unlocked yes)
			(layer "F.SilkS")
			(effects
				(font
					(size 0.7874 0.5842)
					(thickness 0.1524)
				)
				(justify left)
			)
		)
		(property "Value" ""
			(at 0 0 0)
			(layer "F.Fab")
			(effects
				(font
					(size 1.27 1.27)
				)
			)
		)
		(duplicate_pad_numbers_are_jumpers no)
		(fp_circle
			(center 0 0)
			(end 7.999984 0)
			(stroke
				(width 0.1524)
				(type default)
			)
			(fill no)
			(layer "F.SilkS")
		)
		(fp_circle
			(center 0 0)
			(end 7.999984 0)
			(stroke
				(width 0.1524)
				(type default)
			)
			(fill no)
			(layer "B.SilkS")
		)
		(fp_circle
			(center 0 0)
			(end 7.999984 0)
			(stroke
				(width 0.1)
				(type default)
			)
			(fill no)
			(layer "B.Fab")
		)
		(fp_circle
			(center 0 0)
			(end 7.999984 0)
			(stroke
				(width 0.1)
				(type default)
			)
			(fill no)
			(layer "F.Fab")
		)
		(pad "" np_thru_hole circle
			(at 0 0)
			(size 4.0132 4.0132)
			(drill 4.0132)
			(layers "*.Cu" "*.Mask")
			(clearance 0.381)
			(thermal_gap 0.381)
		)
		(pad "2" thru_hole circle
			(at 0 -3.50012)
			(size 0.762 0.762)
			(drill 0.5588)
			(layers "*.Cu" "*.Mask")
			(remove_unused_layers no)
			(net "GND")
			(clearance 0.1524)
			(thermal_gap 0.1524)
		)
		(pad "3" thru_hole circle
			(at -2.500122 -2.500122)
			(size 0.762 0.762)
			(drill 0.5588)
			(layers "*.Cu" "*.Mask")
			(remove_unused_layers no)
			(net "GND")
			(clearance 0.1524)
			(thermal_gap 0.1524)
		)
		(pad "4" thru_hole circle
			(at -3.50012 0)
			(size 0.762 0.762)
			(drill 0.5588)
			(layers "*.Cu" "*.Mask")
			(remove_unused_layers no)
			(net "GND")
			(clearance 0.1524)
			(thermal_gap 0.1524)
		)
		(pad "5" thru_hole circle
			(at -2.500122 2.500122)
			(size 0.762 0.762)
			(drill 0.5588)
			(layers "*.Cu" "*.Mask")
			(remove_unused_layers no)
			(net "GND")
			(clearance 0.1524)
			(thermal_gap 0.1524)
		)
		(pad "6" thru_hole circle
			(at 0 3.50012)
			(size 0.762 0.762)
			(drill 0.5588)
			(layers "*.Cu" "*.Mask")
			(remove_unused_layers no)
			(net "GND")
			(clearance 0.1524)
			(thermal_gap 0.1524)
		)
		(pad "7" thru_hole circle
			(at 2.500122 2.500122)
			(size 0.762 0.762)
			(drill 0.5588)
			(layers "*.Cu" "*.Mask")
			(remove_unused_layers no)
			(net "GND")
			(clearance 0.1524)
			(thermal_gap 0.1524)
		)
		(pad "8" thru_hole circle
			(at 3.50012 0)
			(size 0.762 0.762)
			(drill 0.5588)
			(layers "*.Cu" "*.Mask")
			(remove_unused_layers no)
			(net "GND")
			(clearance 0.1524)
			(thermal_gap 0.1524)
		)
		(pad "9" thru_hole circle
			(at 2.500122 -2.500122)
			(size 0.762 0.762)
			(drill 0.5588)
			(layers "*.Cu" "*.Mask")
			(remove_unused_layers no)
			(net "GND")
			(clearance 0.1524)
			(thermal_gap 0.1524)
		)
		(zone
			(layers "F.Cu" "B.Cu" "In1.Cu" "In2.Cu" "In3.Cu" "In4.Cu" "In5.Cu" "In6.Cu"
				"In7.Cu" "In8.Cu"
			)
			(hatch none 0.5)
			(connect_pads
				(clearance 0)
			)
			(min_thickness 0.25)
			(keepout
				(tracks not_allowed)
				(vias allowed)
				(pads allowed)
				(copperpour not_allowed)
				(footprints allowed)
			)
			(placement
				(enabled no)
				(sheetname "")
			)
			(fill
				(thermal_gap 0.5)
				(thermal_bridge_width 0.5)
				(island_removal_mode 0)
			)
			(polygon
				(pts
					(arc
						(start 17.51457 -104.544876)
						(mid 12.48537 -104.544876)
						(end 17.51457 -104.544876)
					)
				)
			)
		)
	)
	(footprint ""
		(layer "F.Cu")
		(at 190.000128 -87.499952 180)
		(property "Reference" "H6"
			(at 0.643128 -5.484622 0)
			(unlocked yes)
			(layer "F.SilkS")
			(effects
				(font
					(size 0.7874 0.5842)
					(thickness 0.1524)
				)
				(justify left)
			)
		)
		(property "Value" ""
			(at 0 0 180)
			(layer "F.Fab")
			(effects
				(font
					(size 1.27 1.27)
				)
			)
		)
		(duplicate_pad_numbers_are_jumpers no)
		(pad "1" thru_hole oval
			(at 0 0 180)
			(size 9.017 14.0208)
			(drill 3.0226
				(offset 0 2.499868)
			)
			(layers "*.Cu" "*.Mask")
			(remove_unused_layers no)
			(net "GND")
			(clearance -1.500378)
			(padstack
				(mode front_inner_back)
				(layer "Inner"
					(shape circle)
					(size 0 0)
					(clearance 0)
				)
				(layer "B.Cu"
					(shape oval)
					(size 9.017 14.0208)
					(offset 0 2.499868)
					(clearance -1.500378)
				)
			)
		)
	)
	(footprint ""
		(layer "F.Cu")
		(at 168.956736 -66.167)
		(property "Reference" "R5891"
			(at 0 0 0)
			(layer "F.SilkS")
			(hide yes)
			(effects
				(font
					(size 1.27 1.27)
				)
			)
		)
		(property "Value" ""
			(at 0 0 0)
			(layer "F.Fab")
			(effects
				(font
					(size 1.27 1.27)
				)
			)
		)
		(duplicate_pad_numbers_are_jumpers no)
		(fp_line
			(start -0.7874 -0.4064)
			(end 0.7874 -0.4064)
			(stroke
				(width 0.1524)
				(type default)
			)
			(layer "F.SilkS")
		)
		(fp_line
			(start -0.7874 0.4064)
			(end -0.7874 -0.4064)
			(stroke
				(width 0.1524)
				(type default)
			)
			(layer "F.SilkS")
		)
		(fp_line
			(start 0.7874 -0.4064)
			(end 0.7874 0.4064)
			(stroke
				(width 0.1524)
				(type default)
			)
			(layer "F.SilkS")
		)
		(fp_line
			(start 0.7874 0.4064)
			(end -0.7874 0.4064)
			(stroke
				(width 0.1524)
				(type default)
			)
			(layer "F.SilkS")
		)
		(fp_line
			(start -0.67945 -0.305054)
			(end -0.12065 -0.305054)
			(stroke
				(width 0.1)
				(type default)
			)
			(layer "F.Fab")
		)
		(fp_line
			(start -0.67945 0.3048)
			(end -0.67945 -0.305054)
			(stroke
				(width 0.1)
				(type default)
			)
			(layer "F.Fab")
		)
		(fp_line
			(start -0.12065 -0.305054)
			(end -0.12065 -0.2794)
			(stroke
				(width 0.1)
				(type default)
			)
			(layer "F.Fab")
		)
		(fp_line
			(start -0.12065 -0.2794)
			(end 0.12065 -0.2794)
			(stroke
				(width 0.1)
				(type default)
			)
			(layer "F.Fab")
		)
		(fp_line
			(start -0.12065 0.2794)
			(end -0.12065 0.3048)
			(stroke
				(width 0.1)
				(type default)
			)
			(layer "F.Fab")
		)
		(fp_line
			(start -0.12065 0.3048)
			(end -0.67945 0.3048)
			(stroke
				(width 0.1)
				(type default)
			)
			(layer "F.Fab")
		)
		(fp_line
			(start 0.120396 0.2794)
			(end -0.12065 0.2794)
			(stroke
				(width 0.1)
				(type default)
			)
			(layer "F.Fab")
		)
		(fp_line
			(start 0.120396 0.3048)
			(end 0.120396 0.2794)
			(stroke
				(width 0.1)
				(type default)
			)
			(layer "F.Fab")
		)
		(fp_line
			(start 0.12065 -0.3048)
			(end 0.67945 -0.3048)
			(stroke
				(width 0.1)
				(type default)
			)
			(layer "F.Fab")
		)
		(fp_line
			(start 0.12065 -0.2794)
			(end 0.12065 -0.3048)
			(stroke
				(width 0.1)
				(type default)
			)
			(layer "F.Fab")
		)
		(fp_line
			(start 0.67945 -0.3048)
			(end 0.67945 0.3048)
			(stroke
				(width 0.1)
				(type default)
			)
			(layer "F.Fab")
		)
		(fp_line
			(start 0.67945 0.3048)
			(end 0.120396 0.3048)
			(stroke
				(width 0.1)
				(type default)
			)
			(layer "F.Fab")
		)
		(pad "1" smd circle
			(at -0.40005 0)
			(size 0 0)
			(layers "F.Cu" "F.Mask" "F.Paste")
			(net "P52V_HS2_VCAP")
		)
		(pad "2" smd circle
			(at 0.40005 0)
			(size 0 0)
			(layers "F.Cu" "F.Mask" "F.Paste")
			(net "P52V_HS2_ADR0")
		)
	)
	(footprint ""
		(layer "F.Cu")
		(at 318.008 -83.82 180)
		(property "Reference" "PR6968"
			(at 0 0 180)
			(layer "F.SilkS")
			(hide yes)
			(effects
				(font
					(size 1.27 1.27)
				)
			)
		)
		(property "Value" ""
			(at 0 0 180)
			(layer "F.Fab")
			(effects
				(font
					(size 1.27 1.27)
				)
			)
		)
		(duplicate_pad_numbers_are_jumpers no)
		(fp_line
			(start 0.7874 0.4064)
			(end -0.7874 0.4064)
			(stroke
				(width 0.1524)
				(type default)
			)
			(layer "F.SilkS")
		)
		(fp_line
			(start 0.7874 -0.4064)
			(end 0.7874 0.4064)
			(stroke
				(width 0.1524)
				(type default)
			)
			(layer "F.SilkS")
		)
		(fp_line
			(start -0.7874 0.4064)
			(end -0.7874 -0.4064)
			(stroke
				(width 0.1524)
				(type default)
			)
			(layer "F.SilkS")
		)
		(fp_line
			(start -0.7874 -0.4064)
			(end 0.7874 -0.4064)
			(stroke
				(width 0.1524)
				(type default)
			)
			(layer "F.SilkS")
		)
		(fp_line
			(start 0.67945 0.3048)
			(end 0.120396 0.3048)
			(stroke
				(width 0.1)
				(type default)
			)
			(layer "F.Fab")
		)
		(fp_line
			(start 0.67945 -0.3048)
			(end 0.67945 0.3048)
			(stroke
				(width 0.1)
				(type default)
			)
			(layer "F.Fab")
		)
		(fp_line
			(start 0.12065 -0.2794)
			(end 0.12065 -0.3048)
			(stroke
				(width 0.1)
				(type default)
			)
			(layer "F.Fab")
		)
		(fp_line
			(start 0.12065 -0.3048)
			(end 0.67945 -0.3048)
			(stroke
				(width 0.1)
				(type default)
			)
			(layer "F.Fab")
		)
		(fp_line
			(start 0.120396 0.3048)
			(end 0.120396 0.2794)
			(stroke
				(width 0.1)
				(type default)
			)
			(layer "F.Fab")
		)
		(fp_line
			(start 0.120396 0.2794)
			(end -0.12065 0.2794)
			(stroke
				(width 0.1)
				(type default)
			)
			(layer "F.Fab")
		)
		(fp_line
			(start -0.12065 0.3048)
			(end -0.67945 0.3048)
			(stroke
				(width 0.1)
				(type default)
			)
			(layer "F.Fab")
		)
		(fp_line
			(start -0.12065 0.2794)
			(end -0.12065 0.3048)
			(stroke
				(width 0.1)
				(type default)
			)
			(layer "F.Fab")
		)
		(fp_line
			(start -0.12065 -0.2794)
			(end 0.12065 -0.2794)
			(stroke
				(width 0.1)
				(type default)
			)
			(layer "F.Fab")
		)
		(fp_line
			(start -0.12065 -0.305054)
			(end -0.12065 -0.2794)
			(stroke
				(width 0.1)
				(type default)
			)
			(layer "F.Fab")
		)
		(fp_line
			(start -0.67945 0.3048)
			(end -0.67945 -0.305054)
			(stroke
				(width 0.1)
				(type default)
			)
			(layer "F.Fab")
		)
		(fp_line
			(start -0.67945 -0.305054)
			(end -0.12065 -0.305054)
			(stroke
				(width 0.1)
				(type default)
			)
			(layer "F.Fab")
		)
		(pad "1" smd rect
			(at -0.40005 0)
			(size 0.4572 0.508)
			(layers "F.Cu" "F.Mask" "F.Paste")
			(net "P52V_HS1_TEMPN")
		)
		(pad "2" smd rect
			(at 0.40005 0)
			(size 0.4572 0.508)
			(layers "F.Cu" "F.Mask" "F.Paste")
			(net "P52V_HS1_TEMPN_R")
		)
	)
	(footprint ""
		(layer "F.Cu")
		(at 49.3014 -27.051 180)
		(property "Reference" "PU4"
			(at 3.5814 -1.42367 0)
			(unlocked yes)
			(layer "F.SilkS")
			(effects
				(font
					(size 0.7874 0.5842)
					(thickness 0.1524)
				)
				(justify left)
			)
		)
		(property "Value" ""
			(at 0 0 180)
			(layer "F.Fab")
			(effects
				(font
					(size 1.27 1.27)
				)
			)
		)
		(duplicate_pad_numbers_are_jumpers no)
		(fp_line
			(start 1.335278 1.100074)
			(end 1.335278 -1.100074)
			(stroke
				(width 0.1524)
				(type default)
			)
			(layer "F.SilkS")
		)
		(fp_line
			(start 1.335278 -1.100074)
			(end -1.335278 -1.100074)
			(stroke
				(width 0.1524)
				(type default)
			)
			(layer "F.SilkS")
		)
		(fp_line
			(start -1.335278 1.100074)
			(end 1.335278 1.100074)
			(stroke
				(width 0.1524)
				(type default)
			)
			(layer "F.SilkS")
		)
		(fp_line
			(start -1.335278 -1.100074)
			(end -1.335278 1.100074)
			(stroke
				(width 0.1524)
				(type default)
			)
			(layer "F.SilkS")
		)
		(fp_line
			(start 0.674878 1.100074)
			(end 0.674878 -1.100074)
			(stroke
				(width 0.1)
				(type default)
			)
			(layer "F.Fab")
		)
		(fp_line
			(start 0.674878 -1.100074)
			(end -0.674878 -1.100074)
			(stroke
				(width 0.1)
				(type default)
			)
			(layer "F.Fab")
		)
		(fp_line
			(start -0.674878 1.100074)
			(end 0.674878 1.100074)
			(stroke
				(width 0.1)
				(type default)
			)
			(layer "F.Fab")
		)
		(fp_line
			(start -0.674878 -1.100074)
			(end -0.674878 1.100074)
			(stroke
				(width 0.1)
				(type default)
			)
			(layer "F.Fab")
		)
		(pad "D" smd rect
			(at 0.8001 0 90)
			(size 0.6096 0.8128)
			(layers "F.Cu" "F.Mask" "F.Paste")
			(net "P52V_HS2_EN_DISCHARGE_N")
		)
		(pad "G" smd rect
			(at -0.8001 -0.649986 90)
			(size 0.6096 0.8128)
			(layers "F.Cu" "F.Mask" "F.Paste")
			(net "P52V_HS2_EN_DISCHARGE")
		)
		(pad "S" smd rect
			(at -0.8001 0.649986 90)
			(size 0.6096 0.8128)
			(layers "F.Cu" "F.Mask" "F.Paste")
			(net "GND")
		)
	)
	(footprint ""
		(layer "F.Cu")
		(at 142.93342 -73.025 180)
		(property "Reference" "PR7041"
			(at 0 0 180)
			(layer "F.SilkS")
			(hide yes)
			(effects
				(font
					(size 1.27 1.27)
				)
			)
		)
		(property "Value" ""
			(at 0 0 180)
			(layer "F.Fab")
			(effects
				(font
					(size 1.27 1.27)
				)
			)
		)
		(duplicate_pad_numbers_are_jumpers no)
		(fp_line
			(start 0.7874 0.4064)
			(end -0.7874 0.4064)
			(stroke
				(width 0.1524)
				(type default)
			)
			(layer "F.SilkS")
		)
		(fp_line
			(start 0.7874 -0.4064)
			(end 0.7874 0.4064)
			(stroke
				(width 0.1524)
				(type default)
			)
			(layer "F.SilkS")
		)
		(fp_line
			(start -0.7874 0.4064)
			(end -0.7874 -0.4064)
			(stroke
				(width 0.1524)
				(type default)
			)
			(layer "F.SilkS")
		)
		(fp_line
			(start -0.7874 -0.4064)
			(end 0.7874 -0.4064)
			(stroke
				(width 0.1524)
				(type default)
			)
			(layer "F.SilkS")
		)
		(fp_line
			(start 0.67945 0.3048)
			(end 0.120396 0.3048)
			(stroke
				(width 0.1)
				(type default)
			)
			(layer "F.Fab")
		)
		(fp_line
			(start 0.67945 -0.3048)
			(end 0.67945 0.3048)
			(stroke
				(width 0.1)
				(type default)
			)
			(layer "F.Fab")
		)
		(fp_line
			(start 0.12065 -0.2794)
			(end 0.12065 -0.3048)
			(stroke
				(width 0.1)
				(type default)
			)
			(layer "F.Fab")
		)
		(fp_line
			(start 0.12065 -0.3048)
			(end 0.67945 -0.3048)
			(stroke
				(width 0.1)
				(type default)
			)
			(layer "F.Fab")
		)
		(fp_line
			(start 0.120396 0.3048)
			(end 0.120396 0.2794)
			(stroke
				(width 0.1)
				(type default)
			)
			(layer "F.Fab")
		)
		(fp_line
			(start 0.120396 0.2794)
			(end -0.12065 0.2794)
			(stroke
				(width 0.1)
				(type default)
			)
			(layer "F.Fab")
		)
		(fp_line
			(start -0.12065 0.3048)
			(end -0.67945 0.3048)
			(stroke
				(width 0.1)
				(type default)
			)
			(layer "F.Fab")
		)
		(fp_line
			(start -0.12065 0.2794)
			(end -0.12065 0.3048)
			(stroke
				(width 0.1)
				(type default)
			)
			(layer "F.Fab")
		)
		(fp_line
			(start -0.12065 -0.2794)
			(end 0.12065 -0.2794)
			(stroke
				(width 0.1)
				(type default)
			)
			(layer "F.Fab")
		)
		(fp_line
			(start -0.12065 -0.305054)
			(end -0.12065 -0.2794)
			(stroke
				(width 0.1)
				(type default)
			)
			(layer "F.Fab")
		)
		(fp_line
			(start -0.67945 0.3048)
			(end -0.67945 -0.305054)
			(stroke
				(width 0.1)
				(type default)
			)
			(layer "F.Fab")
		)
		(fp_line
			(start -0.67945 -0.305054)
			(end -0.12065 -0.305054)
			(stroke
				(width 0.1)
				(type default)
			)
			(layer "F.Fab")
		)
		(pad "1" smd circle
			(at -0.40005 0 180)
			(size 0 0)
			(layers "F.Cu" "F.Mask" "F.Paste")
			(net "P52V_HS2_4287_S1P")
		)
		(pad "2" smd circle
			(at 0.40005 0 180)
			(size 0 0)
			(layers "F.Cu" "F.Mask" "F.Paste")
			(net "P52V_HS2_4287_S1N")
		)
	)
	(footprint ""
		(layer "F.Cu")
		(at 467.909656 -107.502452 90)
		(property "Reference" "R84"
			(at 0 0 90)
			(layer "F.SilkS")
			(hide yes)
			(effects
				(font
					(size 1.27 1.27)
				)
			)
		)
		(property "Value" ""
			(at 0 0 90)
			(layer "F.Fab")
			(effects
				(font
					(size 1.27 1.27)
				)
			)
		)
		(duplicate_pad_numbers_are_jumpers no)
		(fp_line
			(start 0.7874 -0.4064)
			(end 0.7874 0.4064)
			(stroke
				(width 0.1524)
				(type default)
			)
			(layer "F.SilkS")
		)
		(fp_line
			(start -0.7874 -0.4064)
			(end 0.7874 -0.4064)
			(stroke
				(width 0.1524)
				(type default)
			)
			(layer "F.SilkS")
		)
		(fp_line
			(start 0.7874 0.4064)
			(end -0.7874 0.4064)
			(stroke
				(width 0.1524)
				(type default)
			)
			(layer "F.SilkS")
		)
		(fp_line
			(start -0.7874 0.4064)
			(end -0.7874 -0.4064)
			(stroke
				(width 0.1524)
				(type default)
			)
			(layer "F.SilkS")
		)
		(fp_line
			(start -0.12065 -0.305054)
			(end -0.12065 -0.2794)
			(stroke
				(width 0.1)
				(type default)
			)
			(layer "F.Fab")
		)
		(fp_line
			(start -0.67945 -0.305054)
			(end -0.12065 -0.305054)
			(stroke
				(width 0.1)
				(type default)
			)
			(layer "F.Fab")
		)
		(fp_line
			(start 0.67945 -0.3048)
			(end 0.67945 0.3048)
			(stroke
				(width 0.1)
				(type default)
			)
			(layer "F.Fab")
		)
		(fp_line
			(start 0.12065 -0.3048)
			(end 0.67945 -0.3048)
			(stroke
				(width 0.1)
				(type default)
			)
			(layer "F.Fab")
		)
		(fp_line
			(start 0.12065 -0.2794)
			(end 0.12065 -0.3048)
			(stroke
				(width 0.1)
				(type default)
			)
			(layer "F.Fab")
		)
		(fp_line
			(start -0.12065 -0.2794)
			(end 0.12065 -0.2794)
			(stroke
				(width 0.1)
				(type default)
			)
			(layer "F.Fab")
		)
		(fp_line
			(start 0.120396 0.2794)
			(end -0.12065 0.2794)
			(stroke
				(width 0.1)
				(type default)
			)
			(layer "F.Fab")
		)
		(fp_line
			(start -0.12065 0.2794)
			(end -0.12065 0.3048)
			(stroke
				(width 0.1)
				(type default)
			)
			(layer "F.Fab")
		)
		(fp_line
			(start 0.67945 0.3048)
			(end 0.120396 0.3048)
			(stroke
				(width 0.1)
				(type default)
			)
			(layer "F.Fab")
		)
		(fp_line
			(start 0.120396 0.3048)
			(end 0.120396 0.2794)
			(stroke
				(width 0.1)
				(type default)
			)
			(layer "F.Fab")
		)
		(fp_line
			(start -0.12065 0.3048)
			(end -0.67945 0.3048)
			(stroke
				(width 0.1)
				(type default)
			)
			(layer "F.Fab")
		)
		(fp_line
			(start -0.67945 0.3048)
			(end -0.67945 -0.305054)
			(stroke
				(width 0.1)
				(type default)
			)
			(layer "F.Fab")
		)
		(pad "1" smd circle
			(at -0.40005 0 90)
			(size 0 0)
			(layers "F.Cu" "F.Mask" "F.Paste")
			(net "SMB_PDB_SCL")
		)
		(pad "2" smd circle
			(at 0.40005 0 90)
			(size 0 0)
			(layers "F.Cu" "F.Mask" "F.Paste")
			(net "SMB_PDB_R_SCL")
		)
	)
	(footprint ""
		(layer "F.Cu")
		(at 406.273 -29.21 180)
		(property "Reference" "D1"
			(at 0.7366 -1.29667 0)
			(unlocked yes)
			(layer "F.SilkS")
			(effects
				(font
					(size 0.7874 0.5842)
					(thickness 0.1524)
				)
				(justify left)
			)
		)
		(property "Value" ""
			(at 0 0 180)
			(layer "F.Fab")
			(effects
				(font
					(size 1.27 1.27)
				)
			)
		)
		(duplicate_pad_numbers_are_jumpers no)
		(fp_line
			(start 1.16078 0.4826)
			(end -0.64008 0.4826)
			(stroke
				(width 0.1524)
				(type default)
			)
			(layer "F.SilkS")
		)
		(fp_line
			(start 1.16078 -0.4826)
			(end 1.16078 0.4826)
			(stroke
				(width 0.1524)
				(type default)
			)
			(layer "F.SilkS")
		)
		(fp_line
			(start 1.03378 0.4826)
			(end -0.79248 0.4826)
			(stroke
				(width 0.1524)
				(type default)
			)
			(layer "F.SilkS")
		)
		(fp_line
			(start 1.03378 -0.4826)
			(end 1.03378 0.4826)
			(stroke
				(width 0.1524)
				(type default)
			)
			(layer "F.SilkS")
		)
		(fp_line
			(start 0.90678 0.4826)
			(end -0.90678 0.4826)
			(stroke
				(width 0.1524)
				(type default)
			)
			(layer "F.SilkS")
		)
		(fp_line
			(start 0.90678 -0.4826)
			(end 0.90678 0.4826)
			(stroke
				(width 0.1524)
				(type default)
			)
			(layer "F.SilkS")
		)
		(fp_line
			(start -0.64008 -0.4826)
			(end 1.16078 -0.4826)
			(stroke
				(width 0.1524)
				(type default)
			)
			(layer "F.SilkS")
		)
		(fp_line
			(start -0.79248 -0.4826)
			(end 1.03378 -0.4826)
			(stroke
				(width 0.1524)
				(type default)
			)
			(layer "F.SilkS")
		)
		(fp_line
			(start -0.89408 -0.4826)
			(end 0.90678 -0.4826)
			(stroke
				(width 0.1524)
				(type default)
			)
			(layer "F.SilkS")
		)
		(fp_line
			(start -0.90678 0.4826)
			(end -0.90678 -0.4699)
			(stroke
				(width 0.1524)
				(type default)
			)
			(layer "F.SilkS")
		)
		(fp_line
			(start 0.499872 0.249936)
			(end -0.499872 0.249936)
			(stroke
				(width 0.1)
				(type default)
			)
			(layer "F.Fab")
		)
		(fp_line
			(start 0.499872 -0.249936)
			(end 0.499872 0.249936)
			(stroke
				(width 0.1)
				(type default)
			)
			(layer "F.Fab")
		)
		(fp_line
			(start -0.499872 0.249936)
			(end -0.499872 -0.249936)
			(stroke
				(width 0.1)
				(type default)
			)
			(layer "F.Fab")
		)
		(fp_line
			(start -0.499872 -0.249936)
			(end 0.499872 -0.249936)
			(stroke
				(width 0.1)
				(type default)
			)
			(layer "F.Fab")
		)
		(pad "A" smd rect
			(at -0.47498 0 180)
			(size 0.6096 0.7112)
			(layers "F.Cu" "F.Mask" "F.Paste")
			(net "LED_D1_R5")
		)
		(pad "C" smd rect
			(at 0.47498 0 180)
			(size 0.6096 0.7112)
			(layers "F.Cu" "F.Mask" "F.Paste")
			(net "GND")
		)
	)
	(footprint ""
		(layer "F.Cu")
		(at 449.3514 -29.591)
		(property "Reference" "R330"
			(at 0 0 0)
			(layer "F.SilkS")
			(hide yes)
			(effects
				(font
					(size 1.27 1.27)
				)
			)
		)
		(property "Value" ""
			(at 0 0 0)
			(layer "F.Fab")
			(effects
				(font
					(size 1.27 1.27)
				)
			)
		)
		(duplicate_pad_numbers_are_jumpers no)
		(fp_line
			(start -0.7874 -0.4064)
			(end 0.7874 -0.4064)
			(stroke
				(width 0.1524)
				(type default)
			)
			(layer "F.SilkS")
		)
		(fp_line
			(start -0.7874 0.4064)
			(end -0.7874 -0.4064)
			(stroke
				(width 0.1524)
				(type default)
			)
			(layer "F.SilkS")
		)
		(fp_line
			(start 0.7874 -0.4064)
			(end 0.7874 0.4064)
			(stroke
				(width 0.1524)
				(type default)
			)
			(layer "F.SilkS")
		)
		(fp_line
			(start 0.7874 0.4064)
			(end -0.7874 0.4064)
			(stroke
				(width 0.1524)
				(type default)
			)
			(layer "F.SilkS")
		)
		(fp_line
			(start -0.67945 -0.305054)
			(end -0.12065 -0.305054)
			(stroke
				(width 0.1)
				(type default)
			)
			(layer "F.Fab")
		)
		(fp_line
			(start -0.67945 0.3048)
			(end -0.67945 -0.305054)
			(stroke
				(width 0.1)
				(type default)
			)
			(layer "F.Fab")
		)
		(fp_line
			(start -0.12065 -0.305054)
			(end -0.12065 -0.2794)
			(stroke
				(width 0.1)
				(type default)
			)
			(layer "F.Fab")
		)
		(fp_line
			(start -0.12065 -0.2794)
			(end 0.12065 -0.2794)
			(stroke
				(width 0.1)
				(type default)
			)
			(layer "F.Fab")
		)
		(fp_line
			(start -0.12065 0.2794)
			(end -0.12065 0.3048)
			(stroke
				(width 0.1)
				(type default)
			)
			(layer "F.Fab")
		)
		(fp_line
			(start -0.12065 0.3048)
			(end -0.67945 0.3048)
			(stroke
				(width 0.1)
				(type default)
			)
			(layer "F.Fab")
		)
		(fp_line
			(start 0.120396 0.2794)
			(end -0.12065 0.2794)
			(stroke
				(width 0.1)
				(type default)
			)
			(layer "F.Fab")
		)
		(fp_line
			(start 0.120396 0.3048)
			(end 0.120396 0.2794)
			(stroke
				(width 0.1)
				(type default)
			)
			(layer "F.Fab")
		)
		(fp_line
			(start 0.12065 -0.3048)
			(end 0.67945 -0.3048)
			(stroke
				(width 0.1)
				(type default)
			)
			(layer "F.Fab")
		)
		(fp_line
			(start 0.12065 -0.2794)
			(end 0.12065 -0.3048)
			(stroke
				(width 0.1)
				(type default)
			)
			(layer "F.Fab")
		)
		(fp_line
			(start 0.67945 -0.3048)
			(end 0.67945 0.3048)
			(stroke
				(width 0.1)
				(type default)
			)
			(layer "F.Fab")
		)
		(fp_line
			(start 0.67945 0.3048)
			(end 0.120396 0.3048)
			(stroke
				(width 0.1)
				(type default)
			)
			(layer "F.Fab")
		)
		(pad "1" smd circle
			(at -0.40005 0)
			(size 0 0)
			(layers "F.Cu" "F.Mask" "F.Paste")
			(net "SMB_PDB_FAN_1_SCL")
		)
		(pad "2" smd circle
			(at 0.40005 0)
			(size 0 0)
			(layers "F.Cu" "F.Mask" "F.Paste")
			(net "P3V3_AUX")
		)
	)
	(footprint ""
		(layer "F.Cu")
		(at 411.099 -46.736 -90)
		(property "Reference" "R52"
			(at 0 0 270)
			(layer "F.SilkS")
			(hide yes)
			(effects
				(font
					(size 1.27 1.27)
				)
			)
		)
		(property "Value" ""
			(at 0 0 270)
			(layer "F.Fab")
			(effects
				(font
					(size 1.27 1.27)
				)
			)
		)
		(duplicate_pad_numbers_are_jumpers no)
		(fp_line
			(start -0.7874 0.4064)
			(end -0.7874 -0.4064)
			(stroke
				(width 0.1524)
				(type default)
			)
			(layer "F.SilkS")
		)
		(fp_line
			(start 0.7874 0.4064)
			(end -0.7874 0.4064)
			(stroke
				(width 0.1524)
				(type default)
			)
			(layer "F.SilkS")
		)
		(fp_line
			(start -0.7874 -0.4064)
			(end 0.7874 -0.4064)
			(stroke
				(width 0.1524)
				(type default)
			)
			(layer "F.SilkS")
		)
		(fp_line
			(start 0.7874 -0.4064)
			(end 0.7874 0.4064)
			(stroke
				(width 0.1524)
				(type default)
			)
			(layer "F.SilkS")
		)
		(fp_line
			(start -0.67945 0.3048)
			(end -0.67945 -0.305054)
			(stroke
				(width 0.1)
				(type default)
			)
			(layer "F.Fab")
		)
		(fp_line
			(start -0.12065 0.3048)
			(end -0.67945 0.3048)
			(stroke
				(width 0.1)
				(type default)
			)
			(layer "F.Fab")
		)
		(fp_line
			(start 0.120396 0.3048)
			(end 0.120396 0.2794)
			(stroke
				(width 0.1)
				(type default)
			)
			(layer "F.Fab")
		)
		(fp_line
			(start 0.67945 0.3048)
			(end 0.120396 0.3048)
			(stroke
				(width 0.1)
				(type default)
			)
			(layer "F.Fab")
		)
		(fp_line
			(start -0.12065 0.2794)
			(end -0.12065 0.3048)
			(stroke
				(width 0.1)
				(type default)
			)
			(layer "F.Fab")
		)
		(fp_line
			(start 0.120396 0.2794)
			(end -0.12065 0.2794)
			(stroke
				(width 0.1)
				(type default)
			)
			(layer "F.Fab")
		)
		(fp_line
			(start -0.12065 -0.2794)
			(end 0.12065 -0.2794)
			(stroke
				(width 0.1)
				(type default)
			)
			(layer "F.Fab")
		)
		(fp_line
			(start 0.12065 -0.2794)
			(end 0.12065 -0.3048)
			(stroke
				(width 0.1)
				(type default)
			)
			(layer "F.Fab")
		)
		(fp_line
			(start 0.12065 -0.3048)
			(end 0.67945 -0.3048)
			(stroke
				(width 0.1)
				(type default)
			)
			(layer "F.Fab")
		)
		(fp_line
			(start 0.67945 -0.3048)
			(end 0.67945 0.3048)
			(stroke
				(width 0.1)
				(type default)
			)
			(layer "F.Fab")
		)
		(fp_line
			(start -0.67945 -0.305054)
			(end -0.12065 -0.305054)
			(stroke
				(width 0.1)
				(type default)
			)
			(layer "F.Fab")
		)
		(fp_line
			(start -0.12065 -0.305054)
			(end -0.12065 -0.2794)
			(stroke
				(width 0.1)
				(type default)
			)
			(layer "F.Fab")
		)
		(pad "1" smd circle
			(at -0.40005 0 270)
			(size 0 0)
			(layers "F.Cu" "F.Mask" "F.Paste")
			(net "P3V3_AUX")
		)
		(pad "2" smd circle
			(at 0.40005 0 270)
			(size 0 0)
			(layers "F.Cu" "F.Mask" "F.Paste")
			(net "PCA9555_A1")
		)
	)
	(footprint ""
		(layer "F.Cu")
		(at 443.509908 -83.825842 90)
		(property "Reference" "PC55"
			(at 0 0 90)
			(layer "F.SilkS")
			(hide yes)
			(effects
				(font
					(size 1.27 1.27)
				)
			)
		)
		(property "Value" ""
			(at 0 0 90)
			(layer "F.Fab")
			(effects
				(font
					(size 1.27 1.27)
				)
			)
		)
		(duplicate_pad_numbers_are_jumpers no)
		(fp_line
			(start 0.7874 -0.4064)
			(end 0.7874 0.4064)
			(stroke
				(width 0.1524)
				(type default)
			)
			(layer "F.SilkS")
		)
		(fp_line
			(start -0.7874 -0.4064)
			(end 0.7874 -0.4064)
			(stroke
				(width 0.1524)
				(type default)
			)
			(layer "F.SilkS")
		)
		(fp_line
			(start 0.7874 0.4064)
			(end -0.7874 0.4064)
			(stroke
				(width 0.1524)
				(type default)
			)
			(layer "F.SilkS")
		)
		(fp_line
			(start -0.7874 0.4064)
			(end -0.7874 -0.4064)
			(stroke
				(width 0.1524)
				(type default)
			)
			(layer "F.SilkS")
		)
		(fp_line
			(start -0.12065 -0.305054)
			(end -0.12065 -0.2794)
			(stroke
				(width 0.1)
				(type default)
			)
			(layer "F.Fab")
		)
		(fp_line
			(start -0.67945 -0.305054)
			(end -0.12065 -0.305054)
			(stroke
				(width 0.1)
				(type default)
			)
			(layer "F.Fab")
		)
		(fp_line
			(start 0.67945 -0.3048)
			(end 0.67945 0.3048)
			(stroke
				(width 0.1)
				(type default)
			)
			(layer "F.Fab")
		)
		(fp_line
			(start 0.12065 -0.3048)
			(end 0.67945 -0.3048)
			(stroke
				(width 0.1)
				(type default)
			)
			(layer "F.Fab")
		)
		(fp_line
			(start 0.12065 -0.2794)
			(end 0.12065 -0.3048)
			(stroke
				(width 0.1)
				(type default)
			)
			(layer "F.Fab")
		)
		(fp_line
			(start -0.12065 -0.2794)
			(end 0.12065 -0.2794)
			(stroke
				(width 0.1)
				(type default)
			)
			(layer "F.Fab")
		)
		(fp_line
			(start 0.120396 0.2794)
			(end -0.12065 0.2794)
			(stroke
				(width 0.1)
				(type default)
			)
			(layer "F.Fab")
		)
		(fp_line
			(start -0.12065 0.2794)
			(end -0.12065 0.3048)
			(stroke
				(width 0.1)
				(type default)
			)
			(layer "F.Fab")
		)
		(fp_line
			(start 0.67945 0.3048)
			(end 0.120396 0.3048)
			(stroke
				(width 0.1)
				(type default)
			)
			(layer "F.Fab")
		)
		(fp_line
			(start 0.120396 0.3048)
			(end 0.120396 0.2794)
			(stroke
				(width 0.1)
				(type default)
			)
			(layer "F.Fab")
		)
		(fp_line
			(start -0.12065 0.3048)
			(end -0.67945 0.3048)
			(stroke
				(width 0.1)
				(type default)
			)
			(layer "F.Fab")
		)
		(fp_line
			(start -0.67945 0.3048)
			(end -0.67945 -0.305054)
			(stroke
				(width 0.1)
				(type default)
			)
			(layer "F.Fab")
		)
		(pad "1" smd circle
			(at -0.40005 0 90)
			(size 0 0)
			(layers "F.Cu" "F.Mask" "F.Paste")
			(net "P3V3_HPDB_VCC")
		)
		(pad "2" smd circle
			(at 0.40005 0 90)
			(size 0 0)
			(layers "F.Cu" "F.Mask" "F.Paste")
			(net "GND")
		)
	)
	(footprint ""
		(layer "F.Cu")
		(at 428.00016 -83.999832 180)
		(property "Reference" "H13"
			(at 1.00076 -5.286502 0)
			(unlocked yes)
			(layer "F.SilkS")
			(effects
				(font
					(size 0.7874 0.5842)
					(thickness 0.1524)
				)
				(justify left)
			)
		)
		(property "Value" ""
			(at 0 0 180)
			(layer "F.Fab")
			(effects
				(font
					(size 1.27 1.27)
				)
			)
		)
		(duplicate_pad_numbers_are_jumpers no)
		(pad "1" thru_hole oval
			(at 0 0 180)
			(size 9.017 14.0208)
			(drill 3.0226
				(offset 0 2.499868)
			)
			(layers "*.Cu" "*.Mask")
			(remove_unused_layers no)
			(net "GND")
			(clearance -1.500378)
			(padstack
				(mode front_inner_back)
				(layer "Inner"
					(shape circle)
					(size 0 0)
					(clearance 0)
				)
				(layer "B.Cu"
					(shape oval)
					(size 9.017 14.0208)
					(offset 0 2.499868)
					(clearance -1.500378)
				)
			)
		)
	)
	(footprint ""
		(layer "F.Cu")
		(at 391.0584 -33.02 -90)
		(property "Reference" "PR98"
			(at 0 0 270)
			(layer "F.SilkS")
			(hide yes)
			(effects
				(font
					(size 1.27 1.27)
				)
			)
		)
		(property "Value" ""
			(at 0 0 270)
			(layer "F.Fab")
			(effects
				(font
					(size 1.27 1.27)
				)
			)
		)
		(duplicate_pad_numbers_are_jumpers no)
		(fp_line
			(start -2.234946 0.9271)
			(end -2.234946 -0.9271)
			(stroke
				(width 0.1524)
				(type default)
			)
			(layer "F.SilkS")
		)
		(fp_line
			(start 2.234946 0.9271)
			(end -2.234946 0.9271)
			(stroke
				(width 0.1524)
				(type default)
			)
			(layer "F.SilkS")
		)
		(fp_line
			(start -2.234946 -0.9271)
			(end 2.234946 -0.9271)
			(stroke
				(width 0.1524)
				(type default)
			)
			(layer "F.SilkS")
		)
		(fp_line
			(start 2.234946 -0.9271)
			(end 2.234946 0.9271)
			(stroke
				(width 0.1524)
				(type default)
			)
			(layer "F.SilkS")
		)
		(fp_line
			(start -1.575054 0.824992)
			(end 1.575054 0.824992)
			(stroke
				(width 0.1)
				(type default)
			)
			(layer "F.Fab")
		)
		(fp_line
			(start 1.575054 0.824992)
			(end 1.575054 -0.824992)
			(stroke
				(width 0.1)
				(type default)
			)
			(layer "F.Fab")
		)
		(fp_line
			(start -1.575054 -0.824992)
			(end -1.575054 0.824992)
			(stroke
				(width 0.1)
				(type default)
			)
			(layer "F.Fab")
		)
		(fp_line
			(start 1.575054 -0.824992)
			(end -1.575054 -0.824992)
			(stroke
				(width 0.1)
				(type default)
			)
			(layer "F.Fab")
		)
		(pad "1" smd rect
			(at -1.599946 0 270)
			(size 1.016 1.6002)
			(layers "F.Cu" "F.Mask" "F.Paste")
			(net "P52V_HS1")
		)
		(pad "2" smd rect
			(at 1.599946 0 270)
			(size 1.016 1.6002)
			(layers "F.Cu" "F.Mask" "F.Paste")
			(net "P52V_HS1_EN_DISCHARGE_N")
		)
	)
	(footprint ""
		(layer "F.Cu")
		(at 442.595 -37.465)
		(property "Reference" "U2"
			(at -4.1148 -1.99263 0)
			(unlocked yes)
			(layer "F.SilkS")
			(effects
				(font
					(size 0.7874 0.5842)
					(thickness 0.1524)
				)
				(justify left)
			)
		)
		(property "Value" ""
			(at 0 0 0)
			(layer "F.Fab")
			(effects
				(font
					(size 1.27 1.27)
				)
			)
		)
		(duplicate_pad_numbers_are_jumpers no)
		(fp_line
			(start -1.3716 -1.524)
			(end -0.508 -1.524)
			(stroke
				(width 0.1524)
				(type default)
			)
			(layer "F.SilkS")
		)
		(fp_line
			(start -1.3716 1.524)
			(end -1.3716 -1.524)
			(stroke
				(width 0.1524)
				(type default)
			)
			(layer "F.SilkS")
		)
		(fp_line
			(start -0.508 -1.524)
			(end 0 -1.016)
			(stroke
				(width 0.1524)
				(type default)
			)
			(layer "F.SilkS")
		)
		(fp_line
			(start 0 -1.016)
			(end 0.508 -1.524)
			(stroke
				(width 0.1524)
				(type default)
			)
			(layer "F.SilkS")
		)
		(fp_line
			(start 0.508 -1.524)
			(end 1.3716 -1.524)
			(stroke
				(width 0.1524)
				(type default)
			)
			(layer "F.SilkS")
		)
		(fp_line
			(start 1.3716 -1.524)
			(end 1.3716 1.524)
			(stroke
				(width 0.1524)
				(type default)
			)
			(layer "F.SilkS")
		)
		(fp_line
			(start 1.3716 1.524)
			(end -1.3716 1.524)
			(stroke
				(width 0.1524)
				(type default)
			)
			(layer "F.SilkS")
		)
		(fp_poly
			(pts
				(xy -2.684272 -1.84912) (xy -2.059432 -1.84912) (xy -2.3876 -1.2954)
			)
			(stroke
				(width 0)
				(type default)
			)
			(fill yes)
			(layer "F.SilkS")
		)
		(fp_line
			(start -2.54 -1.0668)
			(end -1.5494 -1.0668)
			(stroke
				(width 0.1)
				(type default)
			)
			(layer "F.Fab")
		)
		(fp_line
			(start -2.54 1.0668)
			(end -2.54 -1.0668)
			(stroke
				(width 0.1)
				(type default)
			)
			(layer "F.Fab")
		)
		(fp_line
			(start -1.5494 -1.524)
			(end 1.5494 -1.524)
			(stroke
				(width 0.1)
				(type default)
			)
			(layer "F.Fab")
		)
		(fp_line
			(start -1.5494 -1.0668)
			(end -1.5494 -1.524)
			(stroke
				(width 0.1)
				(type default)
			)
			(layer "F.Fab")
		)
		(fp_line
			(start -1.5494 1.0668)
			(end -2.54 1.0668)
			(stroke
				(width 0.1)
				(type default)
			)
			(layer "F.Fab")
		)
		(fp_line
			(start -1.5494 1.0668)
			(end -1.5494 -1.0668)
			(stroke
				(width 0.1)
				(type default)
			)
			(layer "F.Fab")
		)
		(fp_line
			(start -1.5494 1.524)
			(end -1.5494 1.0668)
			(stroke
				(width 0.1)
				(type default)
			)
			(layer "F.Fab")
		)
		(fp_line
			(start 1.5494 -1.524)
			(end 1.5494 -1.0668)
			(stroke
				(width 0.1)
				(type default)
			)
			(layer "F.Fab")
		)
		(fp_line
			(start 1.5494 -1.0668)
			(end 1.5494 1.0668)
			(stroke
				(width 0.1)
				(type default)
			)
			(layer "F.Fab")
		)
		(fp_line
			(start 1.5494 -1.0668)
			(end 2.54 -1.0668)
			(stroke
				(width 0.1)
				(type default)
			)
			(layer "F.Fab")
		)
		(fp_line
			(start 1.5494 1.0668)
			(end 1.5494 1.524)
			(stroke
				(width 0.1)
				(type default)
			)
			(layer "F.Fab")
		)
		(fp_line
			(start 1.5494 1.524)
			(end -1.5494 1.524)
			(stroke
				(width 0.1)
				(type default)
			)
			(layer "F.Fab")
		)
		(fp_line
			(start 2.54 -1.0668)
			(end 2.54 1.0668)
			(stroke
				(width 0.1)
				(type default)
			)
			(layer "F.Fab")
		)
		(fp_line
			(start 2.54 1.0668)
			(end 1.5494 1.0668)
			(stroke
				(width 0.1)
				(type default)
			)
			(layer "F.Fab")
		)
		(fp_poly
			(pts
				(xy -3.60172 -0.719328) (xy -3.60172 -1.344168) (xy -3.048 -1.016)
			)
			(stroke
				(width 0)
				(type default)
			)
			(fill yes)
			(layer "F.Fab")
		)
		(pad "1" smd rect
			(at -2.232406 -0.975106 270)
			(size 0.3556 1.4224)
			(layers "F.Cu" "F.Mask" "F.Paste")
			(net "MB_P52V_I2C_EN")
		)
		(pad "2" smd rect
			(at -2.232406 -0.32512 270)
			(size 0.3556 1.4224)
			(layers "F.Cu" "F.Mask" "F.Paste")
			(net "SMB_P52V_PDB_SCL_R")
		)
		(pad "3" smd rect
			(at -2.232406 0.32512 270)
			(size 0.3556 1.4224)
			(layers "F.Cu" "F.Mask" "F.Paste")
			(net "SMB_P52V_SCL")
		)
		(pad "4" smd rect
			(at -2.232406 0.975106 270)
			(size 0.3556 1.4224)
			(layers "F.Cu" "F.Mask" "F.Paste")
			(net "GND")
		)
		(pad "5" smd rect
			(at 2.232406 0.975106 270)
			(size 0.3556 1.4224)
			(layers "F.Cu" "F.Mask" "F.Paste")
			(net "NC_U2_READY")
		)
		(pad "6" smd rect
			(at 2.232406 0.32512 270)
			(size 0.3556 1.4224)
			(layers "F.Cu" "F.Mask" "F.Paste")
			(net "SMB_P52V_SDA")
		)
		(pad "7" smd rect
			(at 2.232406 -0.32512 270)
			(size 0.3556 1.4224)
			(layers "F.Cu" "F.Mask" "F.Paste")
			(net "SMB_P52V_PDB_SDA_R")
		)
		(pad "8" smd rect
			(at 2.232406 -0.975106 270)
			(size 0.3556 1.4224)
			(layers "F.Cu" "F.Mask" "F.Paste")
			(net "P3V3_AUX")
		)
	)
	(footprint ""
		(layer "F.Cu")
		(at 416.3314 -48.514)
		(property "Reference" "U29"
			(at -0.74803 -3.2385 90)
			(unlocked yes)
			(layer "F.SilkS")
			(effects
				(font
					(size 0.7874 0.5842)
					(thickness 0.1524)
				)
				(justify left)
			)
		)
		(property "Value" ""
			(at 0 0 0)
			(layer "F.Fab")
			(effects
				(font
					(size 1.27 1.27)
				)
			)
		)
		(duplicate_pad_numbers_are_jumpers no)
		(fp_line
			(start -1.603248 -1.500124)
			(end 1.603248 -1.500124)
			(stroke
				(width 0.1524)
				(type default)
			)
			(layer "F.SilkS")
		)
		(fp_line
			(start -1.603248 1.500124)
			(end -1.603248 -1.500124)
			(stroke
				(width 0.1524)
				(type default)
			)
			(layer "F.SilkS")
		)
		(fp_line
			(start 1.603248 -1.500124)
			(end 1.603248 1.500124)
			(stroke
				(width 0.1524)
				(type default)
			)
			(layer "F.SilkS")
		)
		(fp_line
			(start 1.603248 1.500124)
			(end -1.603248 1.500124)
			(stroke
				(width 0.1524)
				(type default)
			)
			(layer "F.SilkS")
		)
		(fp_line
			(start -1.249934 -1.169924)
			(end -1.249934 -0.729996)
			(stroke
				(width 0.1)
				(type default)
			)
			(layer "F.Fab")
		)
		(fp_line
			(start -1.249934 -0.729996)
			(end -0.6985 -0.729996)
			(stroke
				(width 0.1)
				(type default)
			)
			(layer "F.Fab")
		)
		(fp_line
			(start -1.249934 0.729996)
			(end -1.249934 1.169924)
			(stroke
				(width 0.1)
				(type default)
			)
			(layer "F.Fab")
		)
		(fp_line
			(start -1.249934 1.169924)
			(end -0.700024 1.169924)
			(stroke
				(width 0.1)
				(type default)
			)
			(layer "F.Fab")
		)
		(fp_line
			(start -0.700024 -1.500124)
			(end -0.700024 -1.169924)
			(stroke
				(width 0.1)
				(type default)
			)
			(layer "F.Fab")
		)
		(fp_line
			(start -0.700024 -1.169924)
			(end -1.249934 -1.169924)
			(stroke
				(width 0.1)
				(type default)
			)
			(layer "F.Fab")
		)
		(fp_line
			(start -0.700024 1.169924)
			(end -0.700024 1.500124)
			(stroke
				(width 0.1)
				(type default)
			)
			(layer "F.Fab")
		)
		(fp_line
			(start -0.700024 1.500124)
			(end 0.700024 1.500124)
			(stroke
				(width 0.1)
				(type default)
			)
			(layer "F.Fab")
		)
		(fp_line
			(start -0.6985 -0.729996)
			(end -0.6985 0.729996)
			(stroke
				(width 0.1)
				(type default)
			)
			(layer "F.Fab")
		)
		(fp_line
			(start -0.6985 0.729996)
			(end -1.249934 0.729996)
			(stroke
				(width 0.1)
				(type default)
			)
			(layer "F.Fab")
		)
		(fp_line
			(start 0.700024 -1.500124)
			(end -0.700024 -1.500124)
			(stroke
				(width 0.1)
				(type default)
			)
			(layer "F.Fab")
		)
		(fp_line
			(start 0.700024 -0.219964)
			(end 0.700024 -1.500124)
			(stroke
				(width 0.1)
				(type default)
			)
			(layer "F.Fab")
		)
		(fp_line
			(start 0.700024 0.219964)
			(end 1.249934 0.219964)
			(stroke
				(width 0.1)
				(type default)
			)
			(layer "F.Fab")
		)
		(fp_line
			(start 0.700024 1.500124)
			(end 0.700024 0.219964)
			(stroke
				(width 0.1)
				(type default)
			)
			(layer "F.Fab")
		)
		(fp_line
			(start 1.249934 -0.219964)
			(end 0.700024 -0.219964)
			(stroke
				(width 0.1)
				(type default)
			)
			(layer "F.Fab")
		)
		(fp_line
			(start 1.249934 0.219964)
			(end 1.249934 -0.219964)
			(stroke
				(width 0.1)
				(type default)
			)
			(layer "F.Fab")
		)
		(fp_rect
			(start -0.700024 1.500124)
			(end 0.700024 -1.500124)
			(stroke
				(width 0)
				(type default)
			)
			(fill no)
			(layer "F.Fab")
		)
		(pad "D" smd rect
			(at 0.999998 0 270)
			(size 0.8128 0.9144)
			(layers "F.Cu" "F.Mask" "F.Paste")
			(net "PWRGD_P52V_HS1_4287_PG")
		)
		(pad "G" smd rect
			(at -0.999998 -0.94996 270)
			(size 0.8128 0.9144)
			(layers "F.Cu" "F.Mask" "F.Paste")
			(net "PWRGD_P52V_HS1_4287_PG_R_N")
		)
		(pad "S" smd rect
			(at -0.999998 0.94996 270)
			(size 0.8128 0.9144)
			(layers "F.Cu" "F.Mask" "F.Paste")
			(net "GND")
		)
	)
	(footprint ""
		(layer "F.Cu")
		(at 406.146 -33.274 180)
		(property "Reference" "R44"
			(at 0 0 180)
			(layer "F.SilkS")
			(hide yes)
			(effects
				(font
					(size 1.27 1.27)
				)
			)
		)
		(property "Value" ""
			(at 0 0 180)
			(layer "F.Fab")
			(effects
				(font
					(size 1.27 1.27)
				)
			)
		)
		(duplicate_pad_numbers_are_jumpers no)
		(fp_line
			(start 2.234946 0.9271)
			(end -2.234946 0.9271)
			(stroke
				(width 0.1524)
				(type default)
			)
			(layer "F.SilkS")
		)
		(fp_line
			(start 2.234946 -0.9271)
			(end 2.234946 0.9271)
			(stroke
				(width 0.1524)
				(type default)
			)
			(layer "F.SilkS")
		)
		(fp_line
			(start -2.234946 0.9271)
			(end -2.234946 -0.9271)
			(stroke
				(width 0.1524)
				(type default)
			)
			(layer "F.SilkS")
		)
		(fp_line
			(start -2.234946 -0.9271)
			(end 2.234946 -0.9271)
			(stroke
				(width 0.1524)
				(type default)
			)
			(layer "F.SilkS")
		)
		(fp_line
			(start 1.575054 0.824992)
			(end 1.575054 -0.824992)
			(stroke
				(width 0.1)
				(type default)
			)
			(layer "F.Fab")
		)
		(fp_line
			(start 1.575054 -0.824992)
			(end -1.575054 -0.824992)
			(stroke
				(width 0.1)
				(type default)
			)
			(layer "F.Fab")
		)
		(fp_line
			(start -1.575054 0.824992)
			(end 1.575054 0.824992)
			(stroke
				(width 0.1)
				(type default)
			)
			(layer "F.Fab")
		)
		(fp_line
			(start -1.575054 -0.824992)
			(end -1.575054 0.824992)
			(stroke
				(width 0.1)
				(type default)
			)
			(layer "F.Fab")
		)
		(pad "1" smd rect
			(at -1.599946 0 180)
			(size 1.016 1.6002)
			(layers "F.Cu" "F.Mask" "F.Paste")
			(net "LED_D1_R3")
		)
		(pad "2" smd rect
			(at 1.599946 0 180)
			(size 1.016 1.6002)
			(layers "F.Cu" "F.Mask" "F.Paste")
			(net "LED_D1_R4")
		)
	)
	(footprint ""
		(layer "F.Cu")
		(at 323.13626 -74.6506 180)
		(property "Reference" "PQ32"
			(at -9.628886 -3.917188 0)
			(unlocked yes)
			(layer "F.SilkS")
			(effects
				(font
					(size 0.7874 0.5842)
					(thickness 0.1524)
				)
				(justify left)
			)
		)
		(property "Value" ""
			(at 0 0 180)
			(layer "F.Fab")
			(effects
				(font
					(size 1.27 1.27)
				)
			)
		)
		(duplicate_pad_numbers_are_jumpers no)
		(fp_line
			(start 7.649972 4.99999)
			(end 7.649972 -4.99999)
			(stroke
				(width 0.1524)
				(type default)
			)
			(layer "F.SilkS")
		)
		(fp_line
			(start 7.649972 -4.99999)
			(end 7.630414 -4.99999)
			(stroke
				(width 0.1524)
				(type default)
			)
			(layer "F.SilkS")
		)
		(fp_line
			(start 7.630414 4.99999)
			(end 7.649972 4.99999)
			(stroke
				(width 0.1524)
				(type default)
			)
			(layer "F.SilkS")
		)
		(fp_line
			(start 5.115814 -4.99999)
			(end -7.649972 -4.99999)
			(stroke
				(width 0.1524)
				(type default)
			)
			(layer "F.SilkS")
		)
		(fp_line
			(start -7.649972 4.99999)
			(end 5.115814 4.99999)
			(stroke
				(width 0.1524)
				(type default)
			)
			(layer "F.SilkS")
		)
		(fp_line
			(start -7.649972 3.3274)
			(end -7.649972 4.99999)
			(stroke
				(width 0.1524)
				(type default)
			)
			(layer "F.SilkS")
		)
		(fp_line
			(start -7.649972 -1.7526)
			(end -7.649972 1.7526)
			(stroke
				(width 0.1524)
				(type default)
			)
			(layer "F.SilkS")
		)
		(fp_line
			(start -7.649972 -4.99999)
			(end -7.649972 -3.3274)
			(stroke
				(width 0.1524)
				(type default)
			)
			(layer "F.SilkS")
		)
		(fp_line
			(start 7.649972 4.99999)
			(end 7.649972 -4.99999)
			(stroke
				(width 0.1)
				(type default)
			)
			(layer "F.Fab")
		)
		(fp_line
			(start 7.649972 -4.99999)
			(end -7.649972 -4.99999)
			(stroke
				(width 0.1)
				(type default)
			)
			(layer "F.Fab")
		)
		(fp_line
			(start -7.649972 4.99999)
			(end 7.649972 4.99999)
			(stroke
				(width 0.1)
				(type default)
			)
			(layer "F.Fab")
		)
		(fp_line
			(start -7.649972 -4.99999)
			(end -7.649972 4.99999)
			(stroke
				(width 0.1)
				(type default)
			)
			(layer "F.Fab")
		)
		(pad "D" smd circle
			(at 2.15011 0 180)
			(size 0 0)
			(layers "F.Cu" "F.Mask" "F.Paste")
			(net "P52V_HS1_DRAIN_1")
		)
		(pad "G" smd rect
			(at -7.050024 -2.54 90)
			(size 1.3208 3.0988)
			(layers "F.Cu" "F.Mask" "F.Paste")
			(net "P52V_HS1_GATE1")
		)
		(pad "S" smd rect
			(at -7.050024 2.54 90)
			(size 1.3208 3.0988)
			(layers "F.Cu" "F.Mask" "F.Paste")
			(net "P52V_HS1")
		)
		(zone
			(layer "F.Cu")
			(hatch none 0.5)
			(connect_pads
				(clearance 0)
			)
			(min_thickness 0.25)
			(keepout
				(tracks not_allowed)
				(vias allowed)
				(pads allowed)
				(copperpour not_allowed)
				(footprints allowed)
			)
			(placement
				(enabled no)
				(sheetname "")
			)
			(fill
				(thermal_gap 0.5)
				(thermal_bridge_width 0.5)
				(island_removal_mode 0)
			)
			(polygon
				(pts
					(xy 317.95466 -69.6722) (xy 330.78166 -69.6722) (xy 330.78166 -71.3994) (xy 328.57186 -71.3994)
					(xy 328.57186 -72.8218) (xy 330.78166 -72.8218) (xy 330.78166 -76.4794) (xy 328.57186 -76.4794)
					(xy 328.57186 -77.9018) (xy 330.78166 -77.9018) (xy 330.78166 -79.629) (xy 317.95466 -79.629) (xy 317.95466 -78.4606)
					(xy 324.15226 -78.4606) (xy 324.15226 -70.8406) (xy 317.95466 -70.8406)
				)
			)
		)
	)
	(footprint ""
		(layer "F.Cu")
		(at 124.483876 -52.0954)
		(property "Reference" "PQ40"
			(at 8.913114 -3.609848 0)
			(unlocked yes)
			(layer "F.SilkS")
			(effects
				(font
					(size 0.7874 0.5842)
					(thickness 0.1524)
				)
				(justify left)
			)
		)
		(property "Value" ""
			(at 0 0 0)
			(layer "F.Fab")
			(effects
				(font
					(size 1.27 1.27)
				)
			)
		)
		(duplicate_pad_numbers_are_jumpers no)
		(fp_line
			(start -7.649972 -4.99999)
			(end -7.649972 -3.3274)
			(stroke
				(width 0.1524)
				(type default)
			)
			(layer "F.SilkS")
		)
		(fp_line
			(start -7.649972 -1.7526)
			(end -7.649972 1.7526)
			(stroke
				(width 0.1524)
				(type default)
			)
			(layer "F.SilkS")
		)
		(fp_line
			(start -7.649972 3.3274)
			(end -7.649972 4.99999)
			(stroke
				(width 0.1524)
				(type default)
			)
			(layer "F.SilkS")
		)
		(fp_line
			(start -7.649972 4.99999)
			(end 5.115814 4.99999)
			(stroke
				(width 0.1524)
				(type default)
			)
			(layer "F.SilkS")
		)
		(fp_line
			(start 5.115814 -4.99999)
			(end -7.649972 -4.99999)
			(stroke
				(width 0.1524)
				(type default)
			)
			(layer "F.SilkS")
		)
		(fp_line
			(start 7.630414 4.99999)
			(end 7.649972 4.99999)
			(stroke
				(width 0.1524)
				(type default)
			)
			(layer "F.SilkS")
		)
		(fp_line
			(start 7.649972 -4.99999)
			(end 7.630414 -4.99999)
			(stroke
				(width 0.1524)
				(type default)
			)
			(layer "F.SilkS")
		)
		(fp_line
			(start 7.649972 4.99999)
			(end 7.649972 -4.99999)
			(stroke
				(width 0.1524)
				(type default)
			)
			(layer "F.SilkS")
		)
		(fp_line
			(start -7.649972 -4.99999)
			(end -7.649972 4.99999)
			(stroke
				(width 0.1)
				(type default)
			)
			(layer "F.Fab")
		)
		(fp_line
			(start -7.649972 4.99999)
			(end 7.649972 4.99999)
			(stroke
				(width 0.1)
				(type default)
			)
			(layer "F.Fab")
		)
		(fp_line
			(start 7.649972 -4.99999)
			(end -7.649972 -4.99999)
			(stroke
				(width 0.1)
				(type default)
			)
			(layer "F.Fab")
		)
		(fp_line
			(start 7.649972 4.99999)
			(end 7.649972 -4.99999)
			(stroke
				(width 0.1)
				(type default)
			)
			(layer "F.Fab")
		)
		(pad "D" smd circle
			(at 2.15011 0)
			(size 0 0)
			(layers "F.Cu" "F.Mask" "F.Paste")
			(net "P52V_HS2_DRAIN_1")
		)
		(pad "G" smd rect
			(at -7.050024 -2.54 270)
			(size 1.3208 3.0988)
			(layers "F.Cu" "F.Mask" "F.Paste")
			(net "P52V_HS2_GATE3")
		)
		(pad "S" smd rect
			(at -7.050024 2.54 270)
			(size 1.3208 3.0988)
			(layers "F.Cu" "F.Mask" "F.Paste")
			(net "P52V_HS2")
		)
		(zone
			(layer "F.Cu")
			(hatch none 0.5)
			(connect_pads
				(clearance 0)
			)
			(min_thickness 0.25)
			(keepout
				(tracks not_allowed)
				(vias allowed)
				(pads allowed)
				(copperpour not_allowed)
				(footprints allowed)
			)
			(placement
				(enabled no)
				(sheetname "")
			)
			(fill
				(thermal_gap 0.5)
				(thermal_bridge_width 0.5)
				(island_removal_mode 0)
			)
			(polygon
				(pts
					(xy 129.665476 -57.0738) (xy 116.838476 -57.0738) (xy 116.838476 -55.3466) (xy 119.048276 -55.3466)
					(xy 119.048276 -53.9242) (xy 116.838476 -53.9242) (xy 116.838476 -50.2666) (xy 119.048276 -50.2666)
					(xy 119.048276 -48.8442) (xy 116.838476 -48.8442) (xy 116.838476 -47.117) (xy 129.665476 -47.117)
					(xy 129.665476 -48.2854) (xy 123.467876 -48.2854) (xy 123.467876 -55.9054) (xy 129.665476 -55.9054)
				)
			)
		)
	)
	(footprint ""
		(layer "F.Cu")
		(at 47.513494 -23.114)
		(property "Reference" "PR106"
			(at -7.991094 0.28067 0)
			(unlocked yes)
			(layer "F.SilkS")
			(effects
				(font
					(size 0.7874 0.5842)
					(thickness 0.1524)
				)
				(justify left)
			)
		)
		(property "Value" ""
			(at 0 0 0)
			(layer "F.Fab")
			(effects
				(font
					(size 1.27 1.27)
				)
			)
		)
		(duplicate_pad_numbers_are_jumpers no)
		(fp_line
			(start -3.62712 -1.8796)
			(end -3.62712 1.8796)
			(stroke
				(width 0.1524)
				(type default)
			)
			(layer "F.SilkS")
		)
		(fp_line
			(start -3.62712 1.8796)
			(end 3.62712 1.8796)
			(stroke
				(width 0.1524)
				(type default)
			)
			(layer "F.SilkS")
		)
		(fp_line
			(start 3.62712 -1.8796)
			(end -3.62712 -1.8796)
			(stroke
				(width 0.1524)
				(type default)
			)
			(layer "F.SilkS")
		)
		(fp_line
			(start 3.62712 1.8796)
			(end 3.62712 -1.8796)
			(stroke
				(width 0.1524)
				(type default)
			)
			(layer "F.SilkS")
		)
		(fp_line
			(start -3.299968 -1.700022)
			(end -3.299968 1.700022)
			(stroke
				(width 0.1)
				(type default)
			)
			(layer "F.Fab")
		)
		(fp_line
			(start -3.299968 1.700022)
			(end 3.299968 1.700022)
			(stroke
				(width 0.1)
				(type default)
			)
			(layer "F.Fab")
		)
		(fp_line
			(start 3.299968 -1.700022)
			(end -3.299968 -1.700022)
			(stroke
				(width 0.1)
				(type default)
			)
			(layer "F.Fab")
		)
		(fp_line
			(start 3.299968 1.700022)
			(end 3.299968 -1.700022)
			(stroke
				(width 0.1)
				(type default)
			)
			(layer "F.Fab")
		)
		(pad "1" smd rect
			(at -2.70002 0)
			(size 1.6002 3.5052)
			(layers "F.Cu" "F.Mask" "F.Paste")
			(net "P52V_HS2_EN_DISCHARGE_VBE_R")
		)
		(pad "2" smd rect
			(at 2.70002 0)
			(size 1.6002 3.5052)
			(layers "F.Cu" "F.Mask" "F.Paste")
			(net "GND")
		)
	)
	(footprint ""
		(layer "F.Cu")
		(at 436.245 -30.353 180)
		(property "Reference" "R15"
			(at 0 0 180)
			(layer "F.SilkS")
			(hide yes)
			(effects
				(font
					(size 1.27 1.27)
				)
			)
		)
		(property "Value" ""
			(at 0 0 180)
			(layer "F.Fab")
			(effects
				(font
					(size 1.27 1.27)
				)
			)
		)
		(duplicate_pad_numbers_are_jumpers no)
		(fp_line
			(start 0.7874 0.4064)
			(end -0.7874 0.4064)
			(stroke
				(width 0.1524)
				(type default)
			)
			(layer "F.SilkS")
		)
		(fp_line
			(start 0.7874 -0.4064)
			(end 0.7874 0.4064)
			(stroke
				(width 0.1524)
				(type default)
			)
			(layer "F.SilkS")
		)
		(fp_line
			(start -0.7874 0.4064)
			(end -0.7874 -0.4064)
			(stroke
				(width 0.1524)
				(type default)
			)
			(layer "F.SilkS")
		)
		(fp_line
			(start -0.7874 -0.4064)
			(end 0.7874 -0.4064)
			(stroke
				(width 0.1524)
				(type default)
			)
			(layer "F.SilkS")
		)
		(fp_line
			(start 0.67945 0.3048)
			(end 0.120396 0.3048)
			(stroke
				(width 0.1)
				(type default)
			)
			(layer "F.Fab")
		)
		(fp_line
			(start 0.67945 -0.3048)
			(end 0.67945 0.3048)
			(stroke
				(width 0.1)
				(type default)
			)
			(layer "F.Fab")
		)
		(fp_line
			(start 0.12065 -0.2794)
			(end 0.12065 -0.3048)
			(stroke
				(width 0.1)
				(type default)
			)
			(layer "F.Fab")
		)
		(fp_line
			(start 0.12065 -0.3048)
			(end 0.67945 -0.3048)
			(stroke
				(width 0.1)
				(type default)
			)
			(layer "F.Fab")
		)
		(fp_line
			(start 0.120396 0.3048)
			(end 0.120396 0.2794)
			(stroke
				(width 0.1)
				(type default)
			)
			(layer "F.Fab")
		)
		(fp_line
			(start 0.120396 0.2794)
			(end -0.12065 0.2794)
			(stroke
				(width 0.1)
				(type default)
			)
			(layer "F.Fab")
		)
		(fp_line
			(start -0.12065 0.3048)
			(end -0.67945 0.3048)
			(stroke
				(width 0.1)
				(type default)
			)
			(layer "F.Fab")
		)
		(fp_line
			(start -0.12065 0.2794)
			(end -0.12065 0.3048)
			(stroke
				(width 0.1)
				(type default)
			)
			(layer "F.Fab")
		)
		(fp_line
			(start -0.12065 -0.2794)
			(end 0.12065 -0.2794)
			(stroke
				(width 0.1)
				(type default)
			)
			(layer "F.Fab")
		)
		(fp_line
			(start -0.12065 -0.305054)
			(end -0.12065 -0.2794)
			(stroke
				(width 0.1)
				(type default)
			)
			(layer "F.Fab")
		)
		(fp_line
			(start -0.67945 0.3048)
			(end -0.67945 -0.305054)
			(stroke
				(width 0.1)
				(type default)
			)
			(layer "F.Fab")
		)
		(fp_line
			(start -0.67945 -0.305054)
			(end -0.12065 -0.305054)
			(stroke
				(width 0.1)
				(type default)
			)
			(layer "F.Fab")
		)
		(pad "1" smd circle
			(at -0.40005 0 180)
			(size 0 0)
			(layers "F.Cu" "F.Mask" "F.Paste")
			(net "PU_9543_0_FAN")
		)
		(pad "2" smd circle
			(at 0.40005 0 180)
			(size 0 0)
			(layers "F.Cu" "F.Mask" "F.Paste")
			(net "P3V3_AUX")
		)
	)
	(footprint ""
		(layer "F.Cu")
		(at 168.956736 -63.881 180)
		(property "Reference" "PR7031"
			(at 0 0 180)
			(layer "F.SilkS")
			(hide yes)
			(effects
				(font
					(size 1.27 1.27)
				)
			)
		)
		(property "Value" ""
			(at 0 0 180)
			(layer "F.Fab")
			(effects
				(font
					(size 1.27 1.27)
				)
			)
		)
		(duplicate_pad_numbers_are_jumpers no)
		(fp_line
			(start 0.7874 0.4064)
			(end -0.7874 0.4064)
			(stroke
				(width 0.1524)
				(type default)
			)
			(layer "F.SilkS")
		)
		(fp_line
			(start 0.7874 -0.4064)
			(end 0.7874 0.4064)
			(stroke
				(width 0.1524)
				(type default)
			)
			(layer "F.SilkS")
		)
		(fp_line
			(start -0.7874 0.4064)
			(end -0.7874 -0.4064)
			(stroke
				(width 0.1524)
				(type default)
			)
			(layer "F.SilkS")
		)
		(fp_line
			(start -0.7874 -0.4064)
			(end 0.7874 -0.4064)
			(stroke
				(width 0.1524)
				(type default)
			)
			(layer "F.SilkS")
		)
		(fp_line
			(start 0.67945 0.3048)
			(end 0.120396 0.3048)
			(stroke
				(width 0.1)
				(type default)
			)
			(layer "F.Fab")
		)
		(fp_line
			(start 0.67945 -0.3048)
			(end 0.67945 0.3048)
			(stroke
				(width 0.1)
				(type default)
			)
			(layer "F.Fab")
		)
		(fp_line
			(start 0.12065 -0.2794)
			(end 0.12065 -0.3048)
			(stroke
				(width 0.1)
				(type default)
			)
			(layer "F.Fab")
		)
		(fp_line
			(start 0.12065 -0.3048)
			(end 0.67945 -0.3048)
			(stroke
				(width 0.1)
				(type default)
			)
			(layer "F.Fab")
		)
		(fp_line
			(start 0.120396 0.3048)
			(end 0.120396 0.2794)
			(stroke
				(width 0.1)
				(type default)
			)
			(layer "F.Fab")
		)
		(fp_line
			(start 0.120396 0.2794)
			(end -0.12065 0.2794)
			(stroke
				(width 0.1)
				(type default)
			)
			(layer "F.Fab")
		)
		(fp_line
			(start -0.12065 0.3048)
			(end -0.67945 0.3048)
			(stroke
				(width 0.1)
				(type default)
			)
			(layer "F.Fab")
		)
		(fp_line
			(start -0.12065 0.2794)
			(end -0.12065 0.3048)
			(stroke
				(width 0.1)
				(type default)
			)
			(layer "F.Fab")
		)
		(fp_line
			(start -0.12065 -0.2794)
			(end 0.12065 -0.2794)
			(stroke
				(width 0.1)
				(type default)
			)
			(layer "F.Fab")
		)
		(fp_line
			(start -0.12065 -0.305054)
			(end -0.12065 -0.2794)
			(stroke
				(width 0.1)
				(type default)
			)
			(layer "F.Fab")
		)
		(fp_line
			(start -0.67945 0.3048)
			(end -0.67945 -0.305054)
			(stroke
				(width 0.1)
				(type default)
			)
			(layer "F.Fab")
		)
		(fp_line
			(start -0.67945 -0.305054)
			(end -0.12065 -0.305054)
			(stroke
				(width 0.1)
				(type default)
			)
			(layer "F.Fab")
		)
		(pad "1" smd circle
			(at -0.40005 0 180)
			(size 0 0)
			(layers "F.Cu" "F.Mask" "F.Paste")
			(net "P52V_HS2_ESTART_R")
		)
		(pad "2" smd circle
			(at 0.40005 0 180)
			(size 0 0)
			(layers "F.Cu" "F.Mask" "F.Paste")
			(net "P52V_HS2_ESTART")
		)
	)
	(footprint ""
		(layer "F.Cu")
		(at 172.4914 -75.819 180)
		(property "Reference" "R5888"
			(at 0 0 180)
			(layer "F.SilkS")
			(hide yes)
			(effects
				(font
					(size 1.27 1.27)
				)
			)
		)
		(property "Value" ""
			(at 0 0 180)
			(layer "F.Fab")
			(effects
				(font
					(size 1.27 1.27)
				)
			)
		)
		(duplicate_pad_numbers_are_jumpers no)
		(fp_line
			(start 0.7874 0.4064)
			(end -0.7874 0.4064)
			(stroke
				(width 0.1524)
				(type default)
			)
			(layer "F.SilkS")
		)
		(fp_line
			(start 0.7874 -0.4064)
			(end 0.7874 0.4064)
			(stroke
				(width 0.1524)
				(type default)
			)
			(layer "F.SilkS")
		)
		(fp_line
			(start -0.7874 0.4064)
			(end -0.7874 -0.4064)
			(stroke
				(width 0.1524)
				(type default)
			)
			(layer "F.SilkS")
		)
		(fp_line
			(start -0.7874 -0.4064)
			(end 0.7874 -0.4064)
			(stroke
				(width 0.1524)
				(type default)
			)
			(layer "F.SilkS")
		)
		(fp_line
			(start 0.67945 0.3048)
			(end 0.120396 0.3048)
			(stroke
				(width 0.1)
				(type default)
			)
			(layer "F.Fab")
		)
		(fp_line
			(start 0.67945 -0.3048)
			(end 0.67945 0.3048)
			(stroke
				(width 0.1)
				(type default)
			)
			(layer "F.Fab")
		)
		(fp_line
			(start 0.12065 -0.2794)
			(end 0.12065 -0.3048)
			(stroke
				(width 0.1)
				(type default)
			)
			(layer "F.Fab")
		)
		(fp_line
			(start 0.12065 -0.3048)
			(end 0.67945 -0.3048)
			(stroke
				(width 0.1)
				(type default)
			)
			(layer "F.Fab")
		)
		(fp_line
			(start 0.120396 0.3048)
			(end 0.120396 0.2794)
			(stroke
				(width 0.1)
				(type default)
			)
			(layer "F.Fab")
		)
		(fp_line
			(start 0.120396 0.2794)
			(end -0.12065 0.2794)
			(stroke
				(width 0.1)
				(type default)
			)
			(layer "F.Fab")
		)
		(fp_line
			(start -0.12065 0.3048)
			(end -0.67945 0.3048)
			(stroke
				(width 0.1)
				(type default)
			)
			(layer "F.Fab")
		)
		(fp_line
			(start -0.12065 0.2794)
			(end -0.12065 0.3048)
			(stroke
				(width 0.1)
				(type default)
			)
			(layer "F.Fab")
		)
		(fp_line
			(start -0.12065 -0.2794)
			(end 0.12065 -0.2794)
			(stroke
				(width 0.1)
				(type default)
			)
			(layer "F.Fab")
		)
		(fp_line
			(start -0.12065 -0.305054)
			(end -0.12065 -0.2794)
			(stroke
				(width 0.1)
				(type default)
			)
			(layer "F.Fab")
		)
		(fp_line
			(start -0.67945 0.3048)
			(end -0.67945 -0.305054)
			(stroke
				(width 0.1)
				(type default)
			)
			(layer "F.Fab")
		)
		(fp_line
			(start -0.67945 -0.305054)
			(end -0.12065 -0.305054)
			(stroke
				(width 0.1)
				(type default)
			)
			(layer "F.Fab")
		)
		(pad "1" smd circle
			(at -0.40005 0 180)
			(size 0 0)
			(layers "F.Cu" "F.Mask" "F.Paste")
			(net "P52V_HS2_GPO2")
		)
		(pad "2" smd circle
			(at 0.40005 0 180)
			(size 0 0)
			(layers "F.Cu" "F.Mask" "F.Paste")
			(net "P52V_HS2_FLT")
		)
	)
	(footprint ""
		(layer "F.Cu")
		(at 414.49244 -25.66162)
		(property "Reference" "C98"
			(at 0 0 0)
			(layer "F.SilkS")
			(hide yes)
			(effects
				(font
					(size 1.27 1.27)
				)
			)
		)
		(property "Value" ""
			(at 0 0 0)
			(layer "F.Fab")
			(effects
				(font
					(size 1.27 1.27)
				)
			)
		)
		(duplicate_pad_numbers_are_jumpers no)
		(fp_line
			(start -1.2954 -0.5842)
			(end 1.2954 -0.5842)
			(stroke
				(width 0.1524)
				(type default)
			)
			(layer "F.SilkS")
		)
		(fp_line
			(start -1.2954 0.5842)
			(end -1.2954 -0.5842)
			(stroke
				(width 0.1524)
				(type default)
			)
			(layer "F.SilkS")
		)
		(fp_line
			(start 1.2954 -0.5842)
			(end 1.2954 0.5842)
			(stroke
				(width 0.1524)
				(type default)
			)
			(layer "F.SilkS")
		)
		(fp_line
			(start 1.2954 0.5842)
			(end -1.2954 0.5842)
			(stroke
				(width 0.1524)
				(type default)
			)
			(layer "F.SilkS")
		)
		(fp_line
			(start -1.1938 -0.4064)
			(end -0.8636 -0.4064)
			(stroke
				(width 0.1)
				(type default)
			)
			(layer "F.Fab")
		)
		(fp_line
			(start -1.1938 0.4064)
			(end -1.1938 -0.4064)
			(stroke
				(width 0.1)
				(type default)
			)
			(layer "F.Fab")
		)
		(fp_line
			(start -0.8636 -0.4572)
			(end 0.8636 -0.4572)
			(stroke
				(width 0.1)
				(type default)
			)
			(layer "F.Fab")
		)
		(fp_line
			(start -0.8636 -0.4064)
			(end -0.8636 -0.4572)
			(stroke
				(width 0.1)
				(type default)
			)
			(layer "F.Fab")
		)
		(fp_line
			(start -0.8636 0.4064)
			(end -1.1938 0.4064)
			(stroke
				(width 0.1)
				(type default)
			)
			(layer "F.Fab")
		)
		(fp_line
			(start -0.8636 0.4572)
			(end -0.8636 0.4064)
			(stroke
				(width 0.1)
				(type default)
			)
			(layer "F.Fab")
		)
		(fp_line
			(start 0.8636 -0.4572)
			(end 0.8636 -0.4064)
			(stroke
				(width 0.1)
				(type default)
			)
			(layer "F.Fab")
		)
		(fp_line
			(start 0.8636 -0.4064)
			(end 1.1938 -0.4064)
			(stroke
				(width 0.1)
				(type default)
			)
			(layer "F.Fab")
		)
		(fp_line
			(start 0.8636 0.4064)
			(end 0.8636 0.4572)
			(stroke
				(width 0.1)
				(type default)
			)
			(layer "F.Fab")
		)
		(fp_line
			(start 0.8636 0.4572)
			(end -0.8636 0.4572)
			(stroke
				(width 0.1)
				(type default)
			)
			(layer "F.Fab")
		)
		(fp_line
			(start 1.1938 -0.4064)
			(end 1.1938 0.4064)
			(stroke
				(width 0.1)
				(type default)
			)
			(layer "F.Fab")
		)
		(fp_line
			(start 1.1938 0.4064)
			(end 0.8636 0.4064)
			(stroke
				(width 0.1)
				(type default)
			)
			(layer "F.Fab")
		)
		(pad "1" smd rect
			(at -0.7366 0 270)
			(size 0.7112 0.8128)
			(layers "F.Cu" "F.Mask" "F.Paste")
			(net "GND")
		)
		(pad "2" smd rect
			(at 0.7366 0 270)
			(size 0.7112 0.8128)
			(layers "F.Cu" "F.Mask" "F.Paste")
			(net "P12V_LED_PD")
		)
	)
	(footprint ""
		(layer "F.Cu")
		(at 71.000112 -13.499592 180)
		(property "Reference" "H4"
			(at 0.769112 10.476738 0)
			(unlocked yes)
			(layer "F.SilkS")
			(effects
				(font
					(size 0.7874 0.5842)
					(thickness 0.1524)
				)
				(justify left)
			)
		)
		(property "Value" ""
			(at 0 0 180)
			(layer "F.Fab")
			(effects
				(font
					(size 1.27 1.27)
				)
			)
		)
		(duplicate_pad_numbers_are_jumpers no)
		(pad "1" thru_hole oval
			(at 0 0 180)
			(size 9.017 14.0208)
			(drill 3.0226
				(offset 0 2.499868)
			)
			(layers "*.Cu" "*.Mask")
			(remove_unused_layers no)
			(net "GND")
			(clearance -1.500378)
			(padstack
				(mode front_inner_back)
				(layer "Inner"
					(shape circle)
					(size 0 0)
					(clearance 0)
				)
				(layer "B.Cu"
					(shape oval)
					(size 9.017 14.0208)
					(offset 0 2.499868)
					(clearance -1.500378)
				)
			)
		)
	)
	(footprint ""
		(layer "F.Cu")
		(at 168.956736 -67.183)
		(property "Reference" "R5892"
			(at 0 0 0)
			(layer "F.SilkS")
			(hide yes)
			(effects
				(font
					(size 1.27 1.27)
				)
			)
		)
		(property "Value" ""
			(at 0 0 0)
			(layer "F.Fab")
			(effects
				(font
					(size 1.27 1.27)
				)
			)
		)
		(duplicate_pad_numbers_are_jumpers no)
		(fp_line
			(start -0.7874 -0.4064)
			(end 0.7874 -0.4064)
			(stroke
				(width 0.1524)
				(type default)
			)
			(layer "F.SilkS")
		)
		(fp_line
			(start -0.7874 0.4064)
			(end -0.7874 -0.4064)
			(stroke
				(width 0.1524)
				(type default)
			)
			(layer "F.SilkS")
		)
		(fp_line
			(start 0.7874 -0.4064)
			(end 0.7874 0.4064)
			(stroke
				(width 0.1524)
				(type default)
			)
			(layer "F.SilkS")
		)
		(fp_line
			(start 0.7874 0.4064)
			(end -0.7874 0.4064)
			(stroke
				(width 0.1524)
				(type default)
			)
			(layer "F.SilkS")
		)
		(fp_line
			(start -0.67945 -0.305054)
			(end -0.12065 -0.305054)
			(stroke
				(width 0.1)
				(type default)
			)
			(layer "F.Fab")
		)
		(fp_line
			(start -0.67945 0.3048)
			(end -0.67945 -0.305054)
			(stroke
				(width 0.1)
				(type default)
			)
			(layer "F.Fab")
		)
		(fp_line
			(start -0.12065 -0.305054)
			(end -0.12065 -0.2794)
			(stroke
				(width 0.1)
				(type default)
			)
			(layer "F.Fab")
		)
		(fp_line
			(start -0.12065 -0.2794)
			(end 0.12065 -0.2794)
			(stroke
				(width 0.1)
				(type default)
			)
			(layer "F.Fab")
		)
		(fp_line
			(start -0.12065 0.2794)
			(end -0.12065 0.3048)
			(stroke
				(width 0.1)
				(type default)
			)
			(layer "F.Fab")
		)
		(fp_line
			(start -0.12065 0.3048)
			(end -0.67945 0.3048)
			(stroke
				(width 0.1)
				(type default)
			)
			(layer "F.Fab")
		)
		(fp_line
			(start 0.120396 0.2794)
			(end -0.12065 0.2794)
			(stroke
				(width 0.1)
				(type default)
			)
			(layer "F.Fab")
		)
		(fp_line
			(start 0.120396 0.3048)
			(end 0.120396 0.2794)
			(stroke
				(width 0.1)
				(type default)
			)
			(layer "F.Fab")
		)
		(fp_line
			(start 0.12065 -0.3048)
			(end 0.67945 -0.3048)
			(stroke
				(width 0.1)
				(type default)
			)
			(layer "F.Fab")
		)
		(fp_line
			(start 0.12065 -0.2794)
			(end 0.12065 -0.3048)
			(stroke
				(width 0.1)
				(type default)
			)
			(layer "F.Fab")
		)
		(fp_line
			(start 0.67945 -0.3048)
			(end 0.67945 0.3048)
			(stroke
				(width 0.1)
				(type default)
			)
			(layer "F.Fab")
		)
		(fp_line
			(start 0.67945 0.3048)
			(end 0.120396 0.3048)
			(stroke
				(width 0.1)
				(type default)
			)
			(layer "F.Fab")
		)
		(pad "1" smd circle
			(at -0.40005 0)
			(size 0 0)
			(layers "F.Cu" "F.Mask" "F.Paste")
			(net "P52V_HS2_VCAP")
		)
		(pad "2" smd circle
			(at 0.40005 0)
			(size 0 0)
			(layers "F.Cu" "F.Mask" "F.Paste")
			(net "P52V_HS2_ADR1")
		)
	)
	(footprint ""
		(layer "F.Cu")
		(at 436.753 -38.862)
		(property "Reference" "R10"
			(at 0 0 0)
			(layer "F.SilkS")
			(hide yes)
			(effects
				(font
					(size 1.27 1.27)
				)
			)
		)
		(property "Value" ""
			(at 0 0 0)
			(layer "F.Fab")
			(effects
				(font
					(size 1.27 1.27)
				)
			)
		)
		(duplicate_pad_numbers_are_jumpers no)
		(fp_line
			(start -0.7874 -0.4064)
			(end 0.7874 -0.4064)
			(stroke
				(width 0.1524)
				(type default)
			)
			(layer "F.SilkS")
		)
		(fp_line
			(start -0.7874 0.4064)
			(end -0.7874 -0.4064)
			(stroke
				(width 0.1524)
				(type default)
			)
			(layer "F.SilkS")
		)
		(fp_line
			(start 0.7874 -0.4064)
			(end 0.7874 0.4064)
			(stroke
				(width 0.1524)
				(type default)
			)
			(layer "F.SilkS")
		)
		(fp_line
			(start 0.7874 0.4064)
			(end -0.7874 0.4064)
			(stroke
				(width 0.1524)
				(type default)
			)
			(layer "F.SilkS")
		)
		(fp_line
			(start -0.67945 -0.305054)
			(end -0.12065 -0.305054)
			(stroke
				(width 0.1)
				(type default)
			)
			(layer "F.Fab")
		)
		(fp_line
			(start -0.67945 0.3048)
			(end -0.67945 -0.305054)
			(stroke
				(width 0.1)
				(type default)
			)
			(layer "F.Fab")
		)
		(fp_line
			(start -0.12065 -0.305054)
			(end -0.12065 -0.2794)
			(stroke
				(width 0.1)
				(type default)
			)
			(layer "F.Fab")
		)
		(fp_line
			(start -0.12065 -0.2794)
			(end 0.12065 -0.2794)
			(stroke
				(width 0.1)
				(type default)
			)
			(layer "F.Fab")
		)
		(fp_line
			(start -0.12065 0.2794)
			(end -0.12065 0.3048)
			(stroke
				(width 0.1)
				(type default)
			)
			(layer "F.Fab")
		)
		(fp_line
			(start -0.12065 0.3048)
			(end -0.67945 0.3048)
			(stroke
				(width 0.1)
				(type default)
			)
			(layer "F.Fab")
		)
		(fp_line
			(start 0.120396 0.2794)
			(end -0.12065 0.2794)
			(stroke
				(width 0.1)
				(type default)
			)
			(layer "F.Fab")
		)
		(fp_line
			(start 0.120396 0.3048)
			(end 0.120396 0.2794)
			(stroke
				(width 0.1)
				(type default)
			)
			(layer "F.Fab")
		)
		(fp_line
			(start 0.12065 -0.3048)
			(end 0.67945 -0.3048)
			(stroke
				(width 0.1)
				(type default)
			)
			(layer "F.Fab")
		)
		(fp_line
			(start 0.12065 -0.2794)
			(end 0.12065 -0.3048)
			(stroke
				(width 0.1)
				(type default)
			)
			(layer "F.Fab")
		)
		(fp_line
			(start 0.67945 -0.3048)
			(end 0.67945 0.3048)
			(stroke
				(width 0.1)
				(type default)
			)
			(layer "F.Fab")
		)
		(fp_line
			(start 0.67945 0.3048)
			(end 0.120396 0.3048)
			(stroke
				(width 0.1)
				(type default)
			)
			(layer "F.Fab")
		)
		(pad "1" smd circle
			(at -0.40005 0)
			(size 0 0)
			(layers "F.Cu" "F.Mask" "F.Paste")
			(net "PWRGD_P3V3_AUX_MB_BUF")
		)
		(pad "2" smd circle
			(at 0.40005 0)
			(size 0 0)
			(layers "F.Cu" "F.Mask" "F.Paste")
			(net "MB_P52V_I2C_EN")
		)
	)
	(footprint ""
		(layer "F.Cu")
		(at 427.228 -37.592)
		(property "Reference" "R138"
			(at 0 0 0)
			(layer "F.SilkS")
			(hide yes)
			(effects
				(font
					(size 1.27 1.27)
				)
			)
		)
		(property "Value" ""
			(at 0 0 0)
			(layer "F.Fab")
			(effects
				(font
					(size 1.27 1.27)
				)
			)
		)
		(duplicate_pad_numbers_are_jumpers no)
		(fp_line
			(start -0.7874 -0.4064)
			(end 0.7874 -0.4064)
			(stroke
				(width 0.1524)
				(type default)
			)
			(layer "F.SilkS")
		)
		(fp_line
			(start -0.7874 0.4064)
			(end -0.7874 -0.4064)
			(stroke
				(width 0.1524)
				(type default)
			)
			(layer "F.SilkS")
		)
		(fp_line
			(start 0.7874 -0.4064)
			(end 0.7874 0.4064)
			(stroke
				(width 0.1524)
				(type default)
			)
			(layer "F.SilkS")
		)
		(fp_line
			(start 0.7874 0.4064)
			(end -0.7874 0.4064)
			(stroke
				(width 0.1524)
				(type default)
			)
			(layer "F.SilkS")
		)
		(fp_line
			(start -0.67945 -0.305054)
			(end -0.12065 -0.305054)
			(stroke
				(width 0.1)
				(type default)
			)
			(layer "F.Fab")
		)
		(fp_line
			(start -0.67945 0.3048)
			(end -0.67945 -0.305054)
			(stroke
				(width 0.1)
				(type default)
			)
			(layer "F.Fab")
		)
		(fp_line
			(start -0.12065 -0.305054)
			(end -0.12065 -0.2794)
			(stroke
				(width 0.1)
				(type default)
			)
			(layer "F.Fab")
		)
		(fp_line
			(start -0.12065 -0.2794)
			(end 0.12065 -0.2794)
			(stroke
				(width 0.1)
				(type default)
			)
			(layer "F.Fab")
		)
		(fp_line
			(start -0.12065 0.2794)
			(end -0.12065 0.3048)
			(stroke
				(width 0.1)
				(type default)
			)
			(layer "F.Fab")
		)
		(fp_line
			(start -0.12065 0.3048)
			(end -0.67945 0.3048)
			(stroke
				(width 0.1)
				(type default)
			)
			(layer "F.Fab")
		)
		(fp_line
			(start 0.120396 0.2794)
			(end -0.12065 0.2794)
			(stroke
				(width 0.1)
				(type default)
			)
			(layer "F.Fab")
		)
		(fp_line
			(start 0.120396 0.3048)
			(end 0.120396 0.2794)
			(stroke
				(width 0.1)
				(type default)
			)
			(layer "F.Fab")
		)
		(fp_line
			(start 0.12065 -0.3048)
			(end 0.67945 -0.3048)
			(stroke
				(width 0.1)
				(type default)
			)
			(layer "F.Fab")
		)
		(fp_line
			(start 0.12065 -0.2794)
			(end 0.12065 -0.3048)
			(stroke
				(width 0.1)
				(type default)
			)
			(layer "F.Fab")
		)
		(fp_line
			(start 0.67945 -0.3048)
			(end 0.67945 0.3048)
			(stroke
				(width 0.1)
				(type default)
			)
			(layer "F.Fab")
		)
		(fp_line
			(start 0.67945 0.3048)
			(end 0.120396 0.3048)
			(stroke
				(width 0.1)
				(type default)
			)
			(layer "F.Fab")
		)
		(pad "1" smd circle
			(at -0.40005 0)
			(size 0 0)
			(layers "F.Cu" "F.Mask" "F.Paste")
			(net "BOARD_ID_0")
		)
		(pad "2" smd circle
			(at 0.40005 0)
			(size 0 0)
			(layers "F.Cu" "F.Mask" "F.Paste")
			(net "GND")
		)
	)
	(footprint ""
		(layer "F.Cu")
		(at 323.13626 -18.2626 180)
		(property "Reference" "PQ36"
			(at -9.628886 -3.917188 0)
			(unlocked yes)
			(layer "F.SilkS")
			(effects
				(font
					(size 0.7874 0.5842)
					(thickness 0.1524)
				)
				(justify left)
			)
		)
		(property "Value" ""
			(at 0 0 180)
			(layer "F.Fab")
			(effects
				(font
					(size 1.27 1.27)
				)
			)
		)
		(duplicate_pad_numbers_are_jumpers no)
		(fp_line
			(start 7.649972 4.99999)
			(end 7.649972 -4.99999)
			(stroke
				(width 0.1524)
				(type default)
			)
			(layer "F.SilkS")
		)
		(fp_line
			(start 7.649972 -4.99999)
			(end 7.630414 -4.99999)
			(stroke
				(width 0.1524)
				(type default)
			)
			(layer "F.SilkS")
		)
		(fp_line
			(start 7.630414 4.99999)
			(end 7.649972 4.99999)
			(stroke
				(width 0.1524)
				(type default)
			)
			(layer "F.SilkS")
		)
		(fp_line
			(start 5.115814 -4.99999)
			(end -7.649972 -4.99999)
			(stroke
				(width 0.1524)
				(type default)
			)
			(layer "F.SilkS")
		)
		(fp_line
			(start -7.649972 4.99999)
			(end 5.115814 4.99999)
			(stroke
				(width 0.1524)
				(type default)
			)
			(layer "F.SilkS")
		)
		(fp_line
			(start -7.649972 3.3274)
			(end -7.649972 4.99999)
			(stroke
				(width 0.1524)
				(type default)
			)
			(layer "F.SilkS")
		)
		(fp_line
			(start -7.649972 -1.7526)
			(end -7.649972 1.7526)
			(stroke
				(width 0.1524)
				(type default)
			)
			(layer "F.SilkS")
		)
		(fp_line
			(start -7.649972 -4.99999)
			(end -7.649972 -3.3274)
			(stroke
				(width 0.1524)
				(type default)
			)
			(layer "F.SilkS")
		)
		(fp_line
			(start 7.649972 4.99999)
			(end 7.649972 -4.99999)
			(stroke
				(width 0.1)
				(type default)
			)
			(layer "F.Fab")
		)
		(fp_line
			(start 7.649972 -4.99999)
			(end -7.649972 -4.99999)
			(stroke
				(width 0.1)
				(type default)
			)
			(layer "F.Fab")
		)
		(fp_line
			(start -7.649972 4.99999)
			(end 7.649972 4.99999)
			(stroke
				(width 0.1)
				(type default)
			)
			(layer "F.Fab")
		)
		(fp_line
			(start -7.649972 -4.99999)
			(end -7.649972 4.99999)
			(stroke
				(width 0.1)
				(type default)
			)
			(layer "F.Fab")
		)
		(pad "D" smd circle
			(at 2.15011 0 180)
			(size 0 0)
			(layers "F.Cu" "F.Mask" "F.Paste")
			(net "P52V_HS1_DRAIN_2")
		)
		(pad "G" smd rect
			(at -7.050024 -2.54 90)
			(size 1.3208 3.0988)
			(layers "F.Cu" "F.Mask" "F.Paste")
			(net "P52V_HS1_GATE5")
		)
		(pad "S" smd rect
			(at -7.050024 2.54 90)
			(size 1.3208 3.0988)
			(layers "F.Cu" "F.Mask" "F.Paste")
			(net "P52V_HS1")
		)
		(zone
			(layer "F.Cu")
			(hatch none 0.5)
			(connect_pads
				(clearance 0)
			)
			(min_thickness 0.25)
			(keepout
				(tracks not_allowed)
				(vias allowed)
				(pads allowed)
				(copperpour not_allowed)
				(footprints allowed)
			)
			(placement
				(enabled no)
				(sheetname "")
			)
			(fill
				(thermal_gap 0.5)
				(thermal_bridge_width 0.5)
				(island_removal_mode 0)
			)
			(polygon
				(pts
					(xy 317.95466 -13.2842) (xy 330.78166 -13.2842) (xy 330.78166 -15.0114) (xy 328.57186 -15.0114)
					(xy 328.57186 -16.4338) (xy 330.78166 -16.4338) (xy 330.78166 -20.0914) (xy 328.57186 -20.0914)
					(xy 328.57186 -21.5138) (xy 330.78166 -21.5138) (xy 330.78166 -23.241) (xy 317.95466 -23.241) (xy 317.95466 -22.0726)
					(xy 324.15226 -22.0726) (xy 324.15226 -14.4526) (xy 317.95466 -14.4526)
				)
			)
		)
	)
	(footprint ""
		(layer "F.Cu")
		(at 318.008 -85.598 180)
		(property "Reference" "PR6967"
			(at 0 0 180)
			(layer "F.SilkS")
			(hide yes)
			(effects
				(font
					(size 1.27 1.27)
				)
			)
		)
		(property "Value" ""
			(at 0 0 180)
			(layer "F.Fab")
			(effects
				(font
					(size 1.27 1.27)
				)
			)
		)
		(duplicate_pad_numbers_are_jumpers no)
		(fp_line
			(start 0.7874 0.4064)
			(end -0.7874 0.4064)
			(stroke
				(width 0.1524)
				(type default)
			)
			(layer "F.SilkS")
		)
		(fp_line
			(start 0.7874 -0.4064)
			(end 0.7874 0.4064)
			(stroke
				(width 0.1524)
				(type default)
			)
			(layer "F.SilkS")
		)
		(fp_line
			(start -0.7874 0.4064)
			(end -0.7874 -0.4064)
			(stroke
				(width 0.1524)
				(type default)
			)
			(layer "F.SilkS")
		)
		(fp_line
			(start -0.7874 -0.4064)
			(end 0.7874 -0.4064)
			(stroke
				(width 0.1524)
				(type default)
			)
			(layer "F.SilkS")
		)
		(fp_line
			(start 0.67945 0.3048)
			(end 0.120396 0.3048)
			(stroke
				(width 0.1)
				(type default)
			)
			(layer "F.Fab")
		)
		(fp_line
			(start 0.67945 -0.3048)
			(end 0.67945 0.3048)
			(stroke
				(width 0.1)
				(type default)
			)
			(layer "F.Fab")
		)
		(fp_line
			(start 0.12065 -0.2794)
			(end 0.12065 -0.3048)
			(stroke
				(width 0.1)
				(type default)
			)
			(layer "F.Fab")
		)
		(fp_line
			(start 0.12065 -0.3048)
			(end 0.67945 -0.3048)
			(stroke
				(width 0.1)
				(type default)
			)
			(layer "F.Fab")
		)
		(fp_line
			(start 0.120396 0.3048)
			(end 0.120396 0.2794)
			(stroke
				(width 0.1)
				(type default)
			)
			(layer "F.Fab")
		)
		(fp_line
			(start 0.120396 0.2794)
			(end -0.12065 0.2794)
			(stroke
				(width 0.1)
				(type default)
			)
			(layer "F.Fab")
		)
		(fp_line
			(start -0.12065 0.3048)
			(end -0.67945 0.3048)
			(stroke
				(width 0.1)
				(type default)
			)
			(layer "F.Fab")
		)
		(fp_line
			(start -0.12065 0.2794)
			(end -0.12065 0.3048)
			(stroke
				(width 0.1)
				(type default)
			)
			(layer "F.Fab")
		)
		(fp_line
			(start -0.12065 -0.2794)
			(end 0.12065 -0.2794)
			(stroke
				(width 0.1)
				(type default)
			)
			(layer "F.Fab")
		)
		(fp_line
			(start -0.12065 -0.305054)
			(end -0.12065 -0.2794)
			(stroke
				(width 0.1)
				(type default)
			)
			(layer "F.Fab")
		)
		(fp_line
			(start -0.67945 0.3048)
			(end -0.67945 -0.305054)
			(stroke
				(width 0.1)
				(type default)
			)
			(layer "F.Fab")
		)
		(fp_line
			(start -0.67945 -0.305054)
			(end -0.12065 -0.305054)
			(stroke
				(width 0.1)
				(type default)
			)
			(layer "F.Fab")
		)
		(pad "1" smd rect
			(at -0.40005 0)
			(size 0.4572 0.508)
			(layers "F.Cu" "F.Mask" "F.Paste")
			(net "P52V_HS1_TEMPP")
		)
		(pad "2" smd rect
			(at 0.40005 0)
			(size 0.4572 0.508)
			(layers "F.Cu" "F.Mask" "F.Paste")
			(net "P52V_HS1_TEMP_R")
		)
	)
	(footprint ""
		(layer "F.Cu")
		(at 334.631284 -27.7876 -90)
		(property "Reference" "PR477"
			(at 0 0 270)
			(layer "F.SilkS")
			(hide yes)
			(effects
				(font
					(size 1.27 1.27)
				)
			)
		)
		(property "Value" ""
			(at 0 0 270)
			(layer "F.Fab")
			(effects
				(font
					(size 1.27 1.27)
				)
			)
		)
		(duplicate_pad_numbers_are_jumpers no)
		(fp_line
			(start -1.2954 0.5842)
			(end -1.2954 -0.5842)
			(stroke
				(width 0.1524)
				(type default)
			)
			(layer "F.SilkS")
		)
		(fp_line
			(start 1.2954 0.5842)
			(end -1.2954 0.5842)
			(stroke
				(width 0.1524)
				(type default)
			)
			(layer "F.SilkS")
		)
		(fp_line
			(start -1.2954 -0.5842)
			(end 1.2954 -0.5842)
			(stroke
				(width 0.1524)
				(type default)
			)
			(layer "F.SilkS")
		)
		(fp_line
			(start 1.2954 -0.5842)
			(end 1.2954 0.5842)
			(stroke
				(width 0.1524)
				(type default)
			)
			(layer "F.SilkS")
		)
		(fp_line
			(start -0.8636 0.4572)
			(end -0.8636 0.4318)
			(stroke
				(width 0.1)
				(type default)
			)
			(layer "F.Fab")
		)
		(fp_line
			(start 0.8636 0.4572)
			(end -0.8636 0.4572)
			(stroke
				(width 0.1)
				(type default)
			)
			(layer "F.Fab")
		)
		(fp_line
			(start -0.8636 0.4318)
			(end -0.8636 0.4064)
			(stroke
				(width 0.1)
				(type default)
			)
			(layer "F.Fab")
		)
		(fp_line
			(start -1.1938 0.4064)
			(end -1.1938 -0.406654)
			(stroke
				(width 0.1)
				(type default)
			)
			(layer "F.Fab")
		)
		(fp_line
			(start -0.8636 0.4064)
			(end -1.1938 0.4064)
			(stroke
				(width 0.1)
				(type default)
			)
			(layer "F.Fab")
		)
		(fp_line
			(start 0.8636 0.4064)
			(end 0.8636 0.4572)
			(stroke
				(width 0.1)
				(type default)
			)
			(layer "F.Fab")
		)
		(fp_line
			(start 1.1938 0.4064)
			(end 0.8636 0.4064)
			(stroke
				(width 0.1)
				(type default)
			)
			(layer "F.Fab")
		)
		(fp_line
			(start -1.1938 -0.406654)
			(end -0.8636 -0.406654)
			(stroke
				(width 0.1)
				(type default)
			)
			(layer "F.Fab")
		)
		(fp_line
			(start -0.8636 -0.406654)
			(end -0.8636 -0.4572)
			(stroke
				(width 0.1)
				(type default)
			)
			(layer "F.Fab")
		)
		(fp_line
			(start 0.8636 -0.406654)
			(end 1.1938 -0.406654)
			(stroke
				(width 0.1)
				(type default)
			)
			(layer "F.Fab")
		)
		(fp_line
			(start 1.1938 -0.406654)
			(end 1.1938 0.4064)
			(stroke
				(width 0.1)
				(type default)
			)
			(layer "F.Fab")
		)
		(fp_line
			(start -0.8636 -0.4572)
			(end 0.8636 -0.4572)
			(stroke
				(width 0.1)
				(type default)
			)
			(layer "F.Fab")
		)
		(fp_line
			(start 0.8636 -0.4572)
			(end 0.8636 -0.406654)
			(stroke
				(width 0.1)
				(type default)
			)
			(layer "F.Fab")
		)
		(pad "1" smd rect
			(at -0.7366 0 180)
			(size 0.7112 0.8128)
			(layers "F.Cu" "F.Mask" "F.Paste")
			(net "P52V_HS1_GATE2_R")
		)
		(pad "2" smd rect
			(at 0.7366 0 180)
			(size 0.7112 0.8128)
			(layers "F.Cu" "F.Mask" "F.Paste")
			(net "P52V_HS1_GATE4")
		)
	)
	(footprint ""
		(layer "F.Cu")
		(at 406.146 -40.132)
		(property "Reference" "R38"
			(at 0 0 0)
			(layer "F.SilkS")
			(hide yes)
			(effects
				(font
					(size 1.27 1.27)
				)
			)
		)
		(property "Value" ""
			(at 0 0 0)
			(layer "F.Fab")
			(effects
				(font
					(size 1.27 1.27)
				)
			)
		)
		(duplicate_pad_numbers_are_jumpers no)
		(fp_line
			(start -2.234946 -0.9271)
			(end 2.234946 -0.9271)
			(stroke
				(width 0.1524)
				(type default)
			)
			(layer "F.SilkS")
		)
		(fp_line
			(start -2.234946 0.9271)
			(end -2.234946 -0.9271)
			(stroke
				(width 0.1524)
				(type default)
			)
			(layer "F.SilkS")
		)
		(fp_line
			(start 2.234946 -0.9271)
			(end 2.234946 0.9271)
			(stroke
				(width 0.1524)
				(type default)
			)
			(layer "F.SilkS")
		)
		(fp_line
			(start 2.234946 0.9271)
			(end -2.234946 0.9271)
			(stroke
				(width 0.1524)
				(type default)
			)
			(layer "F.SilkS")
		)
		(fp_line
			(start -1.575054 -0.824992)
			(end -1.575054 0.824992)
			(stroke
				(width 0.1)
				(type default)
			)
			(layer "F.Fab")
		)
		(fp_line
			(start -1.575054 0.824992)
			(end 1.575054 0.824992)
			(stroke
				(width 0.1)
				(type default)
			)
			(layer "F.Fab")
		)
		(fp_line
			(start 1.575054 -0.824992)
			(end -1.575054 -0.824992)
			(stroke
				(width 0.1)
				(type default)
			)
			(layer "F.Fab")
		)
		(fp_line
			(start 1.575054 0.824992)
			(end 1.575054 -0.824992)
			(stroke
				(width 0.1)
				(type default)
			)
			(layer "F.Fab")
		)
		(pad "1" smd rect
			(at -1.599946 0)
			(size 1.016 1.6002)
			(layers "F.Cu" "F.Mask" "F.Paste")
			(net "P52V_HS1")
		)
		(pad "2" smd rect
			(at 1.599946 0)
			(size 1.016 1.6002)
			(layers "F.Cu" "F.Mask" "F.Paste")
			(net "LED_D1_R1")
		)
	)
	(footprint ""
		(layer "F.Cu")
		(at 440.69 -48.768 90)
		(property "Reference" "U26"
			(at 1.8415 1.18237 90)
			(unlocked yes)
			(layer "F.SilkS")
			(effects
				(font
					(size 0.7874 0.5842)
					(thickness 0.1524)
				)
				(justify left)
			)
		)
		(property "Value" ""
			(at 0 0 90)
			(layer "F.Fab")
			(effects
				(font
					(size 1.27 1.27)
				)
			)
		)
		(duplicate_pad_numbers_are_jumpers no)
		(fp_line
			(start 1.603248 -1.500124)
			(end 1.603248 1.500124)
			(stroke
				(width 0.1524)
				(type default)
			)
			(layer "F.SilkS")
		)
		(fp_line
			(start -1.603248 -1.500124)
			(end 1.603248 -1.500124)
			(stroke
				(width 0.1524)
				(type default)
			)
			(layer "F.SilkS")
		)
		(fp_line
			(start 1.603248 1.500124)
			(end -1.603248 1.500124)
			(stroke
				(width 0.1524)
				(type default)
			)
			(layer "F.SilkS")
		)
		(fp_line
			(start -1.603248 1.500124)
			(end -1.603248 -1.500124)
			(stroke
				(width 0.1524)
				(type default)
			)
			(layer "F.SilkS")
		)
		(fp_line
			(start 0.700024 -1.500124)
			(end -0.700024 -1.500124)
			(stroke
				(width 0.1)
				(type default)
			)
			(layer "F.Fab")
		)
		(fp_line
			(start -0.700024 -1.500124)
			(end -0.700024 -1.169924)
			(stroke
				(width 0.1)
				(type default)
			)
			(layer "F.Fab")
		)
		(fp_line
			(start -0.700024 -1.169924)
			(end -1.249934 -1.169924)
			(stroke
				(width 0.1)
				(type default)
			)
			(layer "F.Fab")
		)
		(fp_line
			(start -1.249934 -1.169924)
			(end -1.249934 -0.729996)
			(stroke
				(width 0.1)
				(type default)
			)
			(layer "F.Fab")
		)
		(fp_line
			(start -0.6985 -0.729996)
			(end -0.6985 0.729996)
			(stroke
				(width 0.1)
				(type default)
			)
			(layer "F.Fab")
		)
		(fp_line
			(start -1.249934 -0.729996)
			(end -0.6985 -0.729996)
			(stroke
				(width 0.1)
				(type default)
			)
			(layer "F.Fab")
		)
		(fp_line
			(start 1.249934 -0.219964)
			(end 0.700024 -0.219964)
			(stroke
				(width 0.1)
				(type default)
			)
			(layer "F.Fab")
		)
		(fp_line
			(start 0.700024 -0.219964)
			(end 0.700024 -1.500124)
			(stroke
				(width 0.1)
				(type default)
			)
			(layer "F.Fab")
		)
		(fp_line
			(start 1.249934 0.219964)
			(end 1.249934 -0.219964)
			(stroke
				(width 0.1)
				(type default)
			)
			(layer "F.Fab")
		)
		(fp_line
			(start 0.700024 0.219964)
			(end 1.249934 0.219964)
			(stroke
				(width 0.1)
				(type default)
			)
			(layer "F.Fab")
		)
		(fp_line
			(start -0.6985 0.729996)
			(end -1.249934 0.729996)
			(stroke
				(width 0.1)
				(type default)
			)
			(layer "F.Fab")
		)
		(fp_line
			(start -1.249934 0.729996)
			(end -1.249934 1.169924)
			(stroke
				(width 0.1)
				(type default)
			)
			(layer "F.Fab")
		)
		(fp_line
			(start -0.700024 1.169924)
			(end -0.700024 1.500124)
			(stroke
				(width 0.1)
				(type default)
			)
			(layer "F.Fab")
		)
		(fp_line
			(start -1.249934 1.169924)
			(end -0.700024 1.169924)
			(stroke
				(width 0.1)
				(type default)
			)
			(layer "F.Fab")
		)
		(fp_line
			(start 0.700024 1.500124)
			(end 0.700024 0.219964)
			(stroke
				(width 0.1)
				(type default)
			)
			(layer "F.Fab")
		)
		(fp_line
			(start -0.700024 1.500124)
			(end 0.700024 1.500124)
			(stroke
				(width 0.1)
				(type default)
			)
			(layer "F.Fab")
		)
		(fp_rect
			(start -0.700024 1.500124)
			(end 0.700024 -1.500124)
			(stroke
				(width 0)
				(type default)
			)
			(fill no)
			(layer "F.Fab")
		)
		(pad "D" smd rect
			(at 0.999998 0)
			(size 0.8128 0.9144)
			(layers "F.Cu" "F.Mask" "F.Paste")
			(net "PWRGD_P3V3_AUX_MB_BUF_N")
		)
		(pad "G" smd rect
			(at -0.999998 -0.94996)
			(size 0.8128 0.9144)
			(layers "F.Cu" "F.Mask" "F.Paste")
			(net "PWRGD_P3V3_AUX_MB_BUF")
		)
		(pad "S" smd rect
			(at -0.999998 0.94996)
			(size 0.8128 0.9144)
			(layers "F.Cu" "F.Mask" "F.Paste")
			(net "GND")
		)
	)
	(footprint ""
		(layer "F.Cu")
		(at 42.36339 -58.42)
		(property "Reference" "PC46"
			(at 5.66801 -5.05333 0)
			(unlocked yes)
			(layer "F.SilkS")
			(effects
				(font
					(size 0.7874 0.5842)
					(thickness 0.1524)
				)
				(justify left)
			)
		)
		(property "Value" ""
			(at 0 0 0)
			(layer "F.Fab")
			(effects
				(font
					(size 1.27 1.27)
				)
			)
		)
		(duplicate_pad_numbers_are_jumpers no)
		(fp_line
			(start -9.253728 3.750056)
			(end 9.249918 3.750056)
			(stroke
				(width 0.1524)
				(type default)
			)
			(layer "F.SilkS")
		)
		(fp_line
			(start 0 3.750056)
			(end -9.253728 3.750056)
			(stroke
				(width 0.1524)
				(type default)
			)
			(layer "F.SilkS")
		)
		(fp_circle
			(center 0 3.750056)
			(end 9.249918 3.750056)
			(stroke
				(width 0.1524)
				(type default)
			)
			(fill no)
			(layer "F.SilkS")
		)
		(fp_poly
			(pts
				(arc
					(start 9.249918 3.750056)
					(mid 0 12.999974)
					(end -9.249918 3.750056)
				)
			)
			(stroke
				(width 0)
				(type default)
			)
			(fill yes)
			(layer "F.SilkS")
		)
		(fp_circle
			(center 0 3.750056)
			(end 9.249918 3.750056)
			(stroke
				(width 0.1)
				(type default)
			)
			(fill no)
			(layer "F.Fab")
		)
		(pad "1" thru_hole rect
			(at 0 0)
			(size 1.778 1.778)
			(drill 1.27)
			(layers "*.Cu" "*.Mask")
			(remove_unused_layers no)
			(net "P52V_HS2")
			(clearance 0)
			(padstack
				(mode front_inner_back)
				(layer "Inner"
					(shape circle)
					(size 1.778 1.778)
					(clearance 0)
				)
				(layer "B.Cu"
					(shape rect)
					(size 1.778 1.778)
					(clearance 0)
				)
			)
		)
		(pad "2" thru_hole circle
			(at 0 7.500112)
			(size 1.778 1.778)
			(drill 1.27)
			(layers "*.Cu" "*.Mask")
			(remove_unused_layers no)
			(net "GND")
			(clearance 0)
		)
	)
	(footprint ""
		(layer "F.Cu")
		(at 412.73476 -27.852878 90)
		(property "Reference" "R5919"
			(at 0 0 90)
			(layer "F.SilkS")
			(hide yes)
			(effects
				(font
					(size 1.27 1.27)
				)
			)
		)
		(property "Value" ""
			(at 0 0 90)
			(layer "F.Fab")
			(effects
				(font
					(size 1.27 1.27)
				)
			)
		)
		(duplicate_pad_numbers_are_jumpers no)
		(fp_line
			(start 0.7874 -0.4064)
			(end 0.7874 0.4064)
			(stroke
				(width 0.1524)
				(type default)
			)
			(layer "F.SilkS")
		)
		(fp_line
			(start -0.7874 -0.4064)
			(end 0.7874 -0.4064)
			(stroke
				(width 0.1524)
				(type default)
			)
			(layer "F.SilkS")
		)
		(fp_line
			(start 0.7874 0.4064)
			(end -0.7874 0.4064)
			(stroke
				(width 0.1524)
				(type default)
			)
			(layer "F.SilkS")
		)
		(fp_line
			(start -0.7874 0.4064)
			(end -0.7874 -0.4064)
			(stroke
				(width 0.1524)
				(type default)
			)
			(layer "F.SilkS")
		)
		(fp_line
			(start -0.12065 -0.305054)
			(end -0.12065 -0.2794)
			(stroke
				(width 0.1)
				(type default)
			)
			(layer "F.Fab")
		)
		(fp_line
			(start -0.67945 -0.305054)
			(end -0.12065 -0.305054)
			(stroke
				(width 0.1)
				(type default)
			)
			(layer "F.Fab")
		)
		(fp_line
			(start 0.67945 -0.3048)
			(end 0.67945 0.3048)
			(stroke
				(width 0.1)
				(type default)
			)
			(layer "F.Fab")
		)
		(fp_line
			(start 0.12065 -0.3048)
			(end 0.67945 -0.3048)
			(stroke
				(width 0.1)
				(type default)
			)
			(layer "F.Fab")
		)
		(fp_line
			(start 0.12065 -0.2794)
			(end 0.12065 -0.3048)
			(stroke
				(width 0.1)
				(type default)
			)
			(layer "F.Fab")
		)
		(fp_line
			(start -0.12065 -0.2794)
			(end 0.12065 -0.2794)
			(stroke
				(width 0.1)
				(type default)
			)
			(layer "F.Fab")
		)
		(fp_line
			(start 0.120396 0.2794)
			(end -0.12065 0.2794)
			(stroke
				(width 0.1)
				(type default)
			)
			(layer "F.Fab")
		)
		(fp_line
			(start -0.12065 0.2794)
			(end -0.12065 0.3048)
			(stroke
				(width 0.1)
				(type default)
			)
			(layer "F.Fab")
		)
		(fp_line
			(start 0.67945 0.3048)
			(end 0.120396 0.3048)
			(stroke
				(width 0.1)
				(type default)
			)
			(layer "F.Fab")
		)
		(fp_line
			(start 0.120396 0.3048)
			(end 0.120396 0.2794)
			(stroke
				(width 0.1)
				(type default)
			)
			(layer "F.Fab")
		)
		(fp_line
			(start -0.12065 0.3048)
			(end -0.67945 0.3048)
			(stroke
				(width 0.1)
				(type default)
			)
			(layer "F.Fab")
		)
		(fp_line
			(start -0.67945 0.3048)
			(end -0.67945 -0.305054)
			(stroke
				(width 0.1)
				(type default)
			)
			(layer "F.Fab")
		)
		(pad "1" smd rect
			(at -0.40005 0 270)
			(size 0.4572 0.508)
			(layers "F.Cu" "F.Mask" "F.Paste")
			(net "P12V_HPDB")
		)
		(pad "2" smd rect
			(at 0.40005 0 270)
			(size 0.4572 0.508)
			(layers "F.Cu" "F.Mask" "F.Paste")
			(net "P12V_LED_FB")
		)
	)
	(footprint ""
		(layer "F.Cu")
		(at 172.847 -84.709 90)
		(property "Reference" "C93"
			(at 0 0 90)
			(layer "F.SilkS")
			(hide yes)
			(effects
				(font
					(size 1.27 1.27)
				)
			)
		)
		(property "Value" ""
			(at 0 0 90)
			(layer "F.Fab")
			(effects
				(font
					(size 1.27 1.27)
				)
			)
		)
		(duplicate_pad_numbers_are_jumpers no)
		(fp_line
			(start 0.7874 -0.4064)
			(end 0.7874 0.4064)
			(stroke
				(width 0.1524)
				(type default)
			)
			(layer "F.SilkS")
		)
		(fp_line
			(start -0.7874 -0.4064)
			(end 0.7874 -0.4064)
			(stroke
				(width 0.1524)
				(type default)
			)
			(layer "F.SilkS")
		)
		(fp_line
			(start 0.7874 0.4064)
			(end -0.7874 0.4064)
			(stroke
				(width 0.1524)
				(type default)
			)
			(layer "F.SilkS")
		)
		(fp_line
			(start -0.7874 0.4064)
			(end -0.7874 -0.4064)
			(stroke
				(width 0.1524)
				(type default)
			)
			(layer "F.SilkS")
		)
		(fp_line
			(start -0.12065 -0.305054)
			(end -0.12065 -0.2794)
			(stroke
				(width 0.1)
				(type default)
			)
			(layer "F.Fab")
		)
		(fp_line
			(start -0.67945 -0.305054)
			(end -0.12065 -0.305054)
			(stroke
				(width 0.1)
				(type default)
			)
			(layer "F.Fab")
		)
		(fp_line
			(start 0.67945 -0.3048)
			(end 0.67945 0.3048)
			(stroke
				(width 0.1)
				(type default)
			)
			(layer "F.Fab")
		)
		(fp_line
			(start 0.12065 -0.3048)
			(end 0.67945 -0.3048)
			(stroke
				(width 0.1)
				(type default)
			)
			(layer "F.Fab")
		)
		(fp_line
			(start 0.12065 -0.2794)
			(end 0.12065 -0.3048)
			(stroke
				(width 0.1)
				(type default)
			)
			(layer "F.Fab")
		)
		(fp_line
			(start -0.12065 -0.2794)
			(end 0.12065 -0.2794)
			(stroke
				(width 0.1)
				(type default)
			)
			(layer "F.Fab")
		)
		(fp_line
			(start 0.120396 0.2794)
			(end -0.12065 0.2794)
			(stroke
				(width 0.1)
				(type default)
			)
			(layer "F.Fab")
		)
		(fp_line
			(start -0.12065 0.2794)
			(end -0.12065 0.3048)
			(stroke
				(width 0.1)
				(type default)
			)
			(layer "F.Fab")
		)
		(fp_line
			(start 0.67945 0.3048)
			(end 0.120396 0.3048)
			(stroke
				(width 0.1)
				(type default)
			)
			(layer "F.Fab")
		)
		(fp_line
			(start 0.120396 0.3048)
			(end 0.120396 0.2794)
			(stroke
				(width 0.1)
				(type default)
			)
			(layer "F.Fab")
		)
		(fp_line
			(start -0.12065 0.3048)
			(end -0.67945 0.3048)
			(stroke
				(width 0.1)
				(type default)
			)
			(layer "F.Fab")
		)
		(fp_line
			(start -0.67945 0.3048)
			(end -0.67945 -0.305054)
			(stroke
				(width 0.1)
				(type default)
			)
			(layer "F.Fab")
		)
		(pad "1" smd circle
			(at -0.40005 0 90)
			(size 0 0)
			(layers "F.Cu" "F.Mask" "F.Paste")
			(net "P3V3_2_AND")
		)
		(pad "2" smd circle
			(at 0.40005 0 90)
			(size 0 0)
			(layers "F.Cu" "F.Mask" "F.Paste")
			(net "GND")
		)
	)
	(footprint ""
		(layer "F.Cu")
		(at 176.1744 -64.897)
		(property "Reference" "PR6980"
			(at 0 0 0)
			(layer "F.SilkS")
			(hide yes)
			(effects
				(font
					(size 1.27 1.27)
				)
			)
		)
		(property "Value" ""
			(at 0 0 0)
			(layer "F.Fab")
			(effects
				(font
					(size 1.27 1.27)
				)
			)
		)
		(duplicate_pad_numbers_are_jumpers no)
		(fp_line
			(start -0.7874 -0.4064)
			(end 0.7874 -0.4064)
			(stroke
				(width 0.1524)
				(type default)
			)
			(layer "F.SilkS")
		)
		(fp_line
			(start -0.7874 0.4064)
			(end -0.7874 -0.4064)
			(stroke
				(width 0.1524)
				(type default)
			)
			(layer "F.SilkS")
		)
		(fp_line
			(start 0.7874 -0.4064)
			(end 0.7874 0.4064)
			(stroke
				(width 0.1524)
				(type default)
			)
			(layer "F.SilkS")
		)
		(fp_line
			(start 0.7874 0.4064)
			(end -0.7874 0.4064)
			(stroke
				(width 0.1524)
				(type default)
			)
			(layer "F.SilkS")
		)
		(fp_line
			(start -0.67945 -0.305054)
			(end -0.12065 -0.305054)
			(stroke
				(width 0.1)
				(type default)
			)
			(layer "F.Fab")
		)
		(fp_line
			(start -0.67945 0.3048)
			(end -0.67945 -0.305054)
			(stroke
				(width 0.1)
				(type default)
			)
			(layer "F.Fab")
		)
		(fp_line
			(start -0.12065 -0.305054)
			(end -0.12065 -0.2794)
			(stroke
				(width 0.1)
				(type default)
			)
			(layer "F.Fab")
		)
		(fp_line
			(start -0.12065 -0.2794)
			(end 0.12065 -0.2794)
			(stroke
				(width 0.1)
				(type default)
			)
			(layer "F.Fab")
		)
		(fp_line
			(start -0.12065 0.2794)
			(end -0.12065 0.3048)
			(stroke
				(width 0.1)
				(type default)
			)
			(layer "F.Fab")
		)
		(fp_line
			(start -0.12065 0.3048)
			(end -0.67945 0.3048)
			(stroke
				(width 0.1)
				(type default)
			)
			(layer "F.Fab")
		)
		(fp_line
			(start 0.120396 0.2794)
			(end -0.12065 0.2794)
			(stroke
				(width 0.1)
				(type default)
			)
			(layer "F.Fab")
		)
		(fp_line
			(start 0.120396 0.3048)
			(end 0.120396 0.2794)
			(stroke
				(width 0.1)
				(type default)
			)
			(layer "F.Fab")
		)
		(fp_line
			(start 0.12065 -0.3048)
			(end 0.67945 -0.3048)
			(stroke
				(width 0.1)
				(type default)
			)
			(layer "F.Fab")
		)
		(fp_line
			(start 0.12065 -0.2794)
			(end 0.12065 -0.3048)
			(stroke
				(width 0.1)
				(type default)
			)
			(layer "F.Fab")
		)
		(fp_line
			(start 0.67945 -0.3048)
			(end 0.67945 0.3048)
			(stroke
				(width 0.1)
				(type default)
			)
			(layer "F.Fab")
		)
		(fp_line
			(start 0.67945 0.3048)
			(end 0.120396 0.3048)
			(stroke
				(width 0.1)
				(type default)
			)
			(layer "F.Fab")
		)
		(pad "1" smd circle
			(at -0.40005 0)
			(size 0 0)
			(layers "F.Cu" "F.Mask" "F.Paste")
			(net "P52V_HS2_UVLO_EN")
		)
		(pad "2" smd circle
			(at 0.40005 0)
			(size 0 0)
			(layers "F.Cu" "F.Mask" "F.Paste")
			(net "GND1_FIELD_SIGNAL")
		)
	)
	(footprint ""
		(layer "F.Cu")
		(at 48.9204 -34.671 -90)
		(property "Reference" "PR104"
			(at 0 0 270)
			(layer "F.SilkS")
			(hide yes)
			(effects
				(font
					(size 1.27 1.27)
				)
			)
		)
		(property "Value" ""
			(at 0 0 270)
			(layer "F.Fab")
			(effects
				(font
					(size 1.27 1.27)
				)
			)
		)
		(duplicate_pad_numbers_are_jumpers no)
		(fp_line
			(start -2.234946 0.9271)
			(end -2.234946 -0.9271)
			(stroke
				(width 0.1524)
				(type default)
			)
			(layer "F.SilkS")
		)
		(fp_line
			(start 2.234946 0.9271)
			(end -2.234946 0.9271)
			(stroke
				(width 0.1524)
				(type default)
			)
			(layer "F.SilkS")
		)
		(fp_line
			(start -2.234946 -0.9271)
			(end 2.234946 -0.9271)
			(stroke
				(width 0.1524)
				(type default)
			)
			(layer "F.SilkS")
		)
		(fp_line
			(start 2.234946 -0.9271)
			(end 2.234946 0.9271)
			(stroke
				(width 0.1524)
				(type default)
			)
			(layer "F.SilkS")
		)
		(fp_line
			(start -1.575054 0.824992)
			(end 1.575054 0.824992)
			(stroke
				(width 0.1)
				(type default)
			)
			(layer "F.Fab")
		)
		(fp_line
			(start 1.575054 0.824992)
			(end 1.575054 -0.824992)
			(stroke
				(width 0.1)
				(type default)
			)
			(layer "F.Fab")
		)
		(fp_line
			(start -1.575054 -0.824992)
			(end -1.575054 0.824992)
			(stroke
				(width 0.1)
				(type default)
			)
			(layer "F.Fab")
		)
		(fp_line
			(start 1.575054 -0.824992)
			(end -1.575054 -0.824992)
			(stroke
				(width 0.1)
				(type default)
			)
			(layer "F.Fab")
		)
		(pad "1" smd rect
			(at -1.599946 0 270)
			(size 1.016 1.6002)
			(layers "F.Cu" "F.Mask" "F.Paste")
			(net "P52V_HS2")
		)
		(pad "2" smd rect
			(at 1.599946 0 270)
			(size 1.016 1.6002)
			(layers "F.Cu" "F.Mask" "F.Paste")
			(net "P52V_HS2_EN_DISCHARGE_N")
		)
	)
	(footprint ""
		(layer "F.Cu")
		(at 169.751756 -144.790668 -90)
		(property "Reference" "J12"
			(at 3.185668 -5.661914 90)
			(unlocked yes)
			(layer "F.SilkS")
			(effects
				(font
					(size 0.7874 0.5842)
					(thickness 0.1524)
				)
				(justify left)
			)
		)
		(property "Value" ""
			(at 0 0 270)
			(layer "F.Fab")
			(effects
				(font
					(size 1.27 1.27)
				)
			)
		)
		(duplicate_pad_numbers_are_jumpers no)
		(fp_line
			(start 0 4.011168)
			(end -3.330702 -4.771136)
			(stroke
				(width 0.1524)
				(type default)
			)
			(layer "F.SilkS")
		)
		(fp_line
			(start -3.330702 -4.771136)
			(end 3.330702 -4.771136)
			(stroke
				(width 0.1524)
				(type default)
			)
			(layer "F.SilkS")
		)
		(fp_line
			(start 3.330702 -4.771136)
			(end 0 4.011168)
			(stroke
				(width 0.1524)
				(type default)
			)
			(layer "F.SilkS")
		)
		(fp_line
			(start 0 4.011168)
			(end -3.330702 -4.771136)
			(stroke
				(width 0.1)
				(type default)
			)
			(layer "F.Fab")
		)
		(fp_line
			(start -3.330702 -4.771136)
			(end 3.330702 -4.771136)
			(stroke
				(width 0.1)
				(type default)
			)
			(layer "F.Fab")
		)
		(fp_line
			(start 3.330702 -4.771136)
			(end 0 4.011168)
			(stroke
				(width 0.1)
				(type default)
			)
			(layer "F.Fab")
		)
		(pad "1" thru_hole circle
			(at 0 0 270)
			(size 2.159 2.159)
			(drill 1.7018)
			(layers "*.Cu" "*.Mask")
			(remove_unused_layers no)
			(net "GND3")
			(clearance 0.0254)
			(thermal_gap 0.0254)
		)
		(pad "2" thru_hole circle
			(at -1.27 -3.348736 270)
			(size 2.159 2.159)
			(drill 1.7018)
			(layers "*.Cu" "*.Mask")
			(remove_unused_layers no)
			(net "TDR_SE_50_OHM_IN1")
			(clearance 0.0254)
			(thermal_gap 0.0254)
		)
		(pad "3" thru_hole circle
			(at 1.27 -3.348736 270)
			(size 2.159 2.159)
			(drill 1.7018)
			(layers "*.Cu" "*.Mask")
			(remove_unused_layers no)
			(net "TDR_SE_50_OHM_IN1")
			(clearance 0.0254)
			(thermal_gap 0.0254)
		)
	)
	(footprint ""
		(layer "F.Cu")
		(at 175.26 -45.339 180)
		(property "Reference" "R385"
			(at 0 0 180)
			(layer "F.SilkS")
			(hide yes)
			(effects
				(font
					(size 1.27 1.27)
				)
			)
		)
		(property "Value" ""
			(at 0 0 180)
			(layer "F.Fab")
			(effects
				(font
					(size 1.27 1.27)
				)
			)
		)
		(duplicate_pad_numbers_are_jumpers no)
		(fp_line
			(start 0.7874 0.4064)
			(end -0.7874 0.4064)
			(stroke
				(width 0.1524)
				(type default)
			)
			(layer "F.SilkS")
		)
		(fp_line
			(start 0.7874 -0.4064)
			(end 0.7874 0.4064)
			(stroke
				(width 0.1524)
				(type default)
			)
			(layer "F.SilkS")
		)
		(fp_line
			(start -0.7874 0.4064)
			(end -0.7874 -0.4064)
			(stroke
				(width 0.1524)
				(type default)
			)
			(layer "F.SilkS")
		)
		(fp_line
			(start -0.7874 -0.4064)
			(end 0.7874 -0.4064)
			(stroke
				(width 0.1524)
				(type default)
			)
			(layer "F.SilkS")
		)
		(fp_line
			(start 0.67945 0.3048)
			(end 0.120396 0.3048)
			(stroke
				(width 0.1)
				(type default)
			)
			(layer "F.Fab")
		)
		(fp_line
			(start 0.67945 -0.3048)
			(end 0.67945 0.3048)
			(stroke
				(width 0.1)
				(type default)
			)
			(layer "F.Fab")
		)
		(fp_line
			(start 0.12065 -0.2794)
			(end 0.12065 -0.3048)
			(stroke
				(width 0.1)
				(type default)
			)
			(layer "F.Fab")
		)
		(fp_line
			(start 0.12065 -0.3048)
			(end 0.67945 -0.3048)
			(stroke
				(width 0.1)
				(type default)
			)
			(layer "F.Fab")
		)
		(fp_line
			(start 0.120396 0.3048)
			(end 0.120396 0.2794)
			(stroke
				(width 0.1)
				(type default)
			)
			(layer "F.Fab")
		)
		(fp_line
			(start 0.120396 0.2794)
			(end -0.12065 0.2794)
			(stroke
				(width 0.1)
				(type default)
			)
			(layer "F.Fab")
		)
		(fp_line
			(start -0.12065 0.3048)
			(end -0.67945 0.3048)
			(stroke
				(width 0.1)
				(type default)
			)
			(layer "F.Fab")
		)
		(fp_line
			(start -0.12065 0.2794)
			(end -0.12065 0.3048)
			(stroke
				(width 0.1)
				(type default)
			)
			(layer "F.Fab")
		)
		(fp_line
			(start -0.12065 -0.2794)
			(end 0.12065 -0.2794)
			(stroke
				(width 0.1)
				(type default)
			)
			(layer "F.Fab")
		)
		(fp_line
			(start -0.12065 -0.305054)
			(end -0.12065 -0.2794)
			(stroke
				(width 0.1)
				(type default)
			)
			(layer "F.Fab")
		)
		(fp_line
			(start -0.67945 0.3048)
			(end -0.67945 -0.305054)
			(stroke
				(width 0.1)
				(type default)
			)
			(layer "F.Fab")
		)
		(fp_line
			(start -0.67945 -0.305054)
			(end -0.12065 -0.305054)
			(stroke
				(width 0.1)
				(type default)
			)
			(layer "F.Fab")
		)
		(pad "1" smd circle
			(at -0.40005 0 180)
			(size 0 0)
			(layers "F.Cu" "F.Mask" "F.Paste")
			(net "GPU_HSC2_BUF_EN_N")
		)
		(pad "2" smd circle
			(at 0.40005 0 180)
			(size 0 0)
			(layers "F.Cu" "F.Mask" "F.Paste")
			(net "GND")
		)
	)
	(footprint ""
		(layer "F.Cu")
		(at 435.5338 -23.749 180)
		(property "Reference" "R60"
			(at 0 0 180)
			(layer "F.SilkS")
			(hide yes)
			(effects
				(font
					(size 1.27 1.27)
				)
			)
		)
		(property "Value" ""
			(at 0 0 180)
			(layer "F.Fab")
			(effects
				(font
					(size 1.27 1.27)
				)
			)
		)
		(duplicate_pad_numbers_are_jumpers no)
		(fp_line
			(start 0.7874 0.4064)
			(end -0.7874 0.4064)
			(stroke
				(width 0.1524)
				(type default)
			)
			(layer "F.SilkS")
		)
		(fp_line
			(start 0.7874 -0.4064)
			(end 0.7874 0.4064)
			(stroke
				(width 0.1524)
				(type default)
			)
			(layer "F.SilkS")
		)
		(fp_line
			(start -0.7874 0.4064)
			(end -0.7874 -0.4064)
			(stroke
				(width 0.1524)
				(type default)
			)
			(layer "F.SilkS")
		)
		(fp_line
			(start -0.7874 -0.4064)
			(end 0.7874 -0.4064)
			(stroke
				(width 0.1524)
				(type default)
			)
			(layer "F.SilkS")
		)
		(fp_line
			(start 0.67945 0.3048)
			(end 0.120396 0.3048)
			(stroke
				(width 0.1)
				(type default)
			)
			(layer "F.Fab")
		)
		(fp_line
			(start 0.67945 -0.3048)
			(end 0.67945 0.3048)
			(stroke
				(width 0.1)
				(type default)
			)
			(layer "F.Fab")
		)
		(fp_line
			(start 0.12065 -0.2794)
			(end 0.12065 -0.3048)
			(stroke
				(width 0.1)
				(type default)
			)
			(layer "F.Fab")
		)
		(fp_line
			(start 0.12065 -0.3048)
			(end 0.67945 -0.3048)
			(stroke
				(width 0.1)
				(type default)
			)
			(layer "F.Fab")
		)
		(fp_line
			(start 0.120396 0.3048)
			(end 0.120396 0.2794)
			(stroke
				(width 0.1)
				(type default)
			)
			(layer "F.Fab")
		)
		(fp_line
			(start 0.120396 0.2794)
			(end -0.12065 0.2794)
			(stroke
				(width 0.1)
				(type default)
			)
			(layer "F.Fab")
		)
		(fp_line
			(start -0.12065 0.3048)
			(end -0.67945 0.3048)
			(stroke
				(width 0.1)
				(type default)
			)
			(layer "F.Fab")
		)
		(fp_line
			(start -0.12065 0.2794)
			(end -0.12065 0.3048)
			(stroke
				(width 0.1)
				(type default)
			)
			(layer "F.Fab")
		)
		(fp_line
			(start -0.12065 -0.2794)
			(end 0.12065 -0.2794)
			(stroke
				(width 0.1)
				(type default)
			)
			(layer "F.Fab")
		)
		(fp_line
			(start -0.12065 -0.305054)
			(end -0.12065 -0.2794)
			(stroke
				(width 0.1)
				(type default)
			)
			(layer "F.Fab")
		)
		(fp_line
			(start -0.67945 0.3048)
			(end -0.67945 -0.305054)
			(stroke
				(width 0.1)
				(type default)
			)
			(layer "F.Fab")
		)
		(fp_line
			(start -0.67945 -0.305054)
			(end -0.12065 -0.305054)
			(stroke
				(width 0.1)
				(type default)
			)
			(layer "F.Fab")
		)
		(pad "1" smd circle
			(at -0.40005 0 180)
			(size 0 0)
			(layers "F.Cu" "F.Mask" "F.Paste")
			(net "P3V3_AUX")
		)
		(pad "2" smd circle
			(at 0.40005 0 180)
			(size 0 0)
			(layers "F.Cu" "F.Mask" "F.Paste")
			(net "FRU_ADDR1")
		)
	)
	(footprint ""
		(layer "F.Cu")
		(at 414.4264 -38.862 90)
		(property "Reference" "U30"
			(at -1.30937 1.6891 0)
			(unlocked yes)
			(layer "F.SilkS")
			(effects
				(font
					(size 0.7874 0.5842)
					(thickness 0.1524)
				)
				(justify left)
			)
		)
		(property "Value" ""
			(at 0 0 90)
			(layer "F.Fab")
			(effects
				(font
					(size 1.27 1.27)
				)
			)
		)
		(duplicate_pad_numbers_are_jumpers no)
		(fp_line
			(start 1.603248 -1.500124)
			(end 1.603248 1.500124)
			(stroke
				(width 0.1524)
				(type default)
			)
			(layer "F.SilkS")
		)
		(fp_line
			(start -1.603248 -1.500124)
			(end 1.603248 -1.500124)
			(stroke
				(width 0.1524)
				(type default)
			)
			(layer "F.SilkS")
		)
		(fp_line
			(start 1.603248 1.500124)
			(end -1.603248 1.500124)
			(stroke
				(width 0.1524)
				(type default)
			)
			(layer "F.SilkS")
		)
		(fp_line
			(start -1.603248 1.500124)
			(end -1.603248 -1.500124)
			(stroke
				(width 0.1524)
				(type default)
			)
			(layer "F.SilkS")
		)
		(fp_line
			(start 0.700024 -1.500124)
			(end -0.700024 -1.500124)
			(stroke
				(width 0.1)
				(type default)
			)
			(layer "F.Fab")
		)
		(fp_line
			(start -0.700024 -1.500124)
			(end -0.700024 -1.169924)
			(stroke
				(width 0.1)
				(type default)
			)
			(layer "F.Fab")
		)
		(fp_line
			(start -0.700024 -1.169924)
			(end -1.249934 -1.169924)
			(stroke
				(width 0.1)
				(type default)
			)
			(layer "F.Fab")
		)
		(fp_line
			(start -1.249934 -1.169924)
			(end -1.249934 -0.729996)
			(stroke
				(width 0.1)
				(type default)
			)
			(layer "F.Fab")
		)
		(fp_line
			(start -0.6985 -0.729996)
			(end -0.6985 0.729996)
			(stroke
				(width 0.1)
				(type default)
			)
			(layer "F.Fab")
		)
		(fp_line
			(start -1.249934 -0.729996)
			(end -0.6985 -0.729996)
			(stroke
				(width 0.1)
				(type default)
			)
			(layer "F.Fab")
		)
		(fp_line
			(start 1.249934 -0.219964)
			(end 0.700024 -0.219964)
			(stroke
				(width 0.1)
				(type default)
			)
			(layer "F.Fab")
		)
		(fp_line
			(start 0.700024 -0.219964)
			(end 0.700024 -1.500124)
			(stroke
				(width 0.1)
				(type default)
			)
			(layer "F.Fab")
		)
		(fp_line
			(start 1.249934 0.219964)
			(end 1.249934 -0.219964)
			(stroke
				(width 0.1)
				(type default)
			)
			(layer "F.Fab")
		)
		(fp_line
			(start 0.700024 0.219964)
			(end 1.249934 0.219964)
			(stroke
				(width 0.1)
				(type default)
			)
			(layer "F.Fab")
		)
		(fp_line
			(start -0.6985 0.729996)
			(end -1.249934 0.729996)
			(stroke
				(width 0.1)
				(type default)
			)
			(layer "F.Fab")
		)
		(fp_line
			(start -1.249934 0.729996)
			(end -1.249934 1.169924)
			(stroke
				(width 0.1)
				(type default)
			)
			(layer "F.Fab")
		)
		(fp_line
			(start -0.700024 1.169924)
			(end -0.700024 1.500124)
			(stroke
				(width 0.1)
				(type default)
			)
			(layer "F.Fab")
		)
		(fp_line
			(start -1.249934 1.169924)
			(end -0.700024 1.169924)
			(stroke
				(width 0.1)
				(type default)
			)
			(layer "F.Fab")
		)
		(fp_line
			(start 0.700024 1.500124)
			(end 0.700024 0.219964)
			(stroke
				(width 0.1)
				(type default)
			)
			(layer "F.Fab")
		)
		(fp_line
			(start -0.700024 1.500124)
			(end 0.700024 1.500124)
			(stroke
				(width 0.1)
				(type default)
			)
			(layer "F.Fab")
		)
		(fp_rect
			(start -0.700024 1.500124)
			(end 0.700024 -1.500124)
			(stroke
				(width 0)
				(type default)
			)
			(fill no)
			(layer "F.Fab")
		)
		(pad "D" smd rect
			(at 0.999998 0)
			(size 0.8128 0.9144)
			(layers "F.Cu" "F.Mask" "F.Paste")
			(net "PWRGD_P52V_HS2_4287_PG")
		)
		(pad "G" smd rect
			(at -0.999998 -0.94996)
			(size 0.8128 0.9144)
			(layers "F.Cu" "F.Mask" "F.Paste")
			(net "PWRGD_P52V_HS2_4287_PG_R_N")
		)
		(pad "S" smd rect
			(at -0.999998 0.94996)
			(size 0.8128 0.9144)
			(layers "F.Cu" "F.Mask" "F.Paste")
			(net "GND")
		)
	)
	(footprint ""
		(layer "F.Cu")
		(at 449.199 -44.196 180)
		(property "Reference" "R186"
			(at 0 0 180)
			(layer "F.SilkS")
			(hide yes)
			(effects
				(font
					(size 1.27 1.27)
				)
			)
		)
		(property "Value" ""
			(at 0 0 180)
			(layer "F.Fab")
			(effects
				(font
					(size 1.27 1.27)
				)
			)
		)
		(duplicate_pad_numbers_are_jumpers no)
		(fp_line
			(start 0.7874 0.4064)
			(end -0.7874 0.4064)
			(stroke
				(width 0.1524)
				(type default)
			)
			(layer "F.SilkS")
		)
		(fp_line
			(start 0.7874 -0.4064)
			(end 0.7874 0.4064)
			(stroke
				(width 0.1524)
				(type default)
			)
			(layer "F.SilkS")
		)
		(fp_line
			(start -0.7874 0.4064)
			(end -0.7874 -0.4064)
			(stroke
				(width 0.1524)
				(type default)
			)
			(layer "F.SilkS")
		)
		(fp_line
			(start -0.7874 -0.4064)
			(end 0.7874 -0.4064)
			(stroke
				(width 0.1524)
				(type default)
			)
			(layer "F.SilkS")
		)
		(fp_line
			(start 0.67945 0.3048)
			(end 0.120396 0.3048)
			(stroke
				(width 0.1)
				(type default)
			)
			(layer "F.Fab")
		)
		(fp_line
			(start 0.67945 -0.3048)
			(end 0.67945 0.3048)
			(stroke
				(width 0.1)
				(type default)
			)
			(layer "F.Fab")
		)
		(fp_line
			(start 0.12065 -0.2794)
			(end 0.12065 -0.3048)
			(stroke
				(width 0.1)
				(type default)
			)
			(layer "F.Fab")
		)
		(fp_line
			(start 0.12065 -0.3048)
			(end 0.67945 -0.3048)
			(stroke
				(width 0.1)
				(type default)
			)
			(layer "F.Fab")
		)
		(fp_line
			(start 0.120396 0.3048)
			(end 0.120396 0.2794)
			(stroke
				(width 0.1)
				(type default)
			)
			(layer "F.Fab")
		)
		(fp_line
			(start 0.120396 0.2794)
			(end -0.12065 0.2794)
			(stroke
				(width 0.1)
				(type default)
			)
			(layer "F.Fab")
		)
		(fp_line
			(start -0.12065 0.3048)
			(end -0.67945 0.3048)
			(stroke
				(width 0.1)
				(type default)
			)
			(layer "F.Fab")
		)
		(fp_line
			(start -0.12065 0.2794)
			(end -0.12065 0.3048)
			(stroke
				(width 0.1)
				(type default)
			)
			(layer "F.Fab")
		)
		(fp_line
			(start -0.12065 -0.2794)
			(end 0.12065 -0.2794)
			(stroke
				(width 0.1)
				(type default)
			)
			(layer "F.Fab")
		)
		(fp_line
			(start -0.12065 -0.305054)
			(end -0.12065 -0.2794)
			(stroke
				(width 0.1)
				(type default)
			)
			(layer "F.Fab")
		)
		(fp_line
			(start -0.67945 0.3048)
			(end -0.67945 -0.305054)
			(stroke
				(width 0.1)
				(type default)
			)
			(layer "F.Fab")
		)
		(fp_line
			(start -0.67945 -0.305054)
			(end -0.12065 -0.305054)
			(stroke
				(width 0.1)
				(type default)
			)
			(layer "F.Fab")
		)
		(pad "1" smd circle
			(at -0.40005 0 180)
			(size 0 0)
			(layers "F.Cu" "F.Mask" "F.Paste")
			(net "GND")
		)
		(pad "2" smd circle
			(at 0.40005 0 180)
			(size 0 0)
			(layers "F.Cu" "F.Mask" "F.Paste")
			(net "GPU_HSC_BUF_EN")
		)
	)
	(footprint ""
		(layer "F.Cu")
		(at 263.5504 -48.387 90)
		(property "Reference" "R155"
			(at 0 0 90)
			(layer "F.SilkS")
			(hide yes)
			(effects
				(font
					(size 1.27 1.27)
				)
			)
		)
		(property "Value" ""
			(at 0 0 90)
			(layer "F.Fab")
			(effects
				(font
					(size 1.27 1.27)
				)
			)
		)
		(duplicate_pad_numbers_are_jumpers no)
		(fp_line
			(start 0.7874 -0.4064)
			(end 0.7874 0.4064)
			(stroke
				(width 0.1524)
				(type default)
			)
			(layer "F.SilkS")
		)
		(fp_line
			(start -0.7874 -0.4064)
			(end 0.7874 -0.4064)
			(stroke
				(width 0.1524)
				(type default)
			)
			(layer "F.SilkS")
		)
		(fp_line
			(start 0.7874 0.4064)
			(end -0.7874 0.4064)
			(stroke
				(width 0.1524)
				(type default)
			)
			(layer "F.SilkS")
		)
		(fp_line
			(start -0.7874 0.4064)
			(end -0.7874 -0.4064)
			(stroke
				(width 0.1524)
				(type default)
			)
			(layer "F.SilkS")
		)
		(fp_line
			(start -0.12065 -0.305054)
			(end -0.12065 -0.2794)
			(stroke
				(width 0.1)
				(type default)
			)
			(layer "F.Fab")
		)
		(fp_line
			(start -0.67945 -0.305054)
			(end -0.12065 -0.305054)
			(stroke
				(width 0.1)
				(type default)
			)
			(layer "F.Fab")
		)
		(fp_line
			(start 0.67945 -0.3048)
			(end 0.67945 0.3048)
			(stroke
				(width 0.1)
				(type default)
			)
			(layer "F.Fab")
		)
		(fp_line
			(start 0.12065 -0.3048)
			(end 0.67945 -0.3048)
			(stroke
				(width 0.1)
				(type default)
			)
			(layer "F.Fab")
		)
		(fp_line
			(start 0.12065 -0.2794)
			(end 0.12065 -0.3048)
			(stroke
				(width 0.1)
				(type default)
			)
			(layer "F.Fab")
		)
		(fp_line
			(start -0.12065 -0.2794)
			(end 0.12065 -0.2794)
			(stroke
				(width 0.1)
				(type default)
			)
			(layer "F.Fab")
		)
		(fp_line
			(start 0.120396 0.2794)
			(end -0.12065 0.2794)
			(stroke
				(width 0.1)
				(type default)
			)
			(layer "F.Fab")
		)
		(fp_line
			(start -0.12065 0.2794)
			(end -0.12065 0.3048)
			(stroke
				(width 0.1)
				(type default)
			)
			(layer "F.Fab")
		)
		(fp_line
			(start 0.67945 0.3048)
			(end 0.120396 0.3048)
			(stroke
				(width 0.1)
				(type default)
			)
			(layer "F.Fab")
		)
		(fp_line
			(start 0.120396 0.3048)
			(end 0.120396 0.2794)
			(stroke
				(width 0.1)
				(type default)
			)
			(layer "F.Fab")
		)
		(fp_line
			(start -0.12065 0.3048)
			(end -0.67945 0.3048)
			(stroke
				(width 0.1)
				(type default)
			)
			(layer "F.Fab")
		)
		(fp_line
			(start -0.67945 0.3048)
			(end -0.67945 -0.305054)
			(stroke
				(width 0.1)
				(type default)
			)
			(layer "F.Fab")
		)
		(pad "1" smd circle
			(at -0.40005 0 90)
			(size 0 0)
			(layers "F.Cu" "F.Mask" "F.Paste")
			(net "GPU_HSC1_BUF_EN_N")
		)
		(pad "2" smd circle
			(at 0.40005 0 90)
			(size 0 0)
			(layers "F.Cu" "F.Mask" "F.Paste")
			(net "GND")
		)
	)
	(footprint ""
		(layer "F.Cu")
		(at 436.753 -42.799)
		(property "Reference" "R3"
			(at 0 0 0)
			(layer "F.SilkS")
			(hide yes)
			(effects
				(font
					(size 1.27 1.27)
				)
			)
		)
		(property "Value" ""
			(at 0 0 0)
			(layer "F.Fab")
			(effects
				(font
					(size 1.27 1.27)
				)
			)
		)
		(duplicate_pad_numbers_are_jumpers no)
		(fp_line
			(start -0.7874 -0.4064)
			(end 0.7874 -0.4064)
			(stroke
				(width 0.1524)
				(type default)
			)
			(layer "F.SilkS")
		)
		(fp_line
			(start -0.7874 0.4064)
			(end -0.7874 -0.4064)
			(stroke
				(width 0.1524)
				(type default)
			)
			(layer "F.SilkS")
		)
		(fp_line
			(start 0.7874 -0.4064)
			(end 0.7874 0.4064)
			(stroke
				(width 0.1524)
				(type default)
			)
			(layer "F.SilkS")
		)
		(fp_line
			(start 0.7874 0.4064)
			(end -0.7874 0.4064)
			(stroke
				(width 0.1524)
				(type default)
			)
			(layer "F.SilkS")
		)
		(fp_line
			(start -0.67945 -0.305054)
			(end -0.12065 -0.305054)
			(stroke
				(width 0.1)
				(type default)
			)
			(layer "F.Fab")
		)
		(fp_line
			(start -0.67945 0.3048)
			(end -0.67945 -0.305054)
			(stroke
				(width 0.1)
				(type default)
			)
			(layer "F.Fab")
		)
		(fp_line
			(start -0.12065 -0.305054)
			(end -0.12065 -0.2794)
			(stroke
				(width 0.1)
				(type default)
			)
			(layer "F.Fab")
		)
		(fp_line
			(start -0.12065 -0.2794)
			(end 0.12065 -0.2794)
			(stroke
				(width 0.1)
				(type default)
			)
			(layer "F.Fab")
		)
		(fp_line
			(start -0.12065 0.2794)
			(end -0.12065 0.3048)
			(stroke
				(width 0.1)
				(type default)
			)
			(layer "F.Fab")
		)
		(fp_line
			(start -0.12065 0.3048)
			(end -0.67945 0.3048)
			(stroke
				(width 0.1)
				(type default)
			)
			(layer "F.Fab")
		)
		(fp_line
			(start 0.120396 0.2794)
			(end -0.12065 0.2794)
			(stroke
				(width 0.1)
				(type default)
			)
			(layer "F.Fab")
		)
		(fp_line
			(start 0.120396 0.3048)
			(end 0.120396 0.2794)
			(stroke
				(width 0.1)
				(type default)
			)
			(layer "F.Fab")
		)
		(fp_line
			(start 0.12065 -0.3048)
			(end 0.67945 -0.3048)
			(stroke
				(width 0.1)
				(type default)
			)
			(layer "F.Fab")
		)
		(fp_line
			(start 0.12065 -0.2794)
			(end 0.12065 -0.3048)
			(stroke
				(width 0.1)
				(type default)
			)
			(layer "F.Fab")
		)
		(fp_line
			(start 0.67945 -0.3048)
			(end 0.67945 0.3048)
			(stroke
				(width 0.1)
				(type default)
			)
			(layer "F.Fab")
		)
		(fp_line
			(start 0.67945 0.3048)
			(end 0.120396 0.3048)
			(stroke
				(width 0.1)
				(type default)
			)
			(layer "F.Fab")
		)
		(pad "1" smd circle
			(at -0.40005 0)
			(size 0 0)
			(layers "F.Cu" "F.Mask" "F.Paste")
			(net "PWRGD_P3V3_AUX_MB_BUF")
		)
		(pad "2" smd circle
			(at 0.40005 0)
			(size 0 0)
			(layers "F.Cu" "F.Mask" "F.Paste")
			(net "MB_MISC_I2C_EN")
		)
	)
	(footprint ""
		(layer "F.Cu")
		(at 406.146 -37.846 180)
		(property "Reference" "R40"
			(at 0 0 180)
			(layer "F.SilkS")
			(hide yes)
			(effects
				(font
					(size 1.27 1.27)
				)
			)
		)
		(property "Value" ""
			(at 0 0 180)
			(layer "F.Fab")
			(effects
				(font
					(size 1.27 1.27)
				)
			)
		)
		(duplicate_pad_numbers_are_jumpers no)
		(fp_line
			(start 2.234946 0.9271)
			(end -2.234946 0.9271)
			(stroke
				(width 0.1524)
				(type default)
			)
			(layer "F.SilkS")
		)
		(fp_line
			(start 2.234946 -0.9271)
			(end 2.234946 0.9271)
			(stroke
				(width 0.1524)
				(type default)
			)
			(layer "F.SilkS")
		)
		(fp_line
			(start -2.234946 0.9271)
			(end -2.234946 -0.9271)
			(stroke
				(width 0.1524)
				(type default)
			)
			(layer "F.SilkS")
		)
		(fp_line
			(start -2.234946 -0.9271)
			(end 2.234946 -0.9271)
			(stroke
				(width 0.1524)
				(type default)
			)
			(layer "F.SilkS")
		)
		(fp_line
			(start 1.575054 0.824992)
			(end 1.575054 -0.824992)
			(stroke
				(width 0.1)
				(type default)
			)
			(layer "F.Fab")
		)
		(fp_line
			(start 1.575054 -0.824992)
			(end -1.575054 -0.824992)
			(stroke
				(width 0.1)
				(type default)
			)
			(layer "F.Fab")
		)
		(fp_line
			(start -1.575054 0.824992)
			(end 1.575054 0.824992)
			(stroke
				(width 0.1)
				(type default)
			)
			(layer "F.Fab")
		)
		(fp_line
			(start -1.575054 -0.824992)
			(end -1.575054 0.824992)
			(stroke
				(width 0.1)
				(type default)
			)
			(layer "F.Fab")
		)
		(pad "1" smd rect
			(at -1.599946 0 180)
			(size 1.016 1.6002)
			(layers "F.Cu" "F.Mask" "F.Paste")
			(net "LED_D1_R1")
		)
		(pad "2" smd rect
			(at 1.599946 0 180)
			(size 1.016 1.6002)
			(layers "F.Cu" "F.Mask" "F.Paste")
			(net "LED_D1_R2")
		)
	)
	(footprint ""
		(layer "F.Cu")
		(at 452.0184 -62.23 -90)
		(property "Reference" "PC48"
			(at 0 0 270)
			(layer "F.SilkS")
			(hide yes)
			(effects
				(font
					(size 1.27 1.27)
				)
			)
		)
		(property "Value" ""
			(at 0 0 270)
			(layer "F.Fab")
			(effects
				(font
					(size 1.27 1.27)
				)
			)
		)
		(duplicate_pad_numbers_are_jumpers no)
		(fp_line
			(start -1.524 0.762)
			(end -1.524 -0.762)
			(stroke
				(width 0.1524)
				(type default)
			)
			(layer "F.SilkS")
		)
		(fp_line
			(start 1.524 0.762)
			(end -1.524 0.762)
			(stroke
				(width 0.1524)
				(type default)
			)
			(layer "F.SilkS")
		)
		(fp_line
			(start -1.524 -0.762)
			(end 1.524 -0.762)
			(stroke
				(width 0.1524)
				(type default)
			)
			(layer "F.SilkS")
		)
		(fp_line
			(start 1.524 -0.762)
			(end 1.524 0.762)
			(stroke
				(width 0.1524)
				(type default)
			)
			(layer "F.SilkS")
		)
		(fp_line
			(start -1.1049 0.724916)
			(end 1.1049 0.724916)
			(stroke
				(width 0.1)
				(type default)
			)
			(layer "F.Fab")
		)
		(fp_line
			(start 1.1049 0.724916)
			(end 1.1049 -0.724916)
			(stroke
				(width 0.1)
				(type default)
			)
			(layer "F.Fab")
		)
		(fp_line
			(start -1.1049 -0.724916)
			(end -1.1049 0.724916)
			(stroke
				(width 0.1)
				(type default)
			)
			(layer "F.Fab")
		)
		(fp_line
			(start 1.1049 -0.724916)
			(end -1.1049 -0.724916)
			(stroke
				(width 0.1)
				(type default)
			)
			(layer "F.Fab")
		)
		(pad "1" smd rect
			(at -0.889 0 90)
			(size 1.016 1.27)
			(layers "F.Cu" "F.Mask" "F.Paste")
			(net "P3V3_AUX")
		)
		(pad "2" smd rect
			(at 0.889 0 90)
			(size 1.016 1.27)
			(layers "F.Cu" "F.Mask" "F.Paste")
			(net "GND")
		)
	)
	(footprint ""
		(layer "F.Cu")
		(at 469.540082 -25.199848 90)
		(property "Reference" "J16"
			(at 6.523482 -1.291082 0)
			(unlocked yes)
			(layer "F.SilkS")
			(effects
				(font
					(size 0.7874 0.5842)
					(thickness 0.1524)
				)
				(justify left)
			)
		)
		(property "Value" ""
			(at 0 0 90)
			(layer "F.Fab")
			(effects
				(font
					(size 1.27 1.27)
				)
			)
		)
		(duplicate_pad_numbers_are_jumpers no)
		(fp_circle
			(center 0 0)
			(end 0 5.3848)
			(stroke
				(width 0.1524)
				(type default)
			)
			(fill no)
			(layer "F.SilkS")
		)
		(fp_line
			(start 3.999992 -2.999994)
			(end 4.000246 2.999994)
			(stroke
				(width 0.1)
				(type default)
			)
			(layer "F.Fab")
		)
		(fp_line
			(start -3.999992 2.999994)
			(end -3.999738 -2.999994)
			(stroke
				(width 0.1)
				(type default)
			)
			(layer "F.Fab")
		)
		(fp_arc
			(start -3.999738 -2.999994)
			(mid 0.000178 -4.99999)
			(end 3.999992 -2.999994)
			(stroke
				(width 0.1)
				(type default)
			)
			(layer "F.Fab")
		)
		(fp_arc
			(start 4.000246 2.999994)
			(mid 0.000178 4.99999)
			(end -3.999992 2.999994)
			(stroke
				(width 0.1)
				(type default)
			)
			(layer "F.Fab")
		)
		(pad "G1" thru_hole oval
			(at 0 -3.262376 90)
			(size 1.8796 3.1242)
			(drill oval 1.6256 2.8702)
			(layers "*.Cu" "*.Mask")
			(remove_unused_layers no)
			(net "GND")
			(clearance 0.254)
			(thermal_gap 0.254)
		)
		(pad "SCR_G1" thru_hole circle
			(at 0 0 90)
			(size 10.5156 10.5156)
			(drill 5.1562)
			(layers "*.Cu" "*.Mask")
			(remove_unused_layers no)
			(net "GND")
			(clearance 0)
		)
		(zone
			(layers "F.Cu" "B.Cu" "In1.Cu" "In2.Cu" "In3.Cu" "In4.Cu" "In5.Cu" "In6.Cu"
				"In7.Cu" "In8.Cu"
			)
			(hatch none 0.5)
			(connect_pads
				(clearance 0)
			)
			(min_thickness 0.25)
			(keepout
				(tracks not_allowed)
				(vias allowed)
				(pads allowed)
				(copperpour not_allowed)
				(footprints allowed)
			)
			(placement
				(enabled no)
				(sheetname "")
			)
			(fill
				(thermal_gap 0.5)
				(thermal_bridge_width 0.5)
				(island_removal_mode 0)
			)
			(polygon
				(pts
					(arc
						(start 542.615882 -26.850848)
						(mid 532.100282 -26.850848)
						(end 542.615882 -26.850848)
					)
				)
			)
		)
	)
	(footprint ""
		(layer "F.Cu")
		(at 429.2854 -34.1376 90)
		(property "Reference" "R58"
			(at 0 0 90)
			(layer "F.SilkS")
			(hide yes)
			(effects
				(font
					(size 1.27 1.27)
				)
			)
		)
		(property "Value" ""
			(at 0 0 90)
			(layer "F.Fab")
			(effects
				(font
					(size 1.27 1.27)
				)
			)
		)
		(duplicate_pad_numbers_are_jumpers no)
		(fp_line
			(start 0.7874 -0.4064)
			(end 0.7874 0.4064)
			(stroke
				(width 0.1524)
				(type default)
			)
			(layer "F.SilkS")
		)
		(fp_line
			(start -0.7874 -0.4064)
			(end 0.7874 -0.4064)
			(stroke
				(width 0.1524)
				(type default)
			)
			(layer "F.SilkS")
		)
		(fp_line
			(start 0.7874 0.4064)
			(end -0.7874 0.4064)
			(stroke
				(width 0.1524)
				(type default)
			)
			(layer "F.SilkS")
		)
		(fp_line
			(start -0.7874 0.4064)
			(end -0.7874 -0.4064)
			(stroke
				(width 0.1524)
				(type default)
			)
			(layer "F.SilkS")
		)
		(fp_line
			(start -0.12065 -0.305054)
			(end -0.12065 -0.2794)
			(stroke
				(width 0.1)
				(type default)
			)
			(layer "F.Fab")
		)
		(fp_line
			(start -0.67945 -0.305054)
			(end -0.12065 -0.305054)
			(stroke
				(width 0.1)
				(type default)
			)
			(layer "F.Fab")
		)
		(fp_line
			(start 0.67945 -0.3048)
			(end 0.67945 0.3048)
			(stroke
				(width 0.1)
				(type default)
			)
			(layer "F.Fab")
		)
		(fp_line
			(start 0.12065 -0.3048)
			(end 0.67945 -0.3048)
			(stroke
				(width 0.1)
				(type default)
			)
			(layer "F.Fab")
		)
		(fp_line
			(start 0.12065 -0.2794)
			(end 0.12065 -0.3048)
			(stroke
				(width 0.1)
				(type default)
			)
			(layer "F.Fab")
		)
		(fp_line
			(start -0.12065 -0.2794)
			(end 0.12065 -0.2794)
			(stroke
				(width 0.1)
				(type default)
			)
			(layer "F.Fab")
		)
		(fp_line
			(start 0.120396 0.2794)
			(end -0.12065 0.2794)
			(stroke
				(width 0.1)
				(type default)
			)
			(layer "F.Fab")
		)
		(fp_line
			(start -0.12065 0.2794)
			(end -0.12065 0.3048)
			(stroke
				(width 0.1)
				(type default)
			)
			(layer "F.Fab")
		)
		(fp_line
			(start 0.67945 0.3048)
			(end 0.120396 0.3048)
			(stroke
				(width 0.1)
				(type default)
			)
			(layer "F.Fab")
		)
		(fp_line
			(start 0.120396 0.3048)
			(end 0.120396 0.2794)
			(stroke
				(width 0.1)
				(type default)
			)
			(layer "F.Fab")
		)
		(fp_line
			(start -0.12065 0.3048)
			(end -0.67945 0.3048)
			(stroke
				(width 0.1)
				(type default)
			)
			(layer "F.Fab")
		)
		(fp_line
			(start -0.67945 0.3048)
			(end -0.67945 -0.305054)
			(stroke
				(width 0.1)
				(type default)
			)
			(layer "F.Fab")
		)
		(pad "1" smd circle
			(at -0.40005 0 90)
			(size 0 0)
			(layers "F.Cu" "F.Mask" "F.Paste")
			(net "FRU_WP_N")
		)
		(pad "2" smd circle
			(at 0.40005 0 90)
			(size 0 0)
			(layers "F.Cu" "F.Mask" "F.Paste")
			(net "GND")
		)
	)
	(footprint ""
		(layer "F.Cu")
		(at 190.000128 -16.500094 180)
		(property "Reference" "H7"
			(at 0.643128 -5.477764 0)
			(unlocked yes)
			(layer "F.SilkS")
			(effects
				(font
					(size 0.7874 0.5842)
					(thickness 0.1524)
				)
				(justify left)
			)
		)
		(property "Value" ""
			(at 0 0 180)
			(layer "F.Fab")
			(effects
				(font
					(size 1.27 1.27)
				)
			)
		)
		(duplicate_pad_numbers_are_jumpers no)
		(pad "1" thru_hole oval
			(at 0 0 180)
			(size 9.017 14.0208)
			(drill 3.0226
				(offset 0 2.499868)
			)
			(layers "*.Cu" "*.Mask")
			(remove_unused_layers no)
			(net "GND")
			(clearance -1.500378)
			(padstack
				(mode front_inner_back)
				(layer "Inner"
					(shape circle)
					(size 0 0)
					(clearance 0)
				)
				(layer "B.Cu"
					(shape oval)
					(size 9.017 14.0208)
					(offset 0 2.499868)
					(clearance -1.500378)
				)
			)
		)
	)
	(footprint ""
		(layer "F.Cu")
		(at 304.616358 -29.5402)
		(property "Reference" "PR315"
			(at -4.197858 4.68757 0)
			(unlocked yes)
			(layer "F.SilkS")
			(effects
				(font
					(size 0.7874 0.5842)
					(thickness 0.1524)
				)
				(justify left)
			)
		)
		(property "Value" ""
			(at 0 0 0)
			(layer "F.Fab")
			(effects
				(font
					(size 1.27 1.27)
				)
			)
		)
		(duplicate_pad_numbers_are_jumpers no)
		(fp_line
			(start -3.9878 -3.5814)
			(end 3.9878 -3.5814)
			(stroke
				(width 0.1524)
				(type default)
			)
			(layer "F.SilkS")
		)
		(fp_line
			(start -3.9878 3.5814)
			(end -3.9878 -3.5814)
			(stroke
				(width 0.1524)
				(type default)
			)
			(layer "F.SilkS")
		)
		(fp_line
			(start 3.9878 -3.5814)
			(end 3.9878 3.5814)
			(stroke
				(width 0.1524)
				(type default)
			)
			(layer "F.SilkS")
		)
		(fp_line
			(start 3.9878 3.5814)
			(end -3.9878 3.5814)
			(stroke
				(width 0.1524)
				(type default)
			)
			(layer "F.SilkS")
		)
		(fp_line
			(start -3.5306 -3.353054)
			(end 3.5306 -3.353054)
			(stroke
				(width 0.1)
				(type default)
			)
			(layer "F.Fab")
		)
		(fp_line
			(start -3.5306 3.353054)
			(end -3.5306 -3.353054)
			(stroke
				(width 0.1)
				(type default)
			)
			(layer "F.Fab")
		)
		(fp_line
			(start 3.5306 -3.353054)
			(end 3.5306 3.353054)
			(stroke
				(width 0.1)
				(type default)
			)
			(layer "F.Fab")
		)
		(fp_line
			(start 3.5306 3.353054)
			(end -3.5306 3.353054)
			(stroke
				(width 0.1)
				(type default)
			)
			(layer "F.Fab")
		)
		(pad "1A" smd rect
			(at -2.249932 0 180)
			(size 3.2004 6.858)
			(layers "F.Cu" "F.Mask" "F.Paste")
			(net "P52V_1")
		)
		(pad "1B" smd rect
			(at -0.776732 0)
			(size 0.254 0.508)
			(layers "F.Cu" "F.Mask" "F.Paste")
			(net "P52V_HS1_SENSE_P_R2")
		)
		(pad "2A" smd rect
			(at 2.249932 0 180)
			(size 3.2004 6.858)
			(layers "F.Cu" "F.Mask" "F.Paste")
			(net "P52V_HS1_DRAIN_2")
		)
		(pad "2B" smd rect
			(at 0.776732 0)
			(size 0.254 0.508)
			(layers "F.Cu" "F.Mask" "F.Paste")
			(net "P52V_HS1_SENSE_N_R2")
		)
	)
	(footprint ""
		(layer "F.Cu")
		(at 8.200136 -137.500106 180)
		(property "Reference" "H19"
			(at -1.007364 -6.475476 0)
			(unlocked yes)
			(layer "F.SilkS")
			(effects
				(font
					(size 0.7874 0.5842)
					(thickness 0.1524)
				)
				(justify left)
			)
		)
		(property "Value" ""
			(at 0 0 180)
			(layer "F.Fab")
			(effects
				(font
					(size 1.27 1.27)
				)
			)
		)
		(duplicate_pad_numbers_are_jumpers no)
		(pad "1" thru_hole circle
			(at 0 0 180)
			(size 10.16 10.16)
			(drill 6.4008
				(offset 0 0)
			)
			(layers "*.Cu" "*.Mask")
			(remove_unused_layers no)
			(net "GND")
			(clearance -1.6256)
			(padstack
				(mode front_inner_back)
				(layer "Inner"
					(shape circle)
					(size 10.16 10.16)
					(clearance -1.6256)
				)
				(layer "B.Cu"
					(shape oval)
					(size 10.0076 17.018)
					(offset 0 3.499866)
					(clearance -1.5494)
				)
			)
		)
	)
	(footprint ""
		(layer "F.Cu")
		(at 424.999912 -126.500128 180)
		(property "Reference" "H37"
			(at -1.021588 -5.762498 0)
			(unlocked yes)
			(layer "F.SilkS")
			(effects
				(font
					(size 0.7874 0.5842)
					(thickness 0.1524)
				)
				(justify left)
			)
		)
		(property "Value" ""
			(at 0 0 180)
			(layer "F.Fab")
			(effects
				(font
					(size 1.27 1.27)
				)
			)
		)
		(duplicate_pad_numbers_are_jumpers no)
		(pad "1" thru_hole circle
			(at 0 0 180)
			(size 10.16 10.16)
			(drill 6.4008
				(offset 0 0)
			)
			(layers "*.Cu" "*.Mask")
			(remove_unused_layers no)
			(net "GND")
			(clearance -1.6256)
			(padstack
				(mode front_inner_back)
				(layer "Inner"
					(shape circle)
					(size 10.16 10.16)
					(clearance -1.6256)
				)
				(layer "B.Cu"
					(shape oval)
					(size 10.0076 17.018)
					(offset 0 3.499866)
					(clearance -1.5494)
				)
			)
		)
	)
	(footprint ""
		(layer "F.Cu")
		(at 436.10022 -127.793496)
		(property "Reference" ""
			(at 0 0 0)
			(layer "F.SilkS")
			(hide yes)
			(effects
				(font
					(size 1.27 1.27)
				)
			)
		)
		(property "Value" ""
			(at 0 0 0)
			(layer "F.Fab")
			(effects
				(font
					(size 1.27 1.27)
				)
			)
		)
		(duplicate_pad_numbers_are_jumpers no)
		(pad "1" smd circle
			(at 0 0)
			(size 0.9906 0.9906)
			(layers "F.Cu" "F.Mask" "F.Paste")
			(net "Net_377")
		)
		(zone
			(layer "F.Cu")
			(hatch none 0.5)
			(connect_pads
				(clearance 0)
			)
			(min_thickness 0.25)
			(keepout
				(tracks not_allowed)
				(vias allowed)
				(pads allowed)
				(copperpour not_allowed)
				(footprints allowed)
			)
			(placement
				(enabled no)
				(sheetname "")
			)
			(fill
				(thermal_gap 0.5)
				(thermal_bridge_width 0.5)
				(island_removal_mode 0)
			)
			(polygon
				(pts
					(arc
						(start 437.72582 -127.793496)
						(mid 434.47462 -127.793496)
						(end 437.72582 -127.793496)
					)
				)
			)
		)
	)
	(footprint ""
		(layer "F.Cu")
		(at 334.631284 -72.898 -90)
		(property "Reference" "PR474"
			(at 0 0 270)
			(layer "F.SilkS")
			(hide yes)
			(effects
				(font
					(size 1.27 1.27)
				)
			)
		)
		(property "Value" ""
			(at 0 0 270)
			(layer "F.Fab")
			(effects
				(font
					(size 1.27 1.27)
				)
			)
		)
		(duplicate_pad_numbers_are_jumpers no)
		(fp_line
			(start -1.2954 0.5842)
			(end -1.2954 -0.5842)
			(stroke
				(width 0.1524)
				(type default)
			)
			(layer "F.SilkS")
		)
		(fp_line
			(start 1.2954 0.5842)
			(end -1.2954 0.5842)
			(stroke
				(width 0.1524)
				(type default)
			)
			(layer "F.SilkS")
		)
		(fp_line
			(start -1.2954 -0.5842)
			(end 1.2954 -0.5842)
			(stroke
				(width 0.1524)
				(type default)
			)
			(layer "F.SilkS")
		)
		(fp_line
			(start 1.2954 -0.5842)
			(end 1.2954 0.5842)
			(stroke
				(width 0.1524)
				(type default)
			)
			(layer "F.SilkS")
		)
		(fp_line
			(start -0.8636 0.4572)
			(end -0.8636 0.4318)
			(stroke
				(width 0.1)
				(type default)
			)
			(layer "F.Fab")
		)
		(fp_line
			(start 0.8636 0.4572)
			(end -0.8636 0.4572)
			(stroke
				(width 0.1)
				(type default)
			)
			(layer "F.Fab")
		)
		(fp_line
			(start -0.8636 0.4318)
			(end -0.8636 0.4064)
			(stroke
				(width 0.1)
				(type default)
			)
			(layer "F.Fab")
		)
		(fp_line
			(start -1.1938 0.4064)
			(end -1.1938 -0.406654)
			(stroke
				(width 0.1)
				(type default)
			)
			(layer "F.Fab")
		)
		(fp_line
			(start -0.8636 0.4064)
			(end -1.1938 0.4064)
			(stroke
				(width 0.1)
				(type default)
			)
			(layer "F.Fab")
		)
		(fp_line
			(start 0.8636 0.4064)
			(end 0.8636 0.4572)
			(stroke
				(width 0.1)
				(type default)
			)
			(layer "F.Fab")
		)
		(fp_line
			(start 1.1938 0.4064)
			(end 0.8636 0.4064)
			(stroke
				(width 0.1)
				(type default)
			)
			(layer "F.Fab")
		)
		(fp_line
			(start -1.1938 -0.406654)
			(end -0.8636 -0.406654)
			(stroke
				(width 0.1)
				(type default)
			)
			(layer "F.Fab")
		)
		(fp_line
			(start -0.8636 -0.406654)
			(end -0.8636 -0.4572)
			(stroke
				(width 0.1)
				(type default)
			)
			(layer "F.Fab")
		)
		(fp_line
			(start 0.8636 -0.406654)
			(end 1.1938 -0.406654)
			(stroke
				(width 0.1)
				(type default)
			)
			(layer "F.Fab")
		)
		(fp_line
			(start 1.1938 -0.406654)
			(end 1.1938 0.4064)
			(stroke
				(width 0.1)
				(type default)
			)
			(layer "F.Fab")
		)
		(fp_line
			(start -0.8636 -0.4572)
			(end 0.8636 -0.4572)
			(stroke
				(width 0.1)
				(type default)
			)
			(layer "F.Fab")
		)
		(fp_line
			(start 0.8636 -0.4572)
			(end 0.8636 -0.406654)
			(stroke
				(width 0.1)
				(type default)
			)
			(layer "F.Fab")
		)
		(pad "1" smd rect
			(at -0.7366 0 180)
			(size 0.7112 0.8128)
			(layers "F.Cu" "F.Mask" "F.Paste")
			(net "P52V_HS1_GATE1_R")
		)
		(pad "2" smd rect
			(at 0.7366 0 180)
			(size 0.7112 0.8128)
			(layers "F.Cu" "F.Mask" "F.Paste")
			(net "P52V_HS1_GATE1")
		)
	)
	(footprint ""
		(layer "F.Cu")
		(at 450.445632 -88.465152)
		(property "Reference" "R393"
			(at 0 0 0)
			(layer "F.SilkS")
			(hide yes)
			(effects
				(font
					(size 1.27 1.27)
				)
			)
		)
		(property "Value" ""
			(at 0 0 0)
			(layer "F.Fab")
			(effects
				(font
					(size 1.27 1.27)
				)
			)
		)
		(duplicate_pad_numbers_are_jumpers no)
		(fp_line
			(start -0.7874 -0.4064)
			(end 0.7874 -0.4064)
			(stroke
				(width 0.1524)
				(type default)
			)
			(layer "F.SilkS")
		)
		(fp_line
			(start -0.7874 0.4064)
			(end -0.7874 -0.4064)
			(stroke
				(width 0.1524)
				(type default)
			)
			(layer "F.SilkS")
		)
		(fp_line
			(start 0.7874 -0.4064)
			(end 0.7874 0.4064)
			(stroke
				(width 0.1524)
				(type default)
			)
			(layer "F.SilkS")
		)
		(fp_line
			(start 0.7874 0.4064)
			(end -0.7874 0.4064)
			(stroke
				(width 0.1524)
				(type default)
			)
			(layer "F.SilkS")
		)
		(fp_line
			(start -0.67945 -0.305054)
			(end -0.12065 -0.305054)
			(stroke
				(width 0.1)
				(type default)
			)
			(layer "F.Fab")
		)
		(fp_line
			(start -0.67945 0.3048)
			(end -0.67945 -0.305054)
			(stroke
				(width 0.1)
				(type default)
			)
			(layer "F.Fab")
		)
		(fp_line
			(start -0.12065 -0.305054)
			(end -0.12065 -0.2794)
			(stroke
				(width 0.1)
				(type default)
			)
			(layer "F.Fab")
		)
		(fp_line
			(start -0.12065 -0.2794)
			(end 0.12065 -0.2794)
			(stroke
				(width 0.1)
				(type default)
			)
			(layer "F.Fab")
		)
		(fp_line
			(start -0.12065 0.2794)
			(end -0.12065 0.3048)
			(stroke
				(width 0.1)
				(type default)
			)
			(layer "F.Fab")
		)
		(fp_line
			(start -0.12065 0.3048)
			(end -0.67945 0.3048)
			(stroke
				(width 0.1)
				(type default)
			)
			(layer "F.Fab")
		)
		(fp_line
			(start 0.120396 0.2794)
			(end -0.12065 0.2794)
			(stroke
				(width 0.1)
				(type default)
			)
			(layer "F.Fab")
		)
		(fp_line
			(start 0.120396 0.3048)
			(end 0.120396 0.2794)
			(stroke
				(width 0.1)
				(type default)
			)
			(layer "F.Fab")
		)
		(fp_line
			(start 0.12065 -0.3048)
			(end 0.67945 -0.3048)
			(stroke
				(width 0.1)
				(type default)
			)
			(layer "F.Fab")
		)
		(fp_line
			(start 0.12065 -0.2794)
			(end 0.12065 -0.3048)
			(stroke
				(width 0.1)
				(type default)
			)
			(layer "F.Fab")
		)
		(fp_line
			(start 0.67945 -0.3048)
			(end 0.67945 0.3048)
			(stroke
				(width 0.1)
				(type default)
			)
			(layer "F.Fab")
		)
		(fp_line
			(start 0.67945 0.3048)
			(end 0.120396 0.3048)
			(stroke
				(width 0.1)
				(type default)
			)
			(layer "F.Fab")
		)
		(pad "1" smd circle
			(at -0.40005 0)
			(size 0 0)
			(layers "F.Cu" "F.Mask" "F.Paste")
			(net "P3V3_HPDB_EN")
		)
		(pad "2" smd circle
			(at 0.40005 0)
			(size 0 0)
			(layers "F.Cu" "F.Mask" "F.Paste")
			(net "GND")
		)
	)
	(footprint ""
		(layer "F.Cu")
		(at 422.148 -27.94 -90)
		(property "Reference" "C94"
			(at 0 0 270)
			(layer "F.SilkS")
			(hide yes)
			(effects
				(font
					(size 1.27 1.27)
				)
			)
		)
		(property "Value" ""
			(at 0 0 270)
			(layer "F.Fab")
			(effects
				(font
					(size 1.27 1.27)
				)
			)
		)
		(duplicate_pad_numbers_are_jumpers no)
		(fp_line
			(start -0.7874 0.4064)
			(end -0.7874 -0.4064)
			(stroke
				(width 0.1524)
				(type default)
			)
			(layer "F.SilkS")
		)
		(fp_line
			(start 0.7874 0.4064)
			(end -0.7874 0.4064)
			(stroke
				(width 0.1524)
				(type default)
			)
			(layer "F.SilkS")
		)
		(fp_line
			(start -0.7874 -0.4064)
			(end 0.7874 -0.4064)
			(stroke
				(width 0.1524)
				(type default)
			)
			(layer "F.SilkS")
		)
		(fp_line
			(start 0.7874 -0.4064)
			(end 0.7874 0.4064)
			(stroke
				(width 0.1524)
				(type default)
			)
			(layer "F.SilkS")
		)
		(fp_line
			(start -0.6858 0.3048)
			(end -0.6858 -0.3048)
			(stroke
				(width 0.1)
				(type default)
			)
			(layer "F.Fab")
		)
		(fp_line
			(start -0.1016 0.3048)
			(end -0.6858 0.3048)
			(stroke
				(width 0.1)
				(type default)
			)
			(layer "F.Fab")
		)
		(fp_line
			(start 0.1016 0.3048)
			(end 0.1016 0.2794)
			(stroke
				(width 0.1)
				(type default)
			)
			(layer "F.Fab")
		)
		(fp_line
			(start 0.6858 0.3048)
			(end 0.1016 0.3048)
			(stroke
				(width 0.1)
				(type default)
			)
			(layer "F.Fab")
		)
		(fp_line
			(start -0.1016 0.2794)
			(end -0.1016 0.3048)
			(stroke
				(width 0.1)
				(type default)
			)
			(layer "F.Fab")
		)
		(fp_line
			(start 0.1016 0.2794)
			(end -0.1016 0.2794)
			(stroke
				(width 0.1)
				(type default)
			)
			(layer "F.Fab")
		)
		(fp_line
			(start -0.1016 -0.2794)
			(end 0.1016 -0.2794)
			(stroke
				(width 0.1)
				(type default)
			)
			(layer "F.Fab")
		)
		(fp_line
			(start 0.1016 -0.2794)
			(end 0.1016 -0.3048)
			(stroke
				(width 0.1)
				(type default)
			)
			(layer "F.Fab")
		)
		(fp_line
			(start -0.6858 -0.3048)
			(end -0.1016 -0.3048)
			(stroke
				(width 0.1)
				(type default)
			)
			(layer "F.Fab")
		)
		(fp_line
			(start -0.1016 -0.3048)
			(end -0.1016 -0.2794)
			(stroke
				(width 0.1)
				(type default)
			)
			(layer "F.Fab")
		)
		(fp_line
			(start 0.1016 -0.3048)
			(end 0.6858 -0.3048)
			(stroke
				(width 0.1)
				(type default)
			)
			(layer "F.Fab")
		)
		(fp_line
			(start 0.6858 -0.3048)
			(end 0.6858 0.3048)
			(stroke
				(width 0.1)
				(type default)
			)
			(layer "F.Fab")
		)
		(pad "1" smd rect
			(at -0.40005 0 90)
			(size 0.4572 0.508)
			(layers "F.Cu" "F.Mask" "F.Paste")
			(net "P12V_HPDB")
		)
		(pad "2" smd rect
			(at 0.40005 0 90)
			(size 0.4572 0.508)
			(layers "F.Cu" "F.Mask" "F.Paste")
			(net "GND")
		)
	)
	(footprint ""
		(layer "F.Cu")
		(at 140.79982 -68.199 180)
		(property "Reference" "PR6986"
			(at 0 0 180)
			(layer "F.SilkS")
			(hide yes)
			(effects
				(font
					(size 1.27 1.27)
				)
			)
		)
		(property "Value" ""
			(at 0 0 180)
			(layer "F.Fab")
			(effects
				(font
					(size 1.27 1.27)
				)
			)
		)
		(duplicate_pad_numbers_are_jumpers no)
		(fp_line
			(start 1.2954 0.5842)
			(end -1.2954 0.5842)
			(stroke
				(width 0.1524)
				(type default)
			)
			(layer "F.SilkS")
		)
		(fp_line
			(start 1.2954 -0.5842)
			(end 1.2954 0.5842)
			(stroke
				(width 0.1524)
				(type default)
			)
			(layer "F.SilkS")
		)
		(fp_line
			(start -1.2954 0.5842)
			(end -1.2954 -0.5842)
			(stroke
				(width 0.1524)
				(type default)
			)
			(layer "F.SilkS")
		)
		(fp_line
			(start -1.2954 -0.5842)
			(end 1.2954 -0.5842)
			(stroke
				(width 0.1524)
				(type default)
			)
			(layer "F.SilkS")
		)
		(fp_line
			(start 1.1938 0.4064)
			(end 0.8636 0.4064)
			(stroke
				(width 0.1)
				(type default)
			)
			(layer "F.Fab")
		)
		(fp_line
			(start 1.1938 -0.406654)
			(end 1.1938 0.4064)
			(stroke
				(width 0.1)
				(type default)
			)
			(layer "F.Fab")
		)
		(fp_line
			(start 0.8636 0.4572)
			(end -0.8636 0.4572)
			(stroke
				(width 0.1)
				(type default)
			)
			(layer "F.Fab")
		)
		(fp_line
			(start 0.8636 0.4064)
			(end 0.8636 0.4572)
			(stroke
				(width 0.1)
				(type default)
			)
			(layer "F.Fab")
		)
		(fp_line
			(start 0.8636 -0.406654)
			(end 1.1938 -0.406654)
			(stroke
				(width 0.1)
				(type default)
			)
			(layer "F.Fab")
		)
		(fp_line
			(start 0.8636 -0.4572)
			(end 0.8636 -0.406654)
			(stroke
				(width 0.1)
				(type default)
			)
			(layer "F.Fab")
		)
		(fp_line
			(start -0.8636 0.4572)
			(end -0.8636 0.4318)
			(stroke
				(width 0.1)
				(type default)
			)
			(layer "F.Fab")
		)
		(fp_line
			(start -0.8636 0.4318)
			(end -0.8636 0.4064)
			(stroke
				(width 0.1)
				(type default)
			)
			(layer "F.Fab")
		)
		(fp_line
			(start -0.8636 0.4064)
			(end -1.1938 0.4064)
			(stroke
				(width 0.1)
				(type default)
			)
			(layer "F.Fab")
		)
		(fp_line
			(start -0.8636 -0.406654)
			(end -0.8636 -0.4572)
			(stroke
				(width 0.1)
				(type default)
			)
			(layer "F.Fab")
		)
		(fp_line
			(start -0.8636 -0.4572)
			(end 0.8636 -0.4572)
			(stroke
				(width 0.1)
				(type default)
			)
			(layer "F.Fab")
		)
		(fp_line
			(start -1.1938 0.4064)
			(end -1.1938 -0.406654)
			(stroke
				(width 0.1)
				(type default)
			)
			(layer "F.Fab")
		)
		(fp_line
			(start -1.1938 -0.406654)
			(end -0.8636 -0.406654)
			(stroke
				(width 0.1)
				(type default)
			)
			(layer "F.Fab")
		)
		(pad "1" smd rect
			(at -0.7366 0 90)
			(size 0.7112 0.8128)
			(layers "F.Cu" "F.Mask" "F.Paste")
			(net "P52V_HS2_1272_S_N")
		)
		(pad "2" smd rect
			(at 0.7366 0 90)
			(size 0.7112 0.8128)
			(layers "F.Cu" "F.Mask" "F.Paste")
			(net "P52V_HS2_SENSE_N_R1")
		)
	)
	(footprint ""
		(layer "F.Cu")
		(at 436.245 -34.163)
		(property "Reference" "R23"
			(at 0 0 0)
			(layer "F.SilkS")
			(hide yes)
			(effects
				(font
					(size 1.27 1.27)
				)
			)
		)
		(property "Value" ""
			(at 0 0 0)
			(layer "F.Fab")
			(effects
				(font
					(size 1.27 1.27)
				)
			)
		)
		(duplicate_pad_numbers_are_jumpers no)
		(fp_line
			(start -0.7874 -0.4064)
			(end 0.7874 -0.4064)
			(stroke
				(width 0.1524)
				(type default)
			)
			(layer "F.SilkS")
		)
		(fp_line
			(start -0.7874 0.4064)
			(end -0.7874 -0.4064)
			(stroke
				(width 0.1524)
				(type default)
			)
			(layer "F.SilkS")
		)
		(fp_line
			(start 0.7874 -0.4064)
			(end 0.7874 0.4064)
			(stroke
				(width 0.1524)
				(type default)
			)
			(layer "F.SilkS")
		)
		(fp_line
			(start 0.7874 0.4064)
			(end -0.7874 0.4064)
			(stroke
				(width 0.1524)
				(type default)
			)
			(layer "F.SilkS")
		)
		(fp_line
			(start -0.67945 -0.305054)
			(end -0.12065 -0.305054)
			(stroke
				(width 0.1)
				(type default)
			)
			(layer "F.Fab")
		)
		(fp_line
			(start -0.67945 0.3048)
			(end -0.67945 -0.305054)
			(stroke
				(width 0.1)
				(type default)
			)
			(layer "F.Fab")
		)
		(fp_line
			(start -0.12065 -0.305054)
			(end -0.12065 -0.2794)
			(stroke
				(width 0.1)
				(type default)
			)
			(layer "F.Fab")
		)
		(fp_line
			(start -0.12065 -0.2794)
			(end 0.12065 -0.2794)
			(stroke
				(width 0.1)
				(type default)
			)
			(layer "F.Fab")
		)
		(fp_line
			(start -0.12065 0.2794)
			(end -0.12065 0.3048)
			(stroke
				(width 0.1)
				(type default)
			)
			(layer "F.Fab")
		)
		(fp_line
			(start -0.12065 0.3048)
			(end -0.67945 0.3048)
			(stroke
				(width 0.1)
				(type default)
			)
			(layer "F.Fab")
		)
		(fp_line
			(start 0.120396 0.2794)
			(end -0.12065 0.2794)
			(stroke
				(width 0.1)
				(type default)
			)
			(layer "F.Fab")
		)
		(fp_line
			(start 0.120396 0.3048)
			(end 0.120396 0.2794)
			(stroke
				(width 0.1)
				(type default)
			)
			(layer "F.Fab")
		)
		(fp_line
			(start 0.12065 -0.3048)
			(end 0.67945 -0.3048)
			(stroke
				(width 0.1)
				(type default)
			)
			(layer "F.Fab")
		)
		(fp_line
			(start 0.12065 -0.2794)
			(end 0.12065 -0.3048)
			(stroke
				(width 0.1)
				(type default)
			)
			(layer "F.Fab")
		)
		(fp_line
			(start 0.67945 -0.3048)
			(end 0.67945 0.3048)
			(stroke
				(width 0.1)
				(type default)
			)
			(layer "F.Fab")
		)
		(fp_line
			(start 0.67945 0.3048)
			(end 0.120396 0.3048)
			(stroke
				(width 0.1)
				(type default)
			)
			(layer "F.Fab")
		)
		(pad "1" smd circle
			(at -0.40005 0)
			(size 0 0)
			(layers "F.Cu" "F.Mask" "F.Paste")
			(net "P3V3_AUX")
		)
		(pad "2" smd circle
			(at 0.40005 0)
			(size 0 0)
			(layers "F.Cu" "F.Mask" "F.Paste")
			(net "PD_9543_FAN_A0")
		)
	)
	(footprint ""
		(layer "F.Cu")
		(at 434.7464 -37.211 -90)
		(property "Reference" "R11"
			(at 0 0 270)
			(layer "F.SilkS")
			(hide yes)
			(effects
				(font
					(size 1.27 1.27)
				)
			)
		)
		(property "Value" ""
			(at 0 0 270)
			(layer "F.Fab")
			(effects
				(font
					(size 1.27 1.27)
				)
			)
		)
		(duplicate_pad_numbers_are_jumpers no)
		(fp_line
			(start -0.7874 0.4064)
			(end -0.7874 -0.4064)
			(stroke
				(width 0.1524)
				(type default)
			)
			(layer "F.SilkS")
		)
		(fp_line
			(start 0.7874 0.4064)
			(end -0.7874 0.4064)
			(stroke
				(width 0.1524)
				(type default)
			)
			(layer "F.SilkS")
		)
		(fp_line
			(start -0.7874 -0.4064)
			(end 0.7874 -0.4064)
			(stroke
				(width 0.1524)
				(type default)
			)
			(layer "F.SilkS")
		)
		(fp_line
			(start 0.7874 -0.4064)
			(end 0.7874 0.4064)
			(stroke
				(width 0.1524)
				(type default)
			)
			(layer "F.SilkS")
		)
		(fp_line
			(start -0.67945 0.3048)
			(end -0.67945 -0.305054)
			(stroke
				(width 0.1)
				(type default)
			)
			(layer "F.Fab")
		)
		(fp_line
			(start -0.12065 0.3048)
			(end -0.67945 0.3048)
			(stroke
				(width 0.1)
				(type default)
			)
			(layer "F.Fab")
		)
		(fp_line
			(start 0.120396 0.3048)
			(end 0.120396 0.2794)
			(stroke
				(width 0.1)
				(type default)
			)
			(layer "F.Fab")
		)
		(fp_line
			(start 0.67945 0.3048)
			(end 0.120396 0.3048)
			(stroke
				(width 0.1)
				(type default)
			)
			(layer "F.Fab")
		)
		(fp_line
			(start -0.12065 0.2794)
			(end -0.12065 0.3048)
			(stroke
				(width 0.1)
				(type default)
			)
			(layer "F.Fab")
		)
		(fp_line
			(start 0.120396 0.2794)
			(end -0.12065 0.2794)
			(stroke
				(width 0.1)
				(type default)
			)
			(layer "F.Fab")
		)
		(fp_line
			(start -0.12065 -0.2794)
			(end 0.12065 -0.2794)
			(stroke
				(width 0.1)
				(type default)
			)
			(layer "F.Fab")
		)
		(fp_line
			(start 0.12065 -0.2794)
			(end 0.12065 -0.3048)
			(stroke
				(width 0.1)
				(type default)
			)
			(layer "F.Fab")
		)
		(fp_line
			(start 0.12065 -0.3048)
			(end 0.67945 -0.3048)
			(stroke
				(width 0.1)
				(type default)
			)
			(layer "F.Fab")
		)
		(fp_line
			(start 0.67945 -0.3048)
			(end 0.67945 0.3048)
			(stroke
				(width 0.1)
				(type default)
			)
			(layer "F.Fab")
		)
		(fp_line
			(start -0.67945 -0.305054)
			(end -0.12065 -0.305054)
			(stroke
				(width 0.1)
				(type default)
			)
			(layer "F.Fab")
		)
		(fp_line
			(start -0.12065 -0.305054)
			(end -0.12065 -0.2794)
			(stroke
				(width 0.1)
				(type default)
			)
			(layer "F.Fab")
		)
		(pad "1" smd circle
			(at -0.40005 0 270)
			(size 0 0)
			(layers "F.Cu" "F.Mask" "F.Paste")
			(net "SMB_P52V_PDB_SCL_R")
		)
		(pad "2" smd circle
			(at 0.40005 0 270)
			(size 0 0)
			(layers "F.Cu" "F.Mask" "F.Paste")
			(net "SMB_P52V_PDB_SCL")
		)
	)
	(footprint ""
		(layer "F.Cu")
		(at 456.999848 -24.500078 180)
		(property "Reference" "H16"
			(at 0.942848 10.525252 0)
			(unlocked yes)
			(layer "F.SilkS")
			(effects
				(font
					(size 0.7874 0.5842)
					(thickness 0.1524)
				)
				(justify left)
			)
		)
		(property "Value" ""
			(at 0 0 180)
			(layer "F.Fab")
			(effects
				(font
					(size 1.27 1.27)
				)
			)
		)
		(duplicate_pad_numbers_are_jumpers no)
		(pad "1" thru_hole oval
			(at 0 0 180)
			(size 9.017 14.0208)
			(drill 3.0226
				(offset 0 2.499868)
			)
			(layers "*.Cu" "*.Mask")
			(remove_unused_layers no)
			(net "GND")
			(clearance -1.500378)
			(padstack
				(mode front_inner_back)
				(layer "Inner"
					(shape circle)
					(size 0 0)
					(clearance 0)
				)
				(layer "B.Cu"
					(shape oval)
					(size 9.017 14.0208)
					(offset 0 2.499868)
					(clearance -1.500378)
				)
			)
		)
	)
	(footprint ""
		(layer "F.Cu")
		(at 397.637 -139.7)
		(property "Reference" "PC29"
			(at -7.5946 -5.30733 0)
			(unlocked yes)
			(layer "F.SilkS")
			(effects
				(font
					(size 0.7874 0.5842)
					(thickness 0.1524)
				)
				(justify left)
			)
		)
		(property "Value" ""
			(at 0 0 0)
			(layer "F.Fab")
			(effects
				(font
					(size 1.27 1.27)
				)
			)
		)
		(duplicate_pad_numbers_are_jumpers no)
		(fp_line
			(start -9.253728 3.750056)
			(end 9.249918 3.750056)
			(stroke
				(width 0.1524)
				(type default)
			)
			(layer "F.SilkS")
		)
		(fp_line
			(start 0 3.750056)
			(end -9.253728 3.750056)
			(stroke
				(width 0.1524)
				(type default)
			)
			(layer "F.SilkS")
		)
		(fp_circle
			(center 0 3.750056)
			(end 9.249918 3.750056)
			(stroke
				(width 0.1524)
				(type default)
			)
			(fill no)
			(layer "F.SilkS")
		)
		(fp_poly
			(pts
				(arc
					(start 9.249918 3.750056)
					(mid 0 12.999974)
					(end -9.249918 3.750056)
				)
			)
			(stroke
				(width 0)
				(type default)
			)
			(fill yes)
			(layer "F.SilkS")
		)
		(fp_circle
			(center 0 3.750056)
			(end 9.249918 3.750056)
			(stroke
				(width 0.1)
				(type default)
			)
			(fill no)
			(layer "F.Fab")
		)
		(pad "1" thru_hole rect
			(at 0 0)
			(size 1.778 1.778)
			(drill 1.27)
			(layers "*.Cu" "*.Mask")
			(remove_unused_layers no)
			(net "P52V_HS1")
			(clearance 0)
			(padstack
				(mode front_inner_back)
				(layer "Inner"
					(shape circle)
					(size 1.778 1.778)
					(clearance 0)
				)
				(layer "B.Cu"
					(shape rect)
					(size 1.778 1.778)
					(clearance 0)
				)
			)
		)
		(pad "2" thru_hole circle
			(at 0 7.500112)
			(size 1.778 1.778)
			(drill 1.27)
			(layers "*.Cu" "*.Mask")
			(remove_unused_layers no)
			(net "GND")
			(clearance 0)
		)
	)
	(footprint ""
		(layer "F.Cu")
		(at 378.079 -58.42)
		(property "Reference" "PC42"
			(at 5.6134 -4.67233 0)
			(unlocked yes)
			(layer "F.SilkS")
			(effects
				(font
					(size 0.7874 0.5842)
					(thickness 0.1524)
				)
				(justify left)
			)
		)
		(property "Value" ""
			(at 0 0 0)
			(layer "F.Fab")
			(effects
				(font
					(size 1.27 1.27)
				)
			)
		)
		(duplicate_pad_numbers_are_jumpers no)
		(fp_line
			(start -9.253728 3.750056)
			(end 9.249918 3.750056)
			(stroke
				(width 0.1524)
				(type default)
			)
			(layer "F.SilkS")
		)
		(fp_line
			(start 0 3.750056)
			(end -9.253728 3.750056)
			(stroke
				(width 0.1524)
				(type default)
			)
			(layer "F.SilkS")
		)
		(fp_circle
			(center 0 3.750056)
			(end 9.249918 3.750056)
			(stroke
				(width 0.1524)
				(type default)
			)
			(fill no)
			(layer "F.SilkS")
		)
		(fp_poly
			(pts
				(arc
					(start 9.249918 3.750056)
					(mid 0 12.999974)
					(end -9.249918 3.750056)
				)
			)
			(stroke
				(width 0)
				(type default)
			)
			(fill yes)
			(layer "F.SilkS")
		)
		(fp_circle
			(center 0 3.750056)
			(end 9.249918 3.750056)
			(stroke
				(width 0.1)
				(type default)
			)
			(fill no)
			(layer "F.Fab")
		)
		(pad "1" thru_hole rect
			(at 0 0)
			(size 1.778 1.778)
			(drill 1.27)
			(layers "*.Cu" "*.Mask")
			(remove_unused_layers no)
			(net "P52V_HS1")
			(clearance 0)
			(padstack
				(mode front_inner_back)
				(layer "Inner"
					(shape circle)
					(size 1.778 1.778)
					(clearance 0)
				)
				(layer "B.Cu"
					(shape rect)
					(size 1.778 1.778)
					(clearance 0)
				)
			)
		)
		(pad "2" thru_hole circle
			(at 0 7.500112)
			(size 1.778 1.778)
			(drill 1.27)
			(layers "*.Cu" "*.Mask")
			(remove_unused_layers no)
			(net "GND")
			(clearance 0)
		)
	)
	(footprint ""
		(layer "F.Cu")
		(at 52.832 -29.718 90)
		(property "Reference" "PR105"
			(at 0 0 90)
			(layer "F.SilkS")
			(hide yes)
			(effects
				(font
					(size 1.27 1.27)
				)
			)
		)
		(property "Value" ""
			(at 0 0 90)
			(layer "F.Fab")
			(effects
				(font
					(size 1.27 1.27)
				)
			)
		)
		(duplicate_pad_numbers_are_jumpers no)
		(fp_line
			(start 0.7874 -0.4064)
			(end 0.7874 0.4064)
			(stroke
				(width 0.1524)
				(type default)
			)
			(layer "F.SilkS")
		)
		(fp_line
			(start -0.7874 -0.4064)
			(end 0.7874 -0.4064)
			(stroke
				(width 0.1524)
				(type default)
			)
			(layer "F.SilkS")
		)
		(fp_line
			(start 0.7874 0.4064)
			(end -0.7874 0.4064)
			(stroke
				(width 0.1524)
				(type default)
			)
			(layer "F.SilkS")
		)
		(fp_line
			(start -0.7874 0.4064)
			(end -0.7874 -0.4064)
			(stroke
				(width 0.1524)
				(type default)
			)
			(layer "F.SilkS")
		)
		(fp_line
			(start -0.12065 -0.305054)
			(end -0.12065 -0.2794)
			(stroke
				(width 0.1)
				(type default)
			)
			(layer "F.Fab")
		)
		(fp_line
			(start -0.67945 -0.305054)
			(end -0.12065 -0.305054)
			(stroke
				(width 0.1)
				(type default)
			)
			(layer "F.Fab")
		)
		(fp_line
			(start 0.67945 -0.3048)
			(end 0.67945 0.3048)
			(stroke
				(width 0.1)
				(type default)
			)
			(layer "F.Fab")
		)
		(fp_line
			(start 0.12065 -0.3048)
			(end 0.67945 -0.3048)
			(stroke
				(width 0.1)
				(type default)
			)
			(layer "F.Fab")
		)
		(fp_line
			(start 0.12065 -0.2794)
			(end 0.12065 -0.3048)
			(stroke
				(width 0.1)
				(type default)
			)
			(layer "F.Fab")
		)
		(fp_line
			(start -0.12065 -0.2794)
			(end 0.12065 -0.2794)
			(stroke
				(width 0.1)
				(type default)
			)
			(layer "F.Fab")
		)
		(fp_line
			(start 0.120396 0.2794)
			(end -0.12065 0.2794)
			(stroke
				(width 0.1)
				(type default)
			)
			(layer "F.Fab")
		)
		(fp_line
			(start -0.12065 0.2794)
			(end -0.12065 0.3048)
			(stroke
				(width 0.1)
				(type default)
			)
			(layer "F.Fab")
		)
		(fp_line
			(start 0.67945 0.3048)
			(end 0.120396 0.3048)
			(stroke
				(width 0.1)
				(type default)
			)
			(layer "F.Fab")
		)
		(fp_line
			(start 0.120396 0.3048)
			(end 0.120396 0.2794)
			(stroke
				(width 0.1)
				(type default)
			)
			(layer "F.Fab")
		)
		(fp_line
			(start -0.12065 0.3048)
			(end -0.67945 0.3048)
			(stroke
				(width 0.1)
				(type default)
			)
			(layer "F.Fab")
		)
		(fp_line
			(start -0.67945 0.3048)
			(end -0.67945 -0.305054)
			(stroke
				(width 0.1)
				(type default)
			)
			(layer "F.Fab")
		)
		(pad "1" smd circle
			(at -0.40005 0 90)
			(size 0 0)
			(layers "F.Cu" "F.Mask" "F.Paste")
			(net "P52V_HS2_EN_DISCHARGE_VBE")
		)
		(pad "2" smd circle
			(at 0.40005 0 90)
			(size 0 0)
			(layers "F.Cu" "F.Mask" "F.Paste")
			(net "P52V_HS2_EN_DISCHARGE_VBE_R")
		)
	)
	(footprint ""
		(layer "F.Cu")
		(at 406.146 -30.988)
		(property "Reference" "R46"
			(at 0 0 0)
			(layer "F.SilkS")
			(hide yes)
			(effects
				(font
					(size 1.27 1.27)
				)
			)
		)
		(property "Value" ""
			(at 0 0 0)
			(layer "F.Fab")
			(effects
				(font
					(size 1.27 1.27)
				)
			)
		)
		(duplicate_pad_numbers_are_jumpers no)
		(fp_line
			(start -2.234946 -0.9271)
			(end 2.234946 -0.9271)
			(stroke
				(width 0.1524)
				(type default)
			)
			(layer "F.SilkS")
		)
		(fp_line
			(start -2.234946 0.9271)
			(end -2.234946 -0.9271)
			(stroke
				(width 0.1524)
				(type default)
			)
			(layer "F.SilkS")
		)
		(fp_line
			(start 2.234946 -0.9271)
			(end 2.234946 0.9271)
			(stroke
				(width 0.1524)
				(type default)
			)
			(layer "F.SilkS")
		)
		(fp_line
			(start 2.234946 0.9271)
			(end -2.234946 0.9271)
			(stroke
				(width 0.1524)
				(type default)
			)
			(layer "F.SilkS")
		)
		(fp_line
			(start -1.575054 -0.824992)
			(end -1.575054 0.824992)
			(stroke
				(width 0.1)
				(type default)
			)
			(layer "F.Fab")
		)
		(fp_line
			(start -1.575054 0.824992)
			(end 1.575054 0.824992)
			(stroke
				(width 0.1)
				(type default)
			)
			(layer "F.Fab")
		)
		(fp_line
			(start 1.575054 -0.824992)
			(end -1.575054 -0.824992)
			(stroke
				(width 0.1)
				(type default)
			)
			(layer "F.Fab")
		)
		(fp_line
			(start 1.575054 0.824992)
			(end 1.575054 -0.824992)
			(stroke
				(width 0.1)
				(type default)
			)
			(layer "F.Fab")
		)
		(pad "1" smd rect
			(at -1.599946 0)
			(size 1.016 1.6002)
			(layers "F.Cu" "F.Mask" "F.Paste")
			(net "LED_D1_R4")
		)
		(pad "2" smd rect
			(at 1.599946 0)
			(size 1.016 1.6002)
			(layers "F.Cu" "F.Mask" "F.Paste")
			(net "LED_D1_R5")
		)
	)
	(footprint ""
		(layer "F.Cu")
		(at 431.4444 -24.6126 90)
		(property "Reference" "U9"
			(at 0.1524 -3.27533 90)
			(unlocked yes)
			(layer "F.SilkS")
			(effects
				(font
					(size 0.7874 0.5842)
					(thickness 0.1524)
				)
				(justify left)
			)
		)
		(property "Value" ""
			(at 0 0 90)
			(layer "F.Fab")
			(effects
				(font
					(size 1.27 1.27)
				)
			)
		)
		(duplicate_pad_numbers_are_jumpers no)
		(fp_line
			(start 1.4224 -2.5146)
			(end 0.4572 -2.5146)
			(stroke
				(width 0.1524)
				(type default)
			)
			(layer "F.SilkS")
		)
		(fp_line
			(start 0.4572 -2.5146)
			(end 0 -2.0574)
			(stroke
				(width 0.1524)
				(type default)
			)
			(layer "F.SilkS")
		)
		(fp_line
			(start -0.4572 -2.5146)
			(end -1.4224 -2.5146)
			(stroke
				(width 0.1524)
				(type default)
			)
			(layer "F.SilkS")
		)
		(fp_line
			(start -1.4224 -2.5146)
			(end -1.4224 2.5146)
			(stroke
				(width 0.1524)
				(type default)
			)
			(layer "F.SilkS")
		)
		(fp_line
			(start 0 -2.0574)
			(end -0.4572 -2.5146)
			(stroke
				(width 0.1524)
				(type default)
			)
			(layer "F.SilkS")
		)
		(fp_line
			(start 1.4224 2.5146)
			(end 1.4224 -2.5146)
			(stroke
				(width 0.1524)
				(type default)
			)
			(layer "F.SilkS")
		)
		(fp_line
			(start -1.4224 2.5146)
			(end 1.4224 2.5146)
			(stroke
				(width 0.1524)
				(type default)
			)
			(layer "F.SilkS")
		)
		(fp_poly
			(pts
				(xy -2.804414 -2.3876) (xy -3.185414 -3.1496) (xy -2.423414 -3.1496)
			)
			(stroke
				(width 0)
				(type default)
			)
			(fill yes)
			(layer "F.SilkS")
		)
		(fp_line
			(start 2.0066 -2.5146)
			(end -2.0066 -2.5146)
			(stroke
				(width 0.1)
				(type default)
			)
			(layer "F.Fab")
		)
		(fp_line
			(start -2.0066 -2.5146)
			(end -2.0066 -2.114804)
			(stroke
				(width 0.1)
				(type default)
			)
			(layer "F.Fab")
		)
		(fp_line
			(start -2.0066 -2.114804)
			(end -2.648712 -2.114804)
			(stroke
				(width 0.1)
				(type default)
			)
			(layer "F.Fab")
		)
		(fp_line
			(start -2.648712 -2.114804)
			(end -2.648712 2.112264)
			(stroke
				(width 0.1)
				(type default)
			)
			(layer "F.Fab")
		)
		(fp_line
			(start 2.642616 -2.112264)
			(end 2.0066 -2.112264)
			(stroke
				(width 0.1)
				(type default)
			)
			(layer "F.Fab")
		)
		(fp_line
			(start 2.0066 -2.112264)
			(end 2.0066 -2.5146)
			(stroke
				(width 0.1)
				(type default)
			)
			(layer "F.Fab")
		)
		(fp_line
			(start 2.642616 2.112264)
			(end 2.642616 -2.112264)
			(stroke
				(width 0.1)
				(type default)
			)
			(layer "F.Fab")
		)
		(fp_line
			(start 2.0066 2.112264)
			(end 2.642616 2.112264)
			(stroke
				(width 0.1)
				(type default)
			)
			(layer "F.Fab")
		)
		(fp_line
			(start -2.0066 2.112264)
			(end -2.0066 2.5146)
			(stroke
				(width 0.1)
				(type default)
			)
			(layer "F.Fab")
		)
		(fp_line
			(start -2.648712 2.112264)
			(end -2.0066 2.112264)
			(stroke
				(width 0.1)
				(type default)
			)
			(layer "F.Fab")
		)
		(fp_line
			(start 2.0066 2.5146)
			(end 2.0066 2.112264)
			(stroke
				(width 0.1)
				(type default)
			)
			(layer "F.Fab")
		)
		(fp_line
			(start -2.0066 2.5146)
			(end 2.0066 2.5146)
			(stroke
				(width 0.1)
				(type default)
			)
			(layer "F.Fab")
		)
		(fp_poly
			(pts
				(xy -3.6322 -1.869186) (xy -4.3942 -1.488186) (xy -4.3942 -2.250186)
			)
			(stroke
				(width 0)
				(type default)
			)
			(fill yes)
			(layer "F.Fab")
		)
		(pad "1" smd rect
			(at -2.6416 -1.905)
			(size 0.5588 1.7272)
			(layers "F.Cu" "F.Mask" "F.Paste")
			(net "FRU_ADDR0")
		)
		(pad "2" smd rect
			(at -2.6416 -0.635)
			(size 0.5588 1.7272)
			(layers "F.Cu" "F.Mask" "F.Paste")
			(net "FRU_ADDR1")
		)
		(pad "3" smd rect
			(at -2.6416 0.635)
			(size 0.5588 1.7272)
			(layers "F.Cu" "F.Mask" "F.Paste")
			(net "FRU_ADDR2")
		)
		(pad "4" smd rect
			(at -2.6416 1.905)
			(size 0.5588 1.7272)
			(layers "F.Cu" "F.Mask" "F.Paste")
			(net "GND")
		)
		(pad "5" smd rect
			(at 2.6416 1.905)
			(size 0.5588 1.7272)
			(layers "F.Cu" "F.Mask" "F.Paste")
			(net "SMB_FRU_DAT")
		)
		(pad "6" smd rect
			(at 2.6416 0.635)
			(size 0.5588 1.7272)
			(layers "F.Cu" "F.Mask" "F.Paste")
			(net "SMB_FRU_CLK")
		)
		(pad "7" smd rect
			(at 2.6416 -0.635)
			(size 0.5588 1.7272)
			(layers "F.Cu" "F.Mask" "F.Paste")
			(net "FRU_WP_N")
		)
		(pad "8" smd rect
			(at 2.6416 -1.905)
			(size 0.5588 1.7272)
			(layers "F.Cu" "F.Mask" "F.Paste")
			(net "P3V3_AUX")
		)
	)
	(footprint ""
		(layer "F.Cu")
		(at 112.988852 -55.372 -90)
		(property "Reference" "PR6972"
			(at 0 0 270)
			(layer "F.SilkS")
			(hide yes)
			(effects
				(font
					(size 1.27 1.27)
				)
			)
		)
		(property "Value" ""
			(at 0 0 270)
			(layer "F.Fab")
			(effects
				(font
					(size 1.27 1.27)
				)
			)
		)
		(duplicate_pad_numbers_are_jumpers no)
		(fp_line
			(start -1.2954 0.5842)
			(end -1.2954 -0.5842)
			(stroke
				(width 0.1524)
				(type default)
			)
			(layer "F.SilkS")
		)
		(fp_line
			(start 1.2954 0.5842)
			(end -1.2954 0.5842)
			(stroke
				(width 0.1524)
				(type default)
			)
			(layer "F.SilkS")
		)
		(fp_line
			(start -1.2954 -0.5842)
			(end 1.2954 -0.5842)
			(stroke
				(width 0.1524)
				(type default)
			)
			(layer "F.SilkS")
		)
		(fp_line
			(start 1.2954 -0.5842)
			(end 1.2954 0.5842)
			(stroke
				(width 0.1524)
				(type default)
			)
			(layer "F.SilkS")
		)
		(fp_line
			(start -0.8636 0.4572)
			(end -0.8636 0.4318)
			(stroke
				(width 0.1)
				(type default)
			)
			(layer "F.Fab")
		)
		(fp_line
			(start 0.8636 0.4572)
			(end -0.8636 0.4572)
			(stroke
				(width 0.1)
				(type default)
			)
			(layer "F.Fab")
		)
		(fp_line
			(start -0.8636 0.4318)
			(end -0.8636 0.4064)
			(stroke
				(width 0.1)
				(type default)
			)
			(layer "F.Fab")
		)
		(fp_line
			(start -1.1938 0.4064)
			(end -1.1938 -0.406654)
			(stroke
				(width 0.1)
				(type default)
			)
			(layer "F.Fab")
		)
		(fp_line
			(start -0.8636 0.4064)
			(end -1.1938 0.4064)
			(stroke
				(width 0.1)
				(type default)
			)
			(layer "F.Fab")
		)
		(fp_line
			(start 0.8636 0.4064)
			(end 0.8636 0.4572)
			(stroke
				(width 0.1)
				(type default)
			)
			(layer "F.Fab")
		)
		(fp_line
			(start 1.1938 0.4064)
			(end 0.8636 0.4064)
			(stroke
				(width 0.1)
				(type default)
			)
			(layer "F.Fab")
		)
		(fp_line
			(start -1.1938 -0.406654)
			(end -0.8636 -0.406654)
			(stroke
				(width 0.1)
				(type default)
			)
			(layer "F.Fab")
		)
		(fp_line
			(start -0.8636 -0.406654)
			(end -0.8636 -0.4572)
			(stroke
				(width 0.1)
				(type default)
			)
			(layer "F.Fab")
		)
		(fp_line
			(start 0.8636 -0.406654)
			(end 1.1938 -0.406654)
			(stroke
				(width 0.1)
				(type default)
			)
			(layer "F.Fab")
		)
		(fp_line
			(start 1.1938 -0.406654)
			(end 1.1938 0.4064)
			(stroke
				(width 0.1)
				(type default)
			)
			(layer "F.Fab")
		)
		(fp_line
			(start -0.8636 -0.4572)
			(end 0.8636 -0.4572)
			(stroke
				(width 0.1)
				(type default)
			)
			(layer "F.Fab")
		)
		(fp_line
			(start 0.8636 -0.4572)
			(end 0.8636 -0.406654)
			(stroke
				(width 0.1)
				(type default)
			)
			(layer "F.Fab")
		)
		(pad "1" smd rect
			(at -0.7366 0 180)
			(size 0.7112 0.8128)
			(layers "F.Cu" "F.Mask" "F.Paste")
			(net "P52V_HS2_GATE1_R")
		)
		(pad "2" smd rect
			(at 0.7366 0 180)
			(size 0.7112 0.8128)
			(layers "F.Cu" "F.Mask" "F.Paste")
			(net "P52V_HS2_GATE3")
		)
	)
	(footprint ""
		(layer "F.Cu")
		(at 317.2079 -85.598)
		(property "Reference" "PR6966"
			(at 0 0 0)
			(layer "F.SilkS")
			(hide yes)
			(effects
				(font
					(size 1.27 1.27)
				)
			)
		)
		(property "Value" ""
			(at 0 0 0)
			(layer "F.Fab")
			(effects
				(font
					(size 1.27 1.27)
				)
			)
		)
		(duplicate_pad_numbers_are_jumpers no)
		(fp_line
			(start -0.7874 -0.4064)
			(end 0.7874 -0.4064)
			(stroke
				(width 0.1524)
				(type default)
			)
			(layer "F.SilkS")
		)
		(fp_line
			(start -0.7874 0.4064)
			(end -0.7874 -0.4064)
			(stroke
				(width 0.1524)
				(type default)
			)
			(layer "F.SilkS")
		)
		(fp_line
			(start 0.7874 -0.4064)
			(end 0.7874 0.4064)
			(stroke
				(width 0.1524)
				(type default)
			)
			(layer "F.SilkS")
		)
		(fp_line
			(start 0.7874 0.4064)
			(end -0.7874 0.4064)
			(stroke
				(width 0.1524)
				(type default)
			)
			(layer "F.SilkS")
		)
		(fp_line
			(start -0.67945 -0.305054)
			(end -0.12065 -0.305054)
			(stroke
				(width 0.1)
				(type default)
			)
			(layer "F.Fab")
		)
		(fp_line
			(start -0.67945 0.3048)
			(end -0.67945 -0.305054)
			(stroke
				(width 0.1)
				(type default)
			)
			(layer "F.Fab")
		)
		(fp_line
			(start -0.12065 -0.305054)
			(end -0.12065 -0.2794)
			(stroke
				(width 0.1)
				(type default)
			)
			(layer "F.Fab")
		)
		(fp_line
			(start -0.12065 -0.2794)
			(end 0.12065 -0.2794)
			(stroke
				(width 0.1)
				(type default)
			)
			(layer "F.Fab")
		)
		(fp_line
			(start -0.12065 0.2794)
			(end -0.12065 0.3048)
			(stroke
				(width 0.1)
				(type default)
			)
			(layer "F.Fab")
		)
		(fp_line
			(start -0.12065 0.3048)
			(end -0.67945 0.3048)
			(stroke
				(width 0.1)
				(type default)
			)
			(layer "F.Fab")
		)
		(fp_line
			(start 0.120396 0.2794)
			(end -0.12065 0.2794)
			(stroke
				(width 0.1)
				(type default)
			)
			(layer "F.Fab")
		)
		(fp_line
			(start 0.120396 0.3048)
			(end 0.120396 0.2794)
			(stroke
				(width 0.1)
				(type default)
			)
			(layer "F.Fab")
		)
		(fp_line
			(start 0.12065 -0.3048)
			(end 0.67945 -0.3048)
			(stroke
				(width 0.1)
				(type default)
			)
			(layer "F.Fab")
		)
		(fp_line
			(start 0.12065 -0.2794)
			(end 0.12065 -0.3048)
			(stroke
				(width 0.1)
				(type default)
			)
			(layer "F.Fab")
		)
		(fp_line
			(start 0.67945 -0.3048)
			(end 0.67945 0.3048)
			(stroke
				(width 0.1)
				(type default)
			)
			(layer "F.Fab")
		)
		(fp_line
			(start 0.67945 0.3048)
			(end 0.120396 0.3048)
			(stroke
				(width 0.1)
				(type default)
			)
			(layer "F.Fab")
		)
		(pad "1" smd rect
			(at -0.40005 0 180)
			(size 0.4572 0.508)
			(layers "F.Cu" "F.Mask" "F.Paste")
			(net "P52V_HS1_TEMP")
		)
		(pad "2" smd rect
			(at 0.40005 0 180)
			(size 0.4572 0.508)
			(layers "F.Cu" "F.Mask" "F.Paste")
			(net "P52V_HS1_TEMP_R")
		)
	)
	(footprint ""
		(layer "F.Cu")
		(at 95.25 -45.9486)
		(property "Reference" "ME2"
			(at 0 0 0)
			(layer "F.SilkS")
			(hide yes)
			(effects
				(font
					(size 1.27 1.27)
				)
			)
		)
		(property "Value" ""
			(at 0 0 0)
			(layer "F.Fab")
			(effects
				(font
					(size 1.27 1.27)
				)
			)
		)
		(duplicate_pad_numbers_are_jumpers no)
		(fp_poly
			(pts
				(xy 0 -0.5842) (xy 3.3401 -0.5842) (xy 3.3401 0) (xy 0 0)
			)
			(stroke
				(width 0)
				(type default)
			)
			(fill yes)
			(layer "F.SilkS")
		)
		(fp_poly
			(pts
				(xy 1.32715 -3.4417) (xy 2.01295 -3.4417) (xy 2.01295 -3.2512) (xy 1.32715 -3.2512)
			)
			(stroke
				(width 0)
				(type default)
			)
			(fill yes)
			(layer "F.SilkS")
		)
		(fp_poly
			(pts
				(xy -0.070612 -0.681228) (xy -0.197612 -0.820928) (xy 0.852678 -1.91262) (xy 0.728472 -3.29184)
				(xy -0.248412 -4.300728) (xy -0.184912 -4.478528) (xy -0.007112 -4.503928) (xy 0.684022 -3.785616)
				(xy 0.65659 -4.0894) (xy 0.97155 -4.3434) (xy 1.22555 -4.3561) (xy 1.46685 -4.4704) (xy 2.01295 -4.4704)
				(xy 2.15265 -4.4069) (xy 2.44475 -4.191) (xy 2.49555 -4.191) (xy 2.59715 -4.2926) (xy 2.80035 -4.2672)
				(xy 2.88925 -4.1656) (xy 2.88925 -4.029456) (xy 3.345688 -4.503928) (xy 3.523488 -4.478528) (xy 3.586988 -4.300728)
				(xy 2.88925 -3.58013) (xy 2.88925 -3.3147) (xy 2.82575 -3.2385) (xy 2.67335 -3.2385) (xy 2.521966 -1.875282)
				(xy 2.545842 -1.85039)
				(arc
					(start 2.55905 -1.8415)
					(mid 2.648099 -1.766068)
					(end 2.717292 -1.672082)
				)
				(xy 3.536188 -0.820928) (xy 3.409188 -0.681228) (xy 3.244088 -0.693928)
				(arc
					(start 2.737612 -1.216914)
					(mid 2.31728 -0.925553)
					(end 1.86055 -1.1557)
				)
				(xy 0.92075 -1.1557) (xy 0.888492 -1.51384) (xy 0.094488 -0.693928)
			)
			(stroke
				(width 0)
				(type default)
			)
			(fill yes)
			(layer "F.SilkS")
		)
	)
	(footprint ""
		(layer "F.Cu")
		(at 176.1744 -63.881)
		(property "Reference" "PC578"
			(at 0 0 0)
			(layer "F.SilkS")
			(hide yes)
			(effects
				(font
					(size 1.27 1.27)
				)
			)
		)
		(property "Value" ""
			(at 0 0 0)
			(layer "F.Fab")
			(effects
				(font
					(size 1.27 1.27)
				)
			)
		)
		(duplicate_pad_numbers_are_jumpers no)
		(fp_line
			(start -0.7874 -0.4064)
			(end 0.7874 -0.4064)
			(stroke
				(width 0.1524)
				(type default)
			)
			(layer "F.SilkS")
		)
		(fp_line
			(start -0.7874 0.4064)
			(end -0.7874 -0.4064)
			(stroke
				(width 0.1524)
				(type default)
			)
			(layer "F.SilkS")
		)
		(fp_line
			(start 0.7874 -0.4064)
			(end 0.7874 0.4064)
			(stroke
				(width 0.1524)
				(type default)
			)
			(layer "F.SilkS")
		)
		(fp_line
			(start 0.7874 0.4064)
			(end -0.7874 0.4064)
			(stroke
				(width 0.1524)
				(type default)
			)
			(layer "F.SilkS")
		)
		(fp_line
			(start -0.67945 -0.305054)
			(end -0.12065 -0.305054)
			(stroke
				(width 0.1)
				(type default)
			)
			(layer "F.Fab")
		)
		(fp_line
			(start -0.67945 0.3048)
			(end -0.67945 -0.305054)
			(stroke
				(width 0.1)
				(type default)
			)
			(layer "F.Fab")
		)
		(fp_line
			(start -0.12065 -0.305054)
			(end -0.12065 -0.2794)
			(stroke
				(width 0.1)
				(type default)
			)
			(layer "F.Fab")
		)
		(fp_line
			(start -0.12065 -0.2794)
			(end 0.12065 -0.2794)
			(stroke
				(width 0.1)
				(type default)
			)
			(layer "F.Fab")
		)
		(fp_line
			(start -0.12065 0.2794)
			(end -0.12065 0.3048)
			(stroke
				(width 0.1)
				(type default)
			)
			(layer "F.Fab")
		)
		(fp_line
			(start -0.12065 0.3048)
			(end -0.67945 0.3048)
			(stroke
				(width 0.1)
				(type default)
			)
			(layer "F.Fab")
		)
		(fp_line
			(start 0.120396 0.2794)
			(end -0.12065 0.2794)
			(stroke
				(width 0.1)
				(type default)
			)
			(layer "F.Fab")
		)
		(fp_line
			(start 0.120396 0.3048)
			(end 0.120396 0.2794)
			(stroke
				(width 0.1)
				(type default)
			)
			(layer "F.Fab")
		)
		(fp_line
			(start 0.12065 -0.3048)
			(end 0.67945 -0.3048)
			(stroke
				(width 0.1)
				(type default)
			)
			(layer "F.Fab")
		)
		(fp_line
			(start 0.12065 -0.2794)
			(end 0.12065 -0.3048)
			(stroke
				(width 0.1)
				(type default)
			)
			(layer "F.Fab")
		)
		(fp_line
			(start 0.67945 -0.3048)
			(end 0.67945 0.3048)
			(stroke
				(width 0.1)
				(type default)
			)
			(layer "F.Fab")
		)
		(fp_line
			(start 0.67945 0.3048)
			(end 0.120396 0.3048)
			(stroke
				(width 0.1)
				(type default)
			)
			(layer "F.Fab")
		)
		(pad "1" smd circle
			(at -0.40005 0)
			(size 0 0)
			(layers "F.Cu" "F.Mask" "F.Paste")
			(net "P52V_HS2_UVLO_EN")
		)
		(pad "2" smd circle
			(at 0.40005 0)
			(size 0 0)
			(layers "F.Cu" "F.Mask" "F.Paste")
			(net "GND1_FIELD_SIGNAL")
		)
	)
	(footprint ""
		(layer "F.Cu")
		(at 125.675136 -82.677 180)
		(property "Reference" "PQ44"
			(at 2.104136 2.64033 0)
			(unlocked yes)
			(layer "F.SilkS")
			(effects
				(font
					(size 0.7874 0.5842)
					(thickness 0.1524)
				)
				(justify left)
			)
		)
		(property "Value" ""
			(at 0 0 180)
			(layer "F.Fab")
			(effects
				(font
					(size 1.27 1.27)
				)
			)
		)
		(duplicate_pad_numbers_are_jumpers no)
		(fp_line
			(start 1.905 1.651)
			(end -1.905 1.651)
			(stroke
				(width 0.1524)
				(type default)
			)
			(layer "F.SilkS")
		)
		(fp_line
			(start 1.905 -1.651)
			(end 1.905 1.651)
			(stroke
				(width 0.1524)
				(type default)
			)
			(layer "F.SilkS")
		)
		(fp_line
			(start -1.905 1.651)
			(end -1.905 -1.651)
			(stroke
				(width 0.1524)
				(type default)
			)
			(layer "F.SilkS")
		)
		(fp_line
			(start -1.905 -1.651)
			(end 1.905 -1.651)
			(stroke
				(width 0.1524)
				(type default)
			)
			(layer "F.SilkS")
		)
		(fp_line
			(start 1.249934 0.219964)
			(end 0.6985 0.219964)
			(stroke
				(width 0.1)
				(type default)
			)
			(layer "F.Fab")
		)
		(fp_line
			(start 1.249934 -0.219964)
			(end 1.249934 0.219964)
			(stroke
				(width 0.1)
				(type default)
			)
			(layer "F.Fab")
		)
		(fp_line
			(start 0.6985 1.524)
			(end -0.649986 1.524)
			(stroke
				(width 0.1)
				(type default)
			)
			(layer "F.Fab")
		)
		(fp_line
			(start 0.6985 0.219964)
			(end 0.6985 1.524)
			(stroke
				(width 0.1)
				(type default)
			)
			(layer "F.Fab")
		)
		(fp_line
			(start 0.6985 -0.219964)
			(end 1.249934 -0.219964)
			(stroke
				(width 0.1)
				(type default)
			)
			(layer "F.Fab")
		)
		(fp_line
			(start 0.6985 -1.524)
			(end 0.6985 -0.219964)
			(stroke
				(width 0.1)
				(type default)
			)
			(layer "F.Fab")
		)
		(fp_line
			(start -0.649986 1.524)
			(end -0.649986 1.169924)
			(stroke
				(width 0.1)
				(type default)
			)
			(layer "F.Fab")
		)
		(fp_line
			(start -0.649986 1.169924)
			(end -1.249934 1.169924)
			(stroke
				(width 0.1)
				(type default)
			)
			(layer "F.Fab")
		)
		(fp_line
			(start -0.649986 -1.169924)
			(end -0.649986 -1.524)
			(stroke
				(width 0.1)
				(type default)
			)
			(layer "F.Fab")
		)
		(fp_line
			(start -0.649986 -1.524)
			(end 0.6985 -1.524)
			(stroke
				(width 0.1)
				(type default)
			)
			(layer "F.Fab")
		)
		(fp_line
			(start -0.6985 0.729996)
			(end -0.6985 -0.729996)
			(stroke
				(width 0.1)
				(type default)
			)
			(layer "F.Fab")
		)
		(fp_line
			(start -0.6985 -0.729996)
			(end -1.249934 -0.729996)
			(stroke
				(width 0.1)
				(type default)
			)
			(layer "F.Fab")
		)
		(fp_line
			(start -1.249934 1.169924)
			(end -1.249934 0.729996)
			(stroke
				(width 0.1)
				(type default)
			)
			(layer "F.Fab")
		)
		(fp_line
			(start -1.249934 0.729996)
			(end -0.6985 0.729996)
			(stroke
				(width 0.1)
				(type default)
			)
			(layer "F.Fab")
		)
		(fp_line
			(start -1.249934 -0.729996)
			(end -1.249934 -1.169924)
			(stroke
				(width 0.1)
				(type default)
			)
			(layer "F.Fab")
		)
		(fp_line
			(start -1.249934 -1.169924)
			(end -0.649986 -1.169924)
			(stroke
				(width 0.1)
				(type default)
			)
			(layer "F.Fab")
		)
		(pad "B" smd rect
			(at -1.1176 -1.016 90)
			(size 1.016 1.27)
			(layers "F.Cu" "F.Mask" "F.Paste")
			(net "P52V_HS2_TEMP_R")
		)
		(pad "C" smd rect
			(at 1.1176 0 90)
			(size 1.016 1.27)
			(layers "F.Cu" "F.Mask" "F.Paste")
			(net "P52V_HS2_TEMP_R")
		)
		(pad "E" smd rect
			(at -1.1176 1.016 90)
			(size 1.016 1.27)
			(layers "F.Cu" "F.Mask" "F.Paste")
			(net "P52V_HS2_TEMPN_R")
		)
	)
	(footprint ""
		(layer "F.Cu")
		(at 449.326 -27.813)
		(property "Reference" "R331"
			(at 0 0 0)
			(layer "F.SilkS")
			(hide yes)
			(effects
				(font
					(size 1.27 1.27)
				)
			)
		)
		(property "Value" ""
			(at 0 0 0)
			(layer "F.Fab")
			(effects
				(font
					(size 1.27 1.27)
				)
			)
		)
		(duplicate_pad_numbers_are_jumpers no)
		(fp_line
			(start -0.7874 -0.4064)
			(end 0.7874 -0.4064)
			(stroke
				(width 0.1524)
				(type default)
			)
			(layer "F.SilkS")
		)
		(fp_line
			(start -0.7874 0.4064)
			(end -0.7874 -0.4064)
			(stroke
				(width 0.1524)
				(type default)
			)
			(layer "F.SilkS")
		)
		(fp_line
			(start 0.7874 -0.4064)
			(end 0.7874 0.4064)
			(stroke
				(width 0.1524)
				(type default)
			)
			(layer "F.SilkS")
		)
		(fp_line
			(start 0.7874 0.4064)
			(end -0.7874 0.4064)
			(stroke
				(width 0.1524)
				(type default)
			)
			(layer "F.SilkS")
		)
		(fp_line
			(start -0.67945 -0.305054)
			(end -0.12065 -0.305054)
			(stroke
				(width 0.1)
				(type default)
			)
			(layer "F.Fab")
		)
		(fp_line
			(start -0.67945 0.3048)
			(end -0.67945 -0.305054)
			(stroke
				(width 0.1)
				(type default)
			)
			(layer "F.Fab")
		)
		(fp_line
			(start -0.12065 -0.305054)
			(end -0.12065 -0.2794)
			(stroke
				(width 0.1)
				(type default)
			)
			(layer "F.Fab")
		)
		(fp_line
			(start -0.12065 -0.2794)
			(end 0.12065 -0.2794)
			(stroke
				(width 0.1)
				(type default)
			)
			(layer "F.Fab")
		)
		(fp_line
			(start -0.12065 0.2794)
			(end -0.12065 0.3048)
			(stroke
				(width 0.1)
				(type default)
			)
			(layer "F.Fab")
		)
		(fp_line
			(start -0.12065 0.3048)
			(end -0.67945 0.3048)
			(stroke
				(width 0.1)
				(type default)
			)
			(layer "F.Fab")
		)
		(fp_line
			(start 0.120396 0.2794)
			(end -0.12065 0.2794)
			(stroke
				(width 0.1)
				(type default)
			)
			(layer "F.Fab")
		)
		(fp_line
			(start 0.120396 0.3048)
			(end 0.120396 0.2794)
			(stroke
				(width 0.1)
				(type default)
			)
			(layer "F.Fab")
		)
		(fp_line
			(start 0.12065 -0.3048)
			(end 0.67945 -0.3048)
			(stroke
				(width 0.1)
				(type default)
			)
			(layer "F.Fab")
		)
		(fp_line
			(start 0.12065 -0.2794)
			(end 0.12065 -0.3048)
			(stroke
				(width 0.1)
				(type default)
			)
			(layer "F.Fab")
		)
		(fp_line
			(start 0.67945 -0.3048)
			(end 0.67945 0.3048)
			(stroke
				(width 0.1)
				(type default)
			)
			(layer "F.Fab")
		)
		(fp_line
			(start 0.67945 0.3048)
			(end 0.120396 0.3048)
			(stroke
				(width 0.1)
				(type default)
			)
			(layer "F.Fab")
		)
		(pad "1" smd circle
			(at -0.40005 0)
			(size 0 0)
			(layers "F.Cu" "F.Mask" "F.Paste")
			(net "SMB_PDB_FAN_1_SDA")
		)
		(pad "2" smd circle
			(at 0.40005 0)
			(size 0 0)
			(layers "F.Cu" "F.Mask" "F.Paste")
			(net "P3V3_AUX")
		)
	)
	(footprint ""
		(layer "F.Cu")
		(at 442.595 -41.402)
		(property "Reference" "U1"
			(at -4.8768 0.54737 0)
			(unlocked yes)
			(layer "F.SilkS")
			(effects
				(font
					(size 0.7874 0.5842)
					(thickness 0.1524)
				)
				(justify left)
			)
		)
		(property "Value" ""
			(at 0 0 0)
			(layer "F.Fab")
			(effects
				(font
					(size 1.27 1.27)
				)
			)
		)
		(duplicate_pad_numbers_are_jumpers no)
		(fp_line
			(start -1.3716 -1.524)
			(end -0.508 -1.524)
			(stroke
				(width 0.1524)
				(type default)
			)
			(layer "F.SilkS")
		)
		(fp_line
			(start -1.3716 1.524)
			(end -1.3716 -1.524)
			(stroke
				(width 0.1524)
				(type default)
			)
			(layer "F.SilkS")
		)
		(fp_line
			(start -0.508 -1.524)
			(end 0 -1.016)
			(stroke
				(width 0.1524)
				(type default)
			)
			(layer "F.SilkS")
		)
		(fp_line
			(start 0 -1.016)
			(end 0.508 -1.524)
			(stroke
				(width 0.1524)
				(type default)
			)
			(layer "F.SilkS")
		)
		(fp_line
			(start 0.508 -1.524)
			(end 1.3716 -1.524)
			(stroke
				(width 0.1524)
				(type default)
			)
			(layer "F.SilkS")
		)
		(fp_line
			(start 1.3716 -1.524)
			(end 1.3716 1.524)
			(stroke
				(width 0.1524)
				(type default)
			)
			(layer "F.SilkS")
		)
		(fp_line
			(start 1.3716 1.524)
			(end -1.3716 1.524)
			(stroke
				(width 0.1524)
				(type default)
			)
			(layer "F.SilkS")
		)
		(fp_poly
			(pts
				(xy -2.557272 -1.84912) (xy -1.932432 -1.84912) (xy -2.2606 -1.2954)
			)
			(stroke
				(width 0)
				(type default)
			)
			(fill yes)
			(layer "F.SilkS")
		)
		(fp_line
			(start -2.54 -1.0668)
			(end -1.5494 -1.0668)
			(stroke
				(width 0.1)
				(type default)
			)
			(layer "F.Fab")
		)
		(fp_line
			(start -2.54 1.0668)
			(end -2.54 -1.0668)
			(stroke
				(width 0.1)
				(type default)
			)
			(layer "F.Fab")
		)
		(fp_line
			(start -1.5494 -1.524)
			(end 1.5494 -1.524)
			(stroke
				(width 0.1)
				(type default)
			)
			(layer "F.Fab")
		)
		(fp_line
			(start -1.5494 -1.0668)
			(end -1.5494 -1.524)
			(stroke
				(width 0.1)
				(type default)
			)
			(layer "F.Fab")
		)
		(fp_line
			(start -1.5494 1.0668)
			(end -2.54 1.0668)
			(stroke
				(width 0.1)
				(type default)
			)
			(layer "F.Fab")
		)
		(fp_line
			(start -1.5494 1.0668)
			(end -1.5494 -1.0668)
			(stroke
				(width 0.1)
				(type default)
			)
			(layer "F.Fab")
		)
		(fp_line
			(start -1.5494 1.524)
			(end -1.5494 1.0668)
			(stroke
				(width 0.1)
				(type default)
			)
			(layer "F.Fab")
		)
		(fp_line
			(start 1.5494 -1.524)
			(end 1.5494 -1.0668)
			(stroke
				(width 0.1)
				(type default)
			)
			(layer "F.Fab")
		)
		(fp_line
			(start 1.5494 -1.0668)
			(end 1.5494 1.0668)
			(stroke
				(width 0.1)
				(type default)
			)
			(layer "F.Fab")
		)
		(fp_line
			(start 1.5494 -1.0668)
			(end 2.54 -1.0668)
			(stroke
				(width 0.1)
				(type default)
			)
			(layer "F.Fab")
		)
		(fp_line
			(start 1.5494 1.0668)
			(end 1.5494 1.524)
			(stroke
				(width 0.1)
				(type default)
			)
			(layer "F.Fab")
		)
		(fp_line
			(start 1.5494 1.524)
			(end -1.5494 1.524)
			(stroke
				(width 0.1)
				(type default)
			)
			(layer "F.Fab")
		)
		(fp_line
			(start 2.54 -1.0668)
			(end 2.54 1.0668)
			(stroke
				(width 0.1)
				(type default)
			)
			(layer "F.Fab")
		)
		(fp_line
			(start 2.54 1.0668)
			(end 1.5494 1.0668)
			(stroke
				(width 0.1)
				(type default)
			)
			(layer "F.Fab")
		)
		(fp_poly
			(pts
				(xy -3.60172 -0.719328) (xy -3.60172 -1.344168) (xy -3.048 -1.016)
			)
			(stroke
				(width 0)
				(type default)
			)
			(fill yes)
			(layer "F.Fab")
		)
		(pad "1" smd rect
			(at -2.232406 -0.975106 270)
			(size 0.3556 1.4224)
			(layers "F.Cu" "F.Mask" "F.Paste")
			(net "MB_MISC_I2C_EN")
		)
		(pad "2" smd rect
			(at -2.232406 -0.32512 270)
			(size 0.3556 1.4224)
			(layers "F.Cu" "F.Mask" "F.Paste")
			(net "SMB_PDB_MISC_SCL_R")
		)
		(pad "3" smd rect
			(at -2.232406 0.32512 270)
			(size 0.3556 1.4224)
			(layers "F.Cu" "F.Mask" "F.Paste")
			(net "SMB_PDB_SCL")
		)
		(pad "4" smd rect
			(at -2.232406 0.975106 270)
			(size 0.3556 1.4224)
			(layers "F.Cu" "F.Mask" "F.Paste")
			(net "GND")
		)
		(pad "5" smd rect
			(at 2.232406 0.975106 270)
			(size 0.3556 1.4224)
			(layers "F.Cu" "F.Mask" "F.Paste")
			(net "NC_U1_READY")
		)
		(pad "6" smd rect
			(at 2.232406 0.32512 270)
			(size 0.3556 1.4224)
			(layers "F.Cu" "F.Mask" "F.Paste")
			(net "SMB_PDB_SDA")
		)
		(pad "7" smd rect
			(at 2.232406 -0.32512 270)
			(size 0.3556 1.4224)
			(layers "F.Cu" "F.Mask" "F.Paste")
			(net "SMB_PDB_MISC_SDA_R")
		)
		(pad "8" smd rect
			(at 2.232406 -0.975106 270)
			(size 0.3556 1.4224)
			(layers "F.Cu" "F.Mask" "F.Paste")
			(net "P3V3_AUX")
		)
	)
	(footprint ""
		(layer "F.Cu")
		(at 164.211 -81.534 90)
		(property "Reference" "U44"
			(at -1.651 -1.793748 90)
			(unlocked yes)
			(layer "F.SilkS")
			(effects
				(font
					(size 0.7874 0.5842)
					(thickness 0.1524)
				)
				(justify left)
			)
		)
		(property "Value" ""
			(at 0 0 90)
			(layer "F.Fab")
			(effects
				(font
					(size 1.27 1.27)
				)
			)
		)
		(duplicate_pad_numbers_are_jumpers no)
		(fp_line
			(start 1.400048 -1.100074)
			(end -1.400048 -1.100074)
			(stroke
				(width 0.1524)
				(type default)
			)
			(layer "F.SilkS")
		)
		(fp_line
			(start 1.400048 -1.100074)
			(end 1.400048 1.100074)
			(stroke
				(width 0.1524)
				(type default)
			)
			(layer "F.SilkS")
		)
		(fp_line
			(start 1.400048 1.100074)
			(end -1.400048 1.100074)
			(stroke
				(width 0.1524)
				(type default)
			)
			(layer "F.SilkS")
		)
		(fp_line
			(start -1.400048 1.100074)
			(end -1.400048 -1.100074)
			(stroke
				(width 0.1524)
				(type default)
			)
			(layer "F.SilkS")
		)
		(fp_poly
			(pts
				(xy -1.590548 -0.649986) (xy -2.606548 -1.157986) (xy -2.606548 -0.141986)
			)
			(stroke
				(width 0)
				(type default)
			)
			(fill yes)
			(layer "F.SilkS")
		)
		(fp_line
			(start 0.674878 -1.100074)
			(end 0.674878 1.100074)
			(stroke
				(width 0.1)
				(type default)
			)
			(layer "F.Fab")
		)
		(fp_line
			(start -0.674878 -1.100074)
			(end 0.674878 -1.100074)
			(stroke
				(width 0.1)
				(type default)
			)
			(layer "F.Fab")
		)
		(fp_line
			(start 0.674878 1.100074)
			(end -0.674878 1.100074)
			(stroke
				(width 0.1)
				(type default)
			)
			(layer "F.Fab")
		)
		(fp_line
			(start -0.674878 1.100074)
			(end -0.674878 -1.100074)
			(stroke
				(width 0.1)
				(type default)
			)
			(layer "F.Fab")
		)
		(fp_poly
			(pts
				(xy -1.590548 -0.649986) (xy -2.606548 -1.157986) (xy -2.606548 -0.141986)
			)
			(stroke
				(width 0)
				(type default)
			)
			(fill yes)
			(layer "F.Fab")
		)
		(pad "1" smd rect
			(at -0.94996 -0.649986)
			(size 0.4318 0.6096)
			(layers "F.Cu" "F.Mask" "F.Paste")
			(net "Net_416")
		)
		(pad "2" smd rect
			(at -0.94996 0)
			(size 0.4318 0.6096)
			(layers "F.Cu" "F.Mask" "F.Paste")
			(net "FM_HS2_EN_BUSBAR")
		)
		(pad "3" smd rect
			(at -0.94996 0.649986)
			(size 0.4318 0.6096)
			(layers "F.Cu" "F.Mask" "F.Paste")
			(net "GND")
		)
		(pad "4" smd rect
			(at 0.94996 0.649986)
			(size 0.4318 0.6096)
			(layers "F.Cu" "F.Mask" "F.Paste")
			(net "FM_HS2_EN_BUSBAR_BUF")
		)
		(pad "5" smd rect
			(at 0.94996 -0.649986)
			(size 0.4318 0.6096)
			(layers "F.Cu" "F.Mask" "F.Paste")
			(net "P3V3_AUX")
		)
	)
	(footprint ""
		(layer "F.Cu")
		(at 436.9054 -50.419 180)
		(property "Reference" "U33"
			(at 1.7399 2.37363 0)
			(unlocked yes)
			(layer "F.SilkS")
			(effects
				(font
					(size 0.7874 0.5842)
					(thickness 0.1524)
				)
				(justify left)
			)
		)
		(property "Value" ""
			(at 0 0 180)
			(layer "F.Fab")
			(effects
				(font
					(size 1.27 1.27)
				)
			)
		)
		(duplicate_pad_numbers_are_jumpers no)
		(fp_line
			(start 1.733296 1.549908)
			(end 1.733296 -1.549908)
			(stroke
				(width 0.1524)
				(type default)
			)
			(layer "F.SilkS")
		)
		(fp_line
			(start 1.733296 -1.549908)
			(end 0.660908 -1.549908)
			(stroke
				(width 0.1524)
				(type default)
			)
			(layer "F.SilkS")
		)
		(fp_line
			(start 0.660908 -1.549908)
			(end 0 -0.889)
			(stroke
				(width 0.1524)
				(type default)
			)
			(layer "F.SilkS")
		)
		(fp_line
			(start 0 -0.889)
			(end -0.660908 -1.549908)
			(stroke
				(width 0.1524)
				(type default)
			)
			(layer "F.SilkS")
		)
		(fp_line
			(start -0.660908 -1.549908)
			(end -1.733296 -1.549908)
			(stroke
				(width 0.1524)
				(type default)
			)
			(layer "F.SilkS")
		)
		(fp_line
			(start -1.733296 1.549908)
			(end 1.733296 1.549908)
			(stroke
				(width 0.1524)
				(type default)
			)
			(layer "F.SilkS")
		)
		(fp_line
			(start -1.733296 -1.549908)
			(end -1.733296 1.549908)
			(stroke
				(width 0.1524)
				(type default)
			)
			(layer "F.SilkS")
		)
		(fp_poly
			(pts
				(xy -0.9906 -2.159) (xy -1.4986 -2.159) (xy -1.2446 -1.651)
			)
			(stroke
				(width 0)
				(type default)
			)
			(fill yes)
			(layer "F.SilkS")
		)
		(fp_line
			(start 0.849884 1.549908)
			(end 0.849884 -1.549908)
			(stroke
				(width 0.1)
				(type default)
			)
			(layer "F.Fab")
		)
		(fp_line
			(start 0.849884 -1.549908)
			(end -0.849884 -1.549908)
			(stroke
				(width 0.1)
				(type default)
			)
			(layer "F.Fab")
		)
		(fp_line
			(start -0.849884 1.549908)
			(end 0.849884 1.549908)
			(stroke
				(width 0.1)
				(type default)
			)
			(layer "F.Fab")
		)
		(fp_line
			(start -0.849884 -1.549908)
			(end -0.849884 1.549908)
			(stroke
				(width 0.1)
				(type default)
			)
			(layer "F.Fab")
		)
		(fp_poly
			(pts
				(xy -2.4384 -1.20396) (xy -2.4384 -0.69596) (xy -1.9304 -0.94996)
			)
			(stroke
				(width 0)
				(type default)
			)
			(fill yes)
			(layer "F.Fab")
		)
		(pad "1" smd rect
			(at -1.199896 -0.94996 90)
			(size 0.5588 0.8128)
			(layers "F.Cu" "F.Mask" "F.Paste")
			(net "PWRGD_P52V_HS1_PG")
		)
		(pad "2" smd rect
			(at -1.199896 0 90)
			(size 0.5588 0.8128)
			(layers "F.Cu" "F.Mask" "F.Paste")
			(net "PWRGD_P52V_HS2_PG")
		)
		(pad "3" smd rect
			(at -1.199896 0.94996 90)
			(size 0.5588 0.8128)
			(layers "F.Cu" "F.Mask" "F.Paste")
			(net "GND")
		)
		(pad "4" smd rect
			(at 1.199896 0.94996 90)
			(size 0.5588 0.8128)
			(layers "F.Cu" "F.Mask" "F.Paste")
			(net "PWRGD_P52V_HS_PG_R2")
		)
		(pad "5" smd rect
			(at 1.199896 -0.94996 90)
			(size 0.5588 0.8128)
			(layers "F.Cu" "F.Mask" "F.Paste")
			(net "P3V3_AUX")
		)
	)
	(footprint ""
		(layer "F.Cu")
		(at 302.4124 -36.1442)
		(property "Reference" "PR6964"
			(at 0 0 0)
			(layer "F.SilkS")
			(hide yes)
			(effects
				(font
					(size 1.27 1.27)
				)
			)
		)
		(property "Value" ""
			(at 0 0 0)
			(layer "F.Fab")
			(effects
				(font
					(size 1.27 1.27)
				)
			)
		)
		(duplicate_pad_numbers_are_jumpers no)
		(fp_line
			(start -1.2954 -0.5842)
			(end 1.2954 -0.5842)
			(stroke
				(width 0.1524)
				(type default)
			)
			(layer "F.SilkS")
		)
		(fp_line
			(start -1.2954 0.5842)
			(end -1.2954 -0.5842)
			(stroke
				(width 0.1524)
				(type default)
			)
			(layer "F.SilkS")
		)
		(fp_line
			(start 1.2954 -0.5842)
			(end 1.2954 0.5842)
			(stroke
				(width 0.1524)
				(type default)
			)
			(layer "F.SilkS")
		)
		(fp_line
			(start 1.2954 0.5842)
			(end -1.2954 0.5842)
			(stroke
				(width 0.1524)
				(type default)
			)
			(layer "F.SilkS")
		)
		(fp_line
			(start -1.1938 -0.406654)
			(end -0.8636 -0.406654)
			(stroke
				(width 0.1)
				(type default)
			)
			(layer "F.Fab")
		)
		(fp_line
			(start -1.1938 0.4064)
			(end -1.1938 -0.406654)
			(stroke
				(width 0.1)
				(type default)
			)
			(layer "F.Fab")
		)
		(fp_line
			(start -0.8636 -0.4572)
			(end 0.8636 -0.4572)
			(stroke
				(width 0.1)
				(type default)
			)
			(layer "F.Fab")
		)
		(fp_line
			(start -0.8636 -0.406654)
			(end -0.8636 -0.4572)
			(stroke
				(width 0.1)
				(type default)
			)
			(layer "F.Fab")
		)
		(fp_line
			(start -0.8636 0.4064)
			(end -1.1938 0.4064)
			(stroke
				(width 0.1)
				(type default)
			)
			(layer "F.Fab")
		)
		(fp_line
			(start -0.8636 0.4318)
			(end -0.8636 0.4064)
			(stroke
				(width 0.1)
				(type default)
			)
			(layer "F.Fab")
		)
		(fp_line
			(start -0.8636 0.4572)
			(end -0.8636 0.4318)
			(stroke
				(width 0.1)
				(type default)
			)
			(layer "F.Fab")
		)
		(fp_line
			(start 0.8636 -0.4572)
			(end 0.8636 -0.406654)
			(stroke
				(width 0.1)
				(type default)
			)
			(layer "F.Fab")
		)
		(fp_line
			(start 0.8636 -0.406654)
			(end 1.1938 -0.406654)
			(stroke
				(width 0.1)
				(type default)
			)
			(layer "F.Fab")
		)
		(fp_line
			(start 0.8636 0.4064)
			(end 0.8636 0.4572)
			(stroke
				(width 0.1)
				(type default)
			)
			(layer "F.Fab")
		)
		(fp_line
			(start 0.8636 0.4572)
			(end -0.8636 0.4572)
			(stroke
				(width 0.1)
				(type default)
			)
			(layer "F.Fab")
		)
		(fp_line
			(start 1.1938 -0.406654)
			(end 1.1938 0.4064)
			(stroke
				(width 0.1)
				(type default)
			)
			(layer "F.Fab")
		)
		(fp_line
			(start 1.1938 0.4064)
			(end 0.8636 0.4064)
			(stroke
				(width 0.1)
				(type default)
			)
			(layer "F.Fab")
		)
		(pad "1" smd rect
			(at -0.7366 0 270)
			(size 0.7112 0.8128)
			(layers "F.Cu" "F.Mask" "F.Paste")
			(net "P52V_HS1_SENSE_P_R2")
		)
		(pad "2" smd rect
			(at 0.7366 0 270)
			(size 0.7112 0.8128)
			(layers "F.Cu" "F.Mask" "F.Paste")
			(net "P52V_HS_4287_ADC_P")
		)
	)
	(footprint ""
		(layer "F.Cu")
		(at 281.0764 -72.39)
		(property "Reference" "R374"
			(at 0 0 0)
			(layer "F.SilkS")
			(hide yes)
			(effects
				(font
					(size 1.27 1.27)
				)
			)
		)
		(property "Value" ""
			(at 0 0 0)
			(layer "F.Fab")
			(effects
				(font
					(size 1.27 1.27)
				)
			)
		)
		(duplicate_pad_numbers_are_jumpers no)
		(fp_line
			(start -0.7874 -0.4064)
			(end 0.7874 -0.4064)
			(stroke
				(width 0.1524)
				(type default)
			)
			(layer "F.SilkS")
		)
		(fp_line
			(start -0.7874 0.4064)
			(end -0.7874 -0.4064)
			(stroke
				(width 0.1524)
				(type default)
			)
			(layer "F.SilkS")
		)
		(fp_line
			(start 0.7874 -0.4064)
			(end 0.7874 0.4064)
			(stroke
				(width 0.1524)
				(type default)
			)
			(layer "F.SilkS")
		)
		(fp_line
			(start 0.7874 0.4064)
			(end -0.7874 0.4064)
			(stroke
				(width 0.1524)
				(type default)
			)
			(layer "F.SilkS")
		)
		(fp_line
			(start -0.67945 -0.305054)
			(end -0.12065 -0.305054)
			(stroke
				(width 0.1)
				(type default)
			)
			(layer "F.Fab")
		)
		(fp_line
			(start -0.67945 0.3048)
			(end -0.67945 -0.305054)
			(stroke
				(width 0.1)
				(type default)
			)
			(layer "F.Fab")
		)
		(fp_line
			(start -0.12065 -0.305054)
			(end -0.12065 -0.2794)
			(stroke
				(width 0.1)
				(type default)
			)
			(layer "F.Fab")
		)
		(fp_line
			(start -0.12065 -0.2794)
			(end 0.12065 -0.2794)
			(stroke
				(width 0.1)
				(type default)
			)
			(layer "F.Fab")
		)
		(fp_line
			(start -0.12065 0.2794)
			(end -0.12065 0.3048)
			(stroke
				(width 0.1)
				(type default)
			)
			(layer "F.Fab")
		)
		(fp_line
			(start -0.12065 0.3048)
			(end -0.67945 0.3048)
			(stroke
				(width 0.1)
				(type default)
			)
			(layer "F.Fab")
		)
		(fp_line
			(start 0.120396 0.2794)
			(end -0.12065 0.2794)
			(stroke
				(width 0.1)
				(type default)
			)
			(layer "F.Fab")
		)
		(fp_line
			(start 0.120396 0.3048)
			(end 0.120396 0.2794)
			(stroke
				(width 0.1)
				(type default)
			)
			(layer "F.Fab")
		)
		(fp_line
			(start 0.12065 -0.3048)
			(end 0.67945 -0.3048)
			(stroke
				(width 0.1)
				(type default)
			)
			(layer "F.Fab")
		)
		(fp_line
			(start 0.12065 -0.2794)
			(end 0.12065 -0.3048)
			(stroke
				(width 0.1)
				(type default)
			)
			(layer "F.Fab")
		)
		(fp_line
			(start 0.67945 -0.3048)
			(end 0.67945 0.3048)
			(stroke
				(width 0.1)
				(type default)
			)
			(layer "F.Fab")
		)
		(fp_line
			(start 0.67945 0.3048)
			(end 0.120396 0.3048)
			(stroke
				(width 0.1)
				(type default)
			)
			(layer "F.Fab")
		)
		(pad "1" smd circle
			(at -0.40005 0)
			(size 0 0)
			(layers "F.Cu" "F.Mask" "F.Paste")
			(net "P52V_HS1_ADR1")
		)
		(pad "2" smd circle
			(at 0.40005 0)
			(size 0 0)
			(layers "F.Cu" "F.Mask" "F.Paste")
			(net "GND_FIELD_SIGNAL")
		)
	)
	(footprint ""
		(layer "F.Cu")
		(at 417.5506 -28.7528 -90)
		(property "Reference" "U38"
			(at -1.7907 -4.25577 90)
			(unlocked yes)
			(layer "F.SilkS")
			(effects
				(font
					(size 0.7874 0.5842)
					(thickness 0.1524)
				)
				(justify left)
			)
		)
		(property "Value" ""
			(at 0 0 270)
			(layer "F.Fab")
			(effects
				(font
					(size 1.27 1.27)
				)
			)
		)
		(duplicate_pad_numbers_are_jumpers no)
		(fp_line
			(start -1.549908 2.549906)
			(end -0.753872 2.549906)
			(stroke
				(width 0.1524)
				(type default)
			)
			(layer "F.SilkS")
		)
		(fp_line
			(start -0.245872 2.549906)
			(end 0.245872 2.549906)
			(stroke
				(width 0.1524)
				(type default)
			)
			(layer "F.SilkS")
		)
		(fp_line
			(start 0.753872 2.549906)
			(end 1.549908 2.549906)
			(stroke
				(width 0.1524)
				(type default)
			)
			(layer "F.SilkS")
		)
		(fp_line
			(start 1.549908 2.549906)
			(end 1.549908 2.253996)
			(stroke
				(width 0.1524)
				(type default)
			)
			(layer "F.SilkS")
		)
		(fp_line
			(start -1.549908 2.253996)
			(end -1.549908 2.549906)
			(stroke
				(width 0.1524)
				(type default)
			)
			(layer "F.SilkS")
		)
		(fp_line
			(start 1.549908 -2.253996)
			(end 1.549908 -2.549906)
			(stroke
				(width 0.1524)
				(type default)
			)
			(layer "F.SilkS")
		)
		(fp_line
			(start -1.549908 -2.549906)
			(end -1.549908 -2.251964)
			(stroke
				(width 0.1524)
				(type default)
			)
			(layer "F.SilkS")
		)
		(fp_line
			(start -0.752094 -2.549906)
			(end -1.549908 -2.549906)
			(stroke
				(width 0.1524)
				(type default)
			)
			(layer "F.SilkS")
		)
		(fp_line
			(start 0.2413 -2.549906)
			(end -0.2413 -2.549906)
			(stroke
				(width 0.1524)
				(type default)
			)
			(layer "F.SilkS")
		)
		(fp_line
			(start 1.549908 -2.549906)
			(end 0.752094 -2.549906)
			(stroke
				(width 0.1524)
				(type default)
			)
			(layer "F.SilkS")
		)
		(fp_poly
			(pts
				(xy -2.06121 -2.13741) (xy -2.964434 -2.438654) (xy -2.362454 -3.040634)
			)
			(stroke
				(width 0)
				(type default)
			)
			(fill yes)
			(layer "F.SilkS")
		)
		(fp_line
			(start -1.549908 2.549906)
			(end 1.549908 2.549906)
			(stroke
				(width 0.1)
				(type default)
			)
			(layer "F.Fab")
		)
		(fp_line
			(start 1.549908 2.549906)
			(end 1.549908 -2.549906)
			(stroke
				(width 0.1)
				(type default)
			)
			(layer "F.Fab")
		)
		(fp_line
			(start -1.549908 -2.549906)
			(end -1.549908 2.549906)
			(stroke
				(width 0.1)
				(type default)
			)
			(layer "F.Fab")
		)
		(fp_line
			(start 1.549908 -2.549906)
			(end -1.549908 -2.549906)
			(stroke
				(width 0.1)
				(type default)
			)
			(layer "F.Fab")
		)
		(fp_poly
			(pts
				(xy -1.891538 -1.999996) (xy -2.7432 -1.574292) (xy -2.7432 -2.4257)
			)
			(stroke
				(width 0)
				(type default)
			)
			(fill yes)
			(layer "F.Fab")
		)
		(fp_text user "11"
			(at 2.2606 5.87375 270)
			(unlocked yes)
			(layer "F.SilkS")
			(effects
				(font
					(size 0.635 0.4064)
					(thickness 0.1524)
				)
			)
		)
		(fp_text user "10"
			(at -1.4224 3.253232 270)
			(unlocked yes)
			(layer "F.SilkS")
			(effects
				(font
					(size 0.635 0.4064)
					(thickness 0.1524)
				)
			)
		)
		(fp_text user "9"
			(at -2.338832 2.5908 180)
			(unlocked yes)
			(layer "F.SilkS")
			(effects
				(font
					(size 0.635 0.4064)
					(thickness 0.1524)
				)
			)
		)
		(fp_text user "12"
			(at 3.67665 1.143 180)
			(unlocked yes)
			(layer "F.SilkS")
			(effects
				(font
					(size 0.635 0.4064)
					(thickness 0.1524)
				)
			)
		)
		(fp_text user "20"
			(at 1.79705 -3.2004 180)
			(unlocked yes)
			(layer "F.SilkS")
			(effects
				(font
					(size 0.635 0.4064)
					(thickness 0.1524)
				)
			)
		)
		(fp_text user "21_22"
			(at -0.0762 -3.401568 270)
			(unlocked yes)
			(layer "F.SilkS")
			(effects
				(font
					(size 0.635 0.4064)
					(thickness 0.1524)
				)
			)
		)
		(fp_text user "11"
			(at 1.1938 3.329432 270)
			(unlocked yes)
			(layer "F.Fab")
			(effects
				(font
					(size 0.635 0.4064)
					(thickness 0.1524)
				)
			)
		)
		(fp_text user "10"
			(at -1.4224 3.253232 270)
			(unlocked yes)
			(layer "F.Fab")
			(effects
				(font
					(size 0.635 0.4064)
					(thickness 0.1524)
				)
			)
		)
		(fp_text user "12"
			(at 2.207768 2.7178 180)
			(unlocked yes)
			(layer "F.Fab")
			(effects
				(font
					(size 0.635 0.4064)
					(thickness 0.1524)
				)
			)
		)
		(fp_text user "9"
			(at -2.338832 2.5908 180)
			(unlocked yes)
			(layer "F.Fab")
			(effects
				(font
					(size 0.635 0.4064)
					(thickness 0.1524)
				)
			)
		)
		(fp_text user "20"
			(at 2.055368 -2.7686 180)
			(unlocked yes)
			(layer "F.Fab")
			(effects
				(font
					(size 0.635 0.4064)
					(thickness 0.1524)
				)
			)
		)
		(fp_text user "21_22"
			(at -0.0762 -3.401568 270)
			(unlocked yes)
			(layer "F.Fab")
			(effects
				(font
					(size 0.635 0.4064)
					(thickness 0.1524)
				)
			)
		)
		(pad "1" smd circle
			(at -1.374902 -1.999996 180)
			(size 0 0)
			(layers "F.Cu" "F.Mask" "F.Paste")
			(net "P12V_LED_EN_R")
		)
		(pad "2" smd rect
			(at -1.400048 -1.500124 180)
			(size 0.254 0.8128)
			(layers "F.Cu" "F.Mask" "F.Paste")
			(net "GND")
		)
		(pad "3" smd rect
			(at -1.400048 -0.999998 180)
			(size 0.254 0.8128)
			(layers "F.Cu" "F.Mask" "F.Paste")
			(net "GND")
		)
		(pad "4" smd rect
			(at -1.400048 -0.499872 180)
			(size 0.254 0.8128)
			(layers "F.Cu" "F.Mask" "F.Paste")
			(net "P12V_LED_TIMER")
		)
		(pad "5" smd rect
			(at -1.400048 0 180)
			(size 0.254 0.8128)
			(layers "F.Cu" "F.Mask" "F.Paste")
			(net "P12V_LED_ISET")
		)
		(pad "6" smd rect
			(at -1.400048 0.499872 180)
			(size 0.254 0.8128)
			(layers "F.Cu" "F.Mask" "F.Paste")
			(net "P12V_LED_SS")
		)
		(pad "7" smd rect
			(at -1.400048 0.999998 180)
			(size 0.254 0.8128)
			(layers "F.Cu" "F.Mask" "F.Paste")
			(net "GND")
		)
		(pad "8" smd rect
			(at -1.400048 1.500124 180)
			(size 0.254 0.8128)
			(layers "F.Cu" "F.Mask" "F.Paste")
			(net "P12V_LED_IMON")
		)
		(pad "9" smd rect
			(at -1.400048 1.999996 180)
			(size 0.254 0.8128)
			(layers "F.Cu" "F.Mask" "F.Paste")
			(net "P12V_LED_FLTB")
		)
		(pad "10" smd rect
			(at -0.499872 2.400046 270)
			(size 0.254 0.8128)
			(layers "F.Cu" "F.Mask" "F.Paste")
			(net "PWRGD_P12V_FAN_LED_R")
		)
		(pad "11" smd rect
			(at 0.499872 2.400046 270)
			(size 0.254 0.8128)
			(layers "F.Cu" "F.Mask" "F.Paste")
			(net "P12V_LED_FB")
		)
		(pad "12" smd rect
			(at 1.400048 1.999996 180)
			(size 0.254 0.8128)
			(layers "F.Cu" "F.Mask" "F.Paste")
			(net "P12V_LED_PD")
		)
		(pad "13" smd rect
			(at 1.400048 1.500124 180)
			(size 0.254 0.8128)
			(layers "F.Cu" "F.Mask" "F.Paste")
			(net "P12V_FAN_LED")
		)
		(pad "14" smd rect
			(at 1.400048 0.999998 180)
			(size 0.254 0.8128)
			(layers "F.Cu" "F.Mask" "F.Paste")
			(net "P12V_FAN_LED")
		)
		(pad "15" smd rect
			(at 1.400048 0.499872 180)
			(size 0.254 0.8128)
			(layers "F.Cu" "F.Mask" "F.Paste")
			(net "P12V_FAN_LED")
		)
		(pad "16" smd rect
			(at 1.400048 0 180)
			(size 0.254 0.8128)
			(layers "F.Cu" "F.Mask" "F.Paste")
			(net "P12V_FAN_LED")
		)
		(pad "17" smd rect
			(at 1.400048 -0.499872 180)
			(size 0.254 0.8128)
			(layers "F.Cu" "F.Mask" "F.Paste")
			(net "P12V_FAN_LED")
		)
		(pad "18" smd rect
			(at 1.400048 -0.999998 180)
			(size 0.254 0.8128)
			(layers "F.Cu" "F.Mask" "F.Paste")
			(net "P12V_FAN_LED")
		)
		(pad "19" smd rect
			(at 1.400048 -1.500124 180)
			(size 0.254 0.8128)
			(layers "F.Cu" "F.Mask" "F.Paste")
			(net "P12V_FAN_LED")
		)
		(pad "20" smd rect
			(at 1.400048 -1.999996 180)
			(size 0.254 0.8128)
			(layers "F.Cu" "F.Mask" "F.Paste")
			(net "P12V_FAN_LED")
		)
		(pad "21_22" smd circle
			(at 0.499872 -2.337562 180)
			(size 0 0)
			(layers "F.Cu" "F.Mask" "F.Paste")
			(net "P12V_HPDB")
		)
		(pad "23" smd rect
			(at 0 -1.100074 180)
			(size 0.254 1.27)
			(layers "F.Cu" "F.Mask" "F.Paste")
			(net "P12V_HPDB")
		)
		(pad "24" smd rect
			(at 0 -0.199898 180)
			(size 0.254 1.27)
			(layers "F.Cu" "F.Mask" "F.Paste")
			(net "P12V_HPDB")
		)
		(pad "25" smd rect
			(at 0 0.700024 180)
			(size 0.254 1.27)
			(layers "F.Cu" "F.Mask" "F.Paste")
			(net "P12V_HPDB")
		)
		(pad "26" smd rect
			(at 0 1.599946 180)
			(size 0.254 1.27)
			(layers "F.Cu" "F.Mask" "F.Paste")
			(net "P12V_HPDB")
		)
	)
	(footprint ""
		(layer "F.Cu")
		(at 278.6634 -76.327)
		(property "Reference" "PR93"
			(at 0 0 0)
			(layer "F.SilkS")
			(hide yes)
			(effects
				(font
					(size 1.27 1.27)
				)
			)
		)
		(property "Value" ""
			(at 0 0 0)
			(layer "F.Fab")
			(effects
				(font
					(size 1.27 1.27)
				)
			)
		)
		(duplicate_pad_numbers_are_jumpers no)
		(fp_line
			(start -0.7874 -0.4064)
			(end 0.7874 -0.4064)
			(stroke
				(width 0.1524)
				(type default)
			)
			(layer "F.SilkS")
		)
		(fp_line
			(start -0.7874 0.4064)
			(end -0.7874 -0.4064)
			(stroke
				(width 0.1524)
				(type default)
			)
			(layer "F.SilkS")
		)
		(fp_line
			(start 0.7874 -0.4064)
			(end 0.7874 0.4064)
			(stroke
				(width 0.1524)
				(type default)
			)
			(layer "F.SilkS")
		)
		(fp_line
			(start 0.7874 0.4064)
			(end -0.7874 0.4064)
			(stroke
				(width 0.1524)
				(type default)
			)
			(layer "F.SilkS")
		)
		(fp_line
			(start -0.67945 -0.305054)
			(end -0.12065 -0.305054)
			(stroke
				(width 0.1)
				(type default)
			)
			(layer "F.Fab")
		)
		(fp_line
			(start -0.67945 0.3048)
			(end -0.67945 -0.305054)
			(stroke
				(width 0.1)
				(type default)
			)
			(layer "F.Fab")
		)
		(fp_line
			(start -0.12065 -0.305054)
			(end -0.12065 -0.2794)
			(stroke
				(width 0.1)
				(type default)
			)
			(layer "F.Fab")
		)
		(fp_line
			(start -0.12065 -0.2794)
			(end 0.12065 -0.2794)
			(stroke
				(width 0.1)
				(type default)
			)
			(layer "F.Fab")
		)
		(fp_line
			(start -0.12065 0.2794)
			(end -0.12065 0.3048)
			(stroke
				(width 0.1)
				(type default)
			)
			(layer "F.Fab")
		)
		(fp_line
			(start -0.12065 0.3048)
			(end -0.67945 0.3048)
			(stroke
				(width 0.1)
				(type default)
			)
			(layer "F.Fab")
		)
		(fp_line
			(start 0.120396 0.2794)
			(end -0.12065 0.2794)
			(stroke
				(width 0.1)
				(type default)
			)
			(layer "F.Fab")
		)
		(fp_line
			(start 0.120396 0.3048)
			(end 0.120396 0.2794)
			(stroke
				(width 0.1)
				(type default)
			)
			(layer "F.Fab")
		)
		(fp_line
			(start 0.12065 -0.3048)
			(end 0.67945 -0.3048)
			(stroke
				(width 0.1)
				(type default)
			)
			(layer "F.Fab")
		)
		(fp_line
			(start 0.12065 -0.2794)
			(end 0.12065 -0.3048)
			(stroke
				(width 0.1)
				(type default)
			)
			(layer "F.Fab")
		)
		(fp_line
			(start 0.67945 -0.3048)
			(end 0.67945 0.3048)
			(stroke
				(width 0.1)
				(type default)
			)
			(layer "F.Fab")
		)
		(fp_line
			(start 0.67945 0.3048)
			(end 0.120396 0.3048)
			(stroke
				(width 0.1)
				(type default)
			)
			(layer "F.Fab")
		)
		(pad "1" smd circle
			(at -0.40005 0)
			(size 0 0)
			(layers "F.Cu" "F.Mask" "F.Paste")
			(net "P52V_HS1_ESTART_R")
		)
		(pad "2" smd circle
			(at 0.40005 0)
			(size 0 0)
			(layers "F.Cu" "F.Mask" "F.Paste")
			(net "P52V_HS1_ESTART")
		)
	)
	(footprint ""
		(layer "F.Cu")
		(at 449.326 -32.893 180)
		(property "Reference" "R19"
			(at 0 0 180)
			(layer "F.SilkS")
			(hide yes)
			(effects
				(font
					(size 1.27 1.27)
				)
			)
		)
		(property "Value" ""
			(at 0 0 180)
			(layer "F.Fab")
			(effects
				(font
					(size 1.27 1.27)
				)
			)
		)
		(duplicate_pad_numbers_are_jumpers no)
		(fp_line
			(start 0.7874 0.4064)
			(end -0.7874 0.4064)
			(stroke
				(width 0.1524)
				(type default)
			)
			(layer "F.SilkS")
		)
		(fp_line
			(start 0.7874 -0.4064)
			(end 0.7874 0.4064)
			(stroke
				(width 0.1524)
				(type default)
			)
			(layer "F.SilkS")
		)
		(fp_line
			(start -0.7874 0.4064)
			(end -0.7874 -0.4064)
			(stroke
				(width 0.1524)
				(type default)
			)
			(layer "F.SilkS")
		)
		(fp_line
			(start -0.7874 -0.4064)
			(end 0.7874 -0.4064)
			(stroke
				(width 0.1524)
				(type default)
			)
			(layer "F.SilkS")
		)
		(fp_line
			(start 0.67945 0.3048)
			(end 0.120396 0.3048)
			(stroke
				(width 0.1)
				(type default)
			)
			(layer "F.Fab")
		)
		(fp_line
			(start 0.67945 -0.3048)
			(end 0.67945 0.3048)
			(stroke
				(width 0.1)
				(type default)
			)
			(layer "F.Fab")
		)
		(fp_line
			(start 0.12065 -0.2794)
			(end 0.12065 -0.3048)
			(stroke
				(width 0.1)
				(type default)
			)
			(layer "F.Fab")
		)
		(fp_line
			(start 0.12065 -0.3048)
			(end 0.67945 -0.3048)
			(stroke
				(width 0.1)
				(type default)
			)
			(layer "F.Fab")
		)
		(fp_line
			(start 0.120396 0.3048)
			(end 0.120396 0.2794)
			(stroke
				(width 0.1)
				(type default)
			)
			(layer "F.Fab")
		)
		(fp_line
			(start 0.120396 0.2794)
			(end -0.12065 0.2794)
			(stroke
				(width 0.1)
				(type default)
			)
			(layer "F.Fab")
		)
		(fp_line
			(start -0.12065 0.3048)
			(end -0.67945 0.3048)
			(stroke
				(width 0.1)
				(type default)
			)
			(layer "F.Fab")
		)
		(fp_line
			(start -0.12065 0.2794)
			(end -0.12065 0.3048)
			(stroke
				(width 0.1)
				(type default)
			)
			(layer "F.Fab")
		)
		(fp_line
			(start -0.12065 -0.2794)
			(end 0.12065 -0.2794)
			(stroke
				(width 0.1)
				(type default)
			)
			(layer "F.Fab")
		)
		(fp_line
			(start -0.12065 -0.305054)
			(end -0.12065 -0.2794)
			(stroke
				(width 0.1)
				(type default)
			)
			(layer "F.Fab")
		)
		(fp_line
			(start -0.67945 0.3048)
			(end -0.67945 -0.305054)
			(stroke
				(width 0.1)
				(type default)
			)
			(layer "F.Fab")
		)
		(fp_line
			(start -0.67945 -0.305054)
			(end -0.12065 -0.305054)
			(stroke
				(width 0.1)
				(type default)
			)
			(layer "F.Fab")
		)
		(pad "1" smd circle
			(at -0.40005 0 180)
			(size 0 0)
			(layers "F.Cu" "F.Mask" "F.Paste")
			(net "SMB_PDB_MISC_SDA")
		)
		(pad "2" smd circle
			(at 0.40005 0 180)
			(size 0 0)
			(layers "F.Cu" "F.Mask" "F.Paste")
			(net "SMB_FAN_MUX_SDA")
		)
	)
	(footprint ""
		(layer "F.Cu")
		(at 250.000008 -16.500094 180)
		(property "Reference" "H9"
			(at 0.572008 -5.350764 0)
			(unlocked yes)
			(layer "F.SilkS")
			(effects
				(font
					(size 0.7874 0.5842)
					(thickness 0.1524)
				)
				(justify left)
			)
		)
		(property "Value" ""
			(at 0 0 180)
			(layer "F.Fab")
			(effects
				(font
					(size 1.27 1.27)
				)
			)
		)
		(duplicate_pad_numbers_are_jumpers no)
		(pad "1" thru_hole oval
			(at 0 0 180)
			(size 9.017 14.0208)
			(drill 3.0226
				(offset 0 2.499868)
			)
			(layers "*.Cu" "*.Mask")
			(remove_unused_layers no)
			(net "GND")
			(clearance -1.500378)
			(padstack
				(mode front_inner_back)
				(layer "Inner"
					(shape circle)
					(size 0 0)
					(clearance 0)
				)
				(layer "B.Cu"
					(shape oval)
					(size 9.017 14.0208)
					(offset 0 2.499868)
					(clearance -1.500378)
				)
			)
		)
	)
	(footprint ""
		(layer "F.Cu")
		(at 439.674 -61.849 -90)
		(property "Reference" "D6"
			(at 2.9718 -0.03937 90)
			(unlocked yes)
			(layer "F.SilkS")
			(effects
				(font
					(size 0.7874 0.5842)
					(thickness 0.1524)
				)
				(justify left)
			)
		)
		(property "Value" ""
			(at 0 0 270)
			(layer "F.Fab")
			(effects
				(font
					(size 1.27 1.27)
				)
			)
		)
		(duplicate_pad_numbers_are_jumpers no)
		(fp_line
			(start -0.90678 0.4826)
			(end -0.90678 -0.4699)
			(stroke
				(width 0.1524)
				(type default)
			)
			(layer "F.SilkS")
		)
		(fp_line
			(start 0.90678 0.4826)
			(end -0.90678 0.4826)
			(stroke
				(width 0.1524)
				(type default)
			)
			(layer "F.SilkS")
		)
		(fp_line
			(start 1.03378 0.4826)
			(end -0.79248 0.4826)
			(stroke
				(width 0.1524)
				(type default)
			)
			(layer "F.SilkS")
		)
		(fp_line
			(start 1.16078 0.4826)
			(end -0.64008 0.4826)
			(stroke
				(width 0.1524)
				(type default)
			)
			(layer "F.SilkS")
		)
		(fp_line
			(start -0.89408 -0.4826)
			(end 0.90678 -0.4826)
			(stroke
				(width 0.1524)
				(type default)
			)
			(layer "F.SilkS")
		)
		(fp_line
			(start -0.79248 -0.4826)
			(end 1.03378 -0.4826)
			(stroke
				(width 0.1524)
				(type default)
			)
			(layer "F.SilkS")
		)
		(fp_line
			(start -0.64008 -0.4826)
			(end 1.16078 -0.4826)
			(stroke
				(width 0.1524)
				(type default)
			)
			(layer "F.SilkS")
		)
		(fp_line
			(start 0.90678 -0.4826)
			(end 0.90678 0.4826)
			(stroke
				(width 0.1524)
				(type default)
			)
			(layer "F.SilkS")
		)
		(fp_line
			(start 1.03378 -0.4826)
			(end 1.03378 0.4826)
			(stroke
				(width 0.1524)
				(type default)
			)
			(layer "F.SilkS")
		)
		(fp_line
			(start 1.16078 -0.4826)
			(end 1.16078 0.4826)
			(stroke
				(width 0.1524)
				(type default)
			)
			(layer "F.SilkS")
		)
		(fp_line
			(start -0.499872 0.249936)
			(end -0.499872 -0.249936)
			(stroke
				(width 0.1)
				(type default)
			)
			(layer "F.Fab")
		)
		(fp_line
			(start 0.499872 0.249936)
			(end -0.499872 0.249936)
			(stroke
				(width 0.1)
				(type default)
			)
			(layer "F.Fab")
		)
		(fp_line
			(start -0.499872 -0.249936)
			(end 0.499872 -0.249936)
			(stroke
				(width 0.1)
				(type default)
			)
			(layer "F.Fab")
		)
		(fp_line
			(start 0.499872 -0.249936)
			(end 0.499872 0.249936)
			(stroke
				(width 0.1)
				(type default)
			)
			(layer "F.Fab")
		)
		(pad "A" smd rect
			(at -0.47498 0 270)
			(size 0.6096 0.7112)
			(layers "F.Cu" "F.Mask" "F.Paste")
			(net "LED_D6_R1")
		)
		(pad "C" smd rect
			(at 0.47498 0 270)
			(size 0.6096 0.7112)
			(layers "F.Cu" "F.Mask" "F.Paste")
			(net "GND")
		)
	)
	(footprint ""
		(layer "F.Cu")
		(at 433.6288 -41.148 90)
		(property "Reference" "R389"
			(at 0 0 90)
			(layer "F.SilkS")
			(hide yes)
			(effects
				(font
					(size 1.27 1.27)
				)
			)
		)
		(property "Value" ""
			(at 0 0 90)
			(layer "F.Fab")
			(effects
				(font
					(size 1.27 1.27)
				)
			)
		)
		(duplicate_pad_numbers_are_jumpers no)
		(fp_line
			(start 0.7874 -0.4064)
			(end 0.7874 0.4064)
			(stroke
				(width 0.1524)
				(type default)
			)
			(layer "F.SilkS")
		)
		(fp_line
			(start -0.7874 -0.4064)
			(end 0.7874 -0.4064)
			(stroke
				(width 0.1524)
				(type default)
			)
			(layer "F.SilkS")
		)
		(fp_line
			(start 0.7874 0.4064)
			(end -0.7874 0.4064)
			(stroke
				(width 0.1524)
				(type default)
			)
			(layer "F.SilkS")
		)
		(fp_line
			(start -0.7874 0.4064)
			(end -0.7874 -0.4064)
			(stroke
				(width 0.1524)
				(type default)
			)
			(layer "F.SilkS")
		)
		(fp_line
			(start -0.12065 -0.305054)
			(end -0.12065 -0.2794)
			(stroke
				(width 0.1)
				(type default)
			)
			(layer "F.Fab")
		)
		(fp_line
			(start -0.67945 -0.305054)
			(end -0.12065 -0.305054)
			(stroke
				(width 0.1)
				(type default)
			)
			(layer "F.Fab")
		)
		(fp_line
			(start 0.67945 -0.3048)
			(end 0.67945 0.3048)
			(stroke
				(width 0.1)
				(type default)
			)
			(layer "F.Fab")
		)
		(fp_line
			(start 0.12065 -0.3048)
			(end 0.67945 -0.3048)
			(stroke
				(width 0.1)
				(type default)
			)
			(layer "F.Fab")
		)
		(fp_line
			(start 0.12065 -0.2794)
			(end 0.12065 -0.3048)
			(stroke
				(width 0.1)
				(type default)
			)
			(layer "F.Fab")
		)
		(fp_line
			(start -0.12065 -0.2794)
			(end 0.12065 -0.2794)
			(stroke
				(width 0.1)
				(type default)
			)
			(layer "F.Fab")
		)
		(fp_line
			(start 0.120396 0.2794)
			(end -0.12065 0.2794)
			(stroke
				(width 0.1)
				(type default)
			)
			(layer "F.Fab")
		)
		(fp_line
			(start -0.12065 0.2794)
			(end -0.12065 0.3048)
			(stroke
				(width 0.1)
				(type default)
			)
			(layer "F.Fab")
		)
		(fp_line
			(start 0.67945 0.3048)
			(end 0.120396 0.3048)
			(stroke
				(width 0.1)
				(type default)
			)
			(layer "F.Fab")
		)
		(fp_line
			(start 0.120396 0.3048)
			(end 0.120396 0.2794)
			(stroke
				(width 0.1)
				(type default)
			)
			(layer "F.Fab")
		)
		(fp_line
			(start -0.12065 0.3048)
			(end -0.67945 0.3048)
			(stroke
				(width 0.1)
				(type default)
			)
			(layer "F.Fab")
		)
		(fp_line
			(start -0.67945 0.3048)
			(end -0.67945 -0.305054)
			(stroke
				(width 0.1)
				(type default)
			)
			(layer "F.Fab")
		)
		(pad "1" smd circle
			(at -0.40005 0 90)
			(size 0 0)
			(layers "F.Cu" "F.Mask" "F.Paste")
			(net "SMB_PDB_MISC_SCL_R1")
		)
		(pad "2" smd circle
			(at 0.40005 0 90)
			(size 0 0)
			(layers "F.Cu" "F.Mask" "F.Paste")
			(net "SMB_PDB_MISC_SCL")
		)
	)
	(footprint ""
		(layer "F.Cu")
		(at 449.3514 -30.607)
		(property "Reference" "R63"
			(at 0 0 0)
			(layer "F.SilkS")
			(hide yes)
			(effects
				(font
					(size 1.27 1.27)
				)
			)
		)
		(property "Value" ""
			(at 0 0 0)
			(layer "F.Fab")
			(effects
				(font
					(size 1.27 1.27)
				)
			)
		)
		(duplicate_pad_numbers_are_jumpers no)
		(fp_line
			(start -0.7874 -0.4064)
			(end 0.7874 -0.4064)
			(stroke
				(width 0.1524)
				(type default)
			)
			(layer "F.SilkS")
		)
		(fp_line
			(start -0.7874 0.4064)
			(end -0.7874 -0.4064)
			(stroke
				(width 0.1524)
				(type default)
			)
			(layer "F.SilkS")
		)
		(fp_line
			(start 0.7874 -0.4064)
			(end 0.7874 0.4064)
			(stroke
				(width 0.1524)
				(type default)
			)
			(layer "F.SilkS")
		)
		(fp_line
			(start 0.7874 0.4064)
			(end -0.7874 0.4064)
			(stroke
				(width 0.1524)
				(type default)
			)
			(layer "F.SilkS")
		)
		(fp_line
			(start -0.67945 -0.305054)
			(end -0.12065 -0.305054)
			(stroke
				(width 0.1)
				(type default)
			)
			(layer "F.Fab")
		)
		(fp_line
			(start -0.67945 0.3048)
			(end -0.67945 -0.305054)
			(stroke
				(width 0.1)
				(type default)
			)
			(layer "F.Fab")
		)
		(fp_line
			(start -0.12065 -0.305054)
			(end -0.12065 -0.2794)
			(stroke
				(width 0.1)
				(type default)
			)
			(layer "F.Fab")
		)
		(fp_line
			(start -0.12065 -0.2794)
			(end 0.12065 -0.2794)
			(stroke
				(width 0.1)
				(type default)
			)
			(layer "F.Fab")
		)
		(fp_line
			(start -0.12065 0.2794)
			(end -0.12065 0.3048)
			(stroke
				(width 0.1)
				(type default)
			)
			(layer "F.Fab")
		)
		(fp_line
			(start -0.12065 0.3048)
			(end -0.67945 0.3048)
			(stroke
				(width 0.1)
				(type default)
			)
			(layer "F.Fab")
		)
		(fp_line
			(start 0.120396 0.2794)
			(end -0.12065 0.2794)
			(stroke
				(width 0.1)
				(type default)
			)
			(layer "F.Fab")
		)
		(fp_line
			(start 0.120396 0.3048)
			(end 0.120396 0.2794)
			(stroke
				(width 0.1)
				(type default)
			)
			(layer "F.Fab")
		)
		(fp_line
			(start 0.12065 -0.3048)
			(end 0.67945 -0.3048)
			(stroke
				(width 0.1)
				(type default)
			)
			(layer "F.Fab")
		)
		(fp_line
			(start 0.12065 -0.2794)
			(end 0.12065 -0.3048)
			(stroke
				(width 0.1)
				(type default)
			)
			(layer "F.Fab")
		)
		(fp_line
			(start 0.67945 -0.3048)
			(end 0.67945 0.3048)
			(stroke
				(width 0.1)
				(type default)
			)
			(layer "F.Fab")
		)
		(fp_line
			(start 0.67945 0.3048)
			(end 0.120396 0.3048)
			(stroke
				(width 0.1)
				(type default)
			)
			(layer "F.Fab")
		)
		(pad "1" smd circle
			(at -0.40005 0)
			(size 0 0)
			(layers "F.Cu" "F.Mask" "F.Paste")
			(net "SMB_FRU_CLK")
		)
		(pad "2" smd circle
			(at 0.40005 0)
			(size 0 0)
			(layers "F.Cu" "F.Mask" "F.Paste")
			(net "SMB_PDB_MISC_SCL_R1")
		)
	)
	(footprint ""
		(layer "F.Cu")
		(at 129.612136 -83.566)
		(property "Reference" "PR6996"
			(at 0 0 0)
			(layer "F.SilkS")
			(hide yes)
			(effects
				(font
					(size 1.27 1.27)
				)
			)
		)
		(property "Value" ""
			(at 0 0 0)
			(layer "F.Fab")
			(effects
				(font
					(size 1.27 1.27)
				)
			)
		)
		(duplicate_pad_numbers_are_jumpers no)
		(fp_line
			(start -0.7874 -0.4064)
			(end 0.7874 -0.4064)
			(stroke
				(width 0.1524)
				(type default)
			)
			(layer "F.SilkS")
		)
		(fp_line
			(start -0.7874 0.4064)
			(end -0.7874 -0.4064)
			(stroke
				(width 0.1524)
				(type default)
			)
			(layer "F.SilkS")
		)
		(fp_line
			(start 0.7874 -0.4064)
			(end 0.7874 0.4064)
			(stroke
				(width 0.1524)
				(type default)
			)
			(layer "F.SilkS")
		)
		(fp_line
			(start 0.7874 0.4064)
			(end -0.7874 0.4064)
			(stroke
				(width 0.1524)
				(type default)
			)
			(layer "F.SilkS")
		)
		(fp_line
			(start -0.67945 -0.305054)
			(end -0.12065 -0.305054)
			(stroke
				(width 0.1)
				(type default)
			)
			(layer "F.Fab")
		)
		(fp_line
			(start -0.67945 0.3048)
			(end -0.67945 -0.305054)
			(stroke
				(width 0.1)
				(type default)
			)
			(layer "F.Fab")
		)
		(fp_line
			(start -0.12065 -0.305054)
			(end -0.12065 -0.2794)
			(stroke
				(width 0.1)
				(type default)
			)
			(layer "F.Fab")
		)
		(fp_line
			(start -0.12065 -0.2794)
			(end 0.12065 -0.2794)
			(stroke
				(width 0.1)
				(type default)
			)
			(layer "F.Fab")
		)
		(fp_line
			(start -0.12065 0.2794)
			(end -0.12065 0.3048)
			(stroke
				(width 0.1)
				(type default)
			)
			(layer "F.Fab")
		)
		(fp_line
			(start -0.12065 0.3048)
			(end -0.67945 0.3048)
			(stroke
				(width 0.1)
				(type default)
			)
			(layer "F.Fab")
		)
		(fp_line
			(start 0.120396 0.2794)
			(end -0.12065 0.2794)
			(stroke
				(width 0.1)
				(type default)
			)
			(layer "F.Fab")
		)
		(fp_line
			(start 0.120396 0.3048)
			(end 0.120396 0.2794)
			(stroke
				(width 0.1)
				(type default)
			)
			(layer "F.Fab")
		)
		(fp_line
			(start 0.12065 -0.3048)
			(end 0.67945 -0.3048)
			(stroke
				(width 0.1)
				(type default)
			)
			(layer "F.Fab")
		)
		(fp_line
			(start 0.12065 -0.2794)
			(end 0.12065 -0.3048)
			(stroke
				(width 0.1)
				(type default)
			)
			(layer "F.Fab")
		)
		(fp_line
			(start 0.67945 -0.3048)
			(end 0.67945 0.3048)
			(stroke
				(width 0.1)
				(type default)
			)
			(layer "F.Fab")
		)
		(fp_line
			(start 0.67945 0.3048)
			(end 0.120396 0.3048)
			(stroke
				(width 0.1)
				(type default)
			)
			(layer "F.Fab")
		)
		(pad "1" smd rect
			(at -0.40005 0 180)
			(size 0.4572 0.508)
			(layers "F.Cu" "F.Mask" "F.Paste")
			(net "P52V_HS2_TEMPN")
		)
		(pad "2" smd rect
			(at 0.40005 0 180)
			(size 0.4572 0.508)
			(layers "F.Cu" "F.Mask" "F.Paste")
			(net "P52V_HS2_TEMPN_R")
		)
	)
	(footprint ""
		(layer "F.Cu")
		(at 445.741806 -88.932258 180)
		(property "Reference" "PC57"
			(at 0 0 180)
			(layer "F.SilkS")
			(hide yes)
			(effects
				(font
					(size 1.27 1.27)
				)
			)
		)
		(property "Value" ""
			(at 0 0 180)
			(layer "F.Fab")
			(effects
				(font
					(size 1.27 1.27)
				)
			)
		)
		(duplicate_pad_numbers_are_jumpers no)
		(fp_line
			(start 1.524 0.762)
			(end -1.524 0.762)
			(stroke
				(width 0.1524)
				(type default)
			)
			(layer "F.SilkS")
		)
		(fp_line
			(start 1.524 -0.762)
			(end 1.524 0.762)
			(stroke
				(width 0.1524)
				(type default)
			)
			(layer "F.SilkS")
		)
		(fp_line
			(start -1.524 0.762)
			(end -1.524 -0.762)
			(stroke
				(width 0.1524)
				(type default)
			)
			(layer "F.SilkS")
		)
		(fp_line
			(start -1.524 -0.762)
			(end 1.524 -0.762)
			(stroke
				(width 0.1524)
				(type default)
			)
			(layer "F.SilkS")
		)
		(fp_line
			(start 1.1049 0.724916)
			(end 1.1049 -0.724916)
			(stroke
				(width 0.1)
				(type default)
			)
			(layer "F.Fab")
		)
		(fp_line
			(start 1.1049 -0.724916)
			(end -1.1049 -0.724916)
			(stroke
				(width 0.1)
				(type default)
			)
			(layer "F.Fab")
		)
		(fp_line
			(start -1.1049 0.724916)
			(end 1.1049 0.724916)
			(stroke
				(width 0.1)
				(type default)
			)
			(layer "F.Fab")
		)
		(fp_line
			(start -1.1049 -0.724916)
			(end -1.1049 0.724916)
			(stroke
				(width 0.1)
				(type default)
			)
			(layer "F.Fab")
		)
		(pad "1" smd rect
			(at -0.889 0)
			(size 1.016 1.27)
			(layers "F.Cu" "F.Mask" "F.Paste")
			(net "SW_P3V3_HPDB_FLT")
		)
		(pad "2" smd rect
			(at 0.889 0)
			(size 1.016 1.27)
			(layers "F.Cu" "F.Mask" "F.Paste")
			(net "GND")
		)
	)
	(footprint ""
		(layer "F.Cu")
		(at 112.988852 -77.9272 -90)
		(property "Reference" "PR6970"
			(at 0 0 270)
			(layer "F.SilkS")
			(hide yes)
			(effects
				(font
					(size 1.27 1.27)
				)
			)
		)
		(property "Value" ""
			(at 0 0 270)
			(layer "F.Fab")
			(effects
				(font
					(size 1.27 1.27)
				)
			)
		)
		(duplicate_pad_numbers_are_jumpers no)
		(fp_line
			(start -1.2954 0.5842)
			(end -1.2954 -0.5842)
			(stroke
				(width 0.1524)
				(type default)
			)
			(layer "F.SilkS")
		)
		(fp_line
			(start 1.2954 0.5842)
			(end -1.2954 0.5842)
			(stroke
				(width 0.1524)
				(type default)
			)
			(layer "F.SilkS")
		)
		(fp_line
			(start -1.2954 -0.5842)
			(end 1.2954 -0.5842)
			(stroke
				(width 0.1524)
				(type default)
			)
			(layer "F.SilkS")
		)
		(fp_line
			(start 1.2954 -0.5842)
			(end 1.2954 0.5842)
			(stroke
				(width 0.1524)
				(type default)
			)
			(layer "F.SilkS")
		)
		(fp_line
			(start -0.8636 0.4572)
			(end -0.8636 0.4318)
			(stroke
				(width 0.1)
				(type default)
			)
			(layer "F.Fab")
		)
		(fp_line
			(start 0.8636 0.4572)
			(end -0.8636 0.4572)
			(stroke
				(width 0.1)
				(type default)
			)
			(layer "F.Fab")
		)
		(fp_line
			(start -0.8636 0.4318)
			(end -0.8636 0.4064)
			(stroke
				(width 0.1)
				(type default)
			)
			(layer "F.Fab")
		)
		(fp_line
			(start -1.1938 0.4064)
			(end -1.1938 -0.406654)
			(stroke
				(width 0.1)
				(type default)
			)
			(layer "F.Fab")
		)
		(fp_line
			(start -0.8636 0.4064)
			(end -1.1938 0.4064)
			(stroke
				(width 0.1)
				(type default)
			)
			(layer "F.Fab")
		)
		(fp_line
			(start 0.8636 0.4064)
			(end 0.8636 0.4572)
			(stroke
				(width 0.1)
				(type default)
			)
			(layer "F.Fab")
		)
		(fp_line
			(start 1.1938 0.4064)
			(end 0.8636 0.4064)
			(stroke
				(width 0.1)
				(type default)
			)
			(layer "F.Fab")
		)
		(fp_line
			(start -1.1938 -0.406654)
			(end -0.8636 -0.406654)
			(stroke
				(width 0.1)
				(type default)
			)
			(layer "F.Fab")
		)
		(fp_line
			(start -0.8636 -0.406654)
			(end -0.8636 -0.4572)
			(stroke
				(width 0.1)
				(type default)
			)
			(layer "F.Fab")
		)
		(fp_line
			(start 0.8636 -0.406654)
			(end 1.1938 -0.406654)
			(stroke
				(width 0.1)
				(type default)
			)
			(layer "F.Fab")
		)
		(fp_line
			(start 1.1938 -0.406654)
			(end 1.1938 0.4064)
			(stroke
				(width 0.1)
				(type default)
			)
			(layer "F.Fab")
		)
		(fp_line
			(start -0.8636 -0.4572)
			(end 0.8636 -0.4572)
			(stroke
				(width 0.1)
				(type default)
			)
			(layer "F.Fab")
		)
		(fp_line
			(start 0.8636 -0.4572)
			(end 0.8636 -0.406654)
			(stroke
				(width 0.1)
				(type default)
			)
			(layer "F.Fab")
		)
		(pad "1" smd rect
			(at -0.7366 0 180)
			(size 0.7112 0.8128)
			(layers "F.Cu" "F.Mask" "F.Paste")
			(net "P52V_HS2_GATE1_R")
		)
		(pad "2" smd rect
			(at 0.7366 0 180)
			(size 0.7112 0.8128)
			(layers "F.Cu" "F.Mask" "F.Paste")
			(net "P52V_HS2_GATE1")
		)
	)
	(footprint ""
		(layer "F.Cu")
		(at 278.6634 -74.041 180)
		(property "Reference" "R371"
			(at 0 0 180)
			(layer "F.SilkS")
			(hide yes)
			(effects
				(font
					(size 1.27 1.27)
				)
			)
		)
		(property "Value" ""
			(at 0 0 180)
			(layer "F.Fab")
			(effects
				(font
					(size 1.27 1.27)
				)
			)
		)
		(duplicate_pad_numbers_are_jumpers no)
		(fp_line
			(start 0.7874 0.4064)
			(end -0.7874 0.4064)
			(stroke
				(width 0.1524)
				(type default)
			)
			(layer "F.SilkS")
		)
		(fp_line
			(start 0.7874 -0.4064)
			(end 0.7874 0.4064)
			(stroke
				(width 0.1524)
				(type default)
			)
			(layer "F.SilkS")
		)
		(fp_line
			(start -0.7874 0.4064)
			(end -0.7874 -0.4064)
			(stroke
				(width 0.1524)
				(type default)
			)
			(layer "F.SilkS")
		)
		(fp_line
			(start -0.7874 -0.4064)
			(end 0.7874 -0.4064)
			(stroke
				(width 0.1524)
				(type default)
			)
			(layer "F.SilkS")
		)
		(fp_line
			(start 0.67945 0.3048)
			(end 0.120396 0.3048)
			(stroke
				(width 0.1)
				(type default)
			)
			(layer "F.Fab")
		)
		(fp_line
			(start 0.67945 -0.3048)
			(end 0.67945 0.3048)
			(stroke
				(width 0.1)
				(type default)
			)
			(layer "F.Fab")
		)
		(fp_line
			(start 0.12065 -0.2794)
			(end 0.12065 -0.3048)
			(stroke
				(width 0.1)
				(type default)
			)
			(layer "F.Fab")
		)
		(fp_line
			(start 0.12065 -0.3048)
			(end 0.67945 -0.3048)
			(stroke
				(width 0.1)
				(type default)
			)
			(layer "F.Fab")
		)
		(fp_line
			(start 0.120396 0.3048)
			(end 0.120396 0.2794)
			(stroke
				(width 0.1)
				(type default)
			)
			(layer "F.Fab")
		)
		(fp_line
			(start 0.120396 0.2794)
			(end -0.12065 0.2794)
			(stroke
				(width 0.1)
				(type default)
			)
			(layer "F.Fab")
		)
		(fp_line
			(start -0.12065 0.3048)
			(end -0.67945 0.3048)
			(stroke
				(width 0.1)
				(type default)
			)
			(layer "F.Fab")
		)
		(fp_line
			(start -0.12065 0.2794)
			(end -0.12065 0.3048)
			(stroke
				(width 0.1)
				(type default)
			)
			(layer "F.Fab")
		)
		(fp_line
			(start -0.12065 -0.2794)
			(end 0.12065 -0.2794)
			(stroke
				(width 0.1)
				(type default)
			)
			(layer "F.Fab")
		)
		(fp_line
			(start -0.12065 -0.305054)
			(end -0.12065 -0.2794)
			(stroke
				(width 0.1)
				(type default)
			)
			(layer "F.Fab")
		)
		(fp_line
			(start -0.67945 0.3048)
			(end -0.67945 -0.305054)
			(stroke
				(width 0.1)
				(type default)
			)
			(layer "F.Fab")
		)
		(fp_line
			(start -0.67945 -0.305054)
			(end -0.12065 -0.305054)
			(stroke
				(width 0.1)
				(type default)
			)
			(layer "F.Fab")
		)
		(pad "1" smd circle
			(at -0.40005 0 180)
			(size 0 0)
			(layers "F.Cu" "F.Mask" "F.Paste")
			(net "P52V_HS1_VCAP")
		)
		(pad "2" smd circle
			(at 0.40005 0 180)
			(size 0 0)
			(layers "F.Cu" "F.Mask" "F.Paste")
			(net "P52V_HS1_ADR0")
		)
	)
	(footprint ""
		(layer "F.Cu")
		(at 438.023 -45.593)
		(property "Reference" "R383"
			(at 0 0 0)
			(layer "F.SilkS")
			(hide yes)
			(effects
				(font
					(size 1.27 1.27)
				)
			)
		)
		(property "Value" ""
			(at 0 0 0)
			(layer "F.Fab")
			(effects
				(font
					(size 1.27 1.27)
				)
			)
		)
		(duplicate_pad_numbers_are_jumpers no)
		(fp_line
			(start -0.7874 -0.4064)
			(end 0.7874 -0.4064)
			(stroke
				(width 0.1524)
				(type default)
			)
			(layer "F.SilkS")
		)
		(fp_line
			(start -0.7874 0.4064)
			(end -0.7874 -0.4064)
			(stroke
				(width 0.1524)
				(type default)
			)
			(layer "F.SilkS")
		)
		(fp_line
			(start 0.7874 -0.4064)
			(end 0.7874 0.4064)
			(stroke
				(width 0.1524)
				(type default)
			)
			(layer "F.SilkS")
		)
		(fp_line
			(start 0.7874 0.4064)
			(end -0.7874 0.4064)
			(stroke
				(width 0.1524)
				(type default)
			)
			(layer "F.SilkS")
		)
		(fp_line
			(start -0.67945 -0.305054)
			(end -0.12065 -0.305054)
			(stroke
				(width 0.1)
				(type default)
			)
			(layer "F.Fab")
		)
		(fp_line
			(start -0.67945 0.3048)
			(end -0.67945 -0.305054)
			(stroke
				(width 0.1)
				(type default)
			)
			(layer "F.Fab")
		)
		(fp_line
			(start -0.12065 -0.305054)
			(end -0.12065 -0.2794)
			(stroke
				(width 0.1)
				(type default)
			)
			(layer "F.Fab")
		)
		(fp_line
			(start -0.12065 -0.2794)
			(end 0.12065 -0.2794)
			(stroke
				(width 0.1)
				(type default)
			)
			(layer "F.Fab")
		)
		(fp_line
			(start -0.12065 0.2794)
			(end -0.12065 0.3048)
			(stroke
				(width 0.1)
				(type default)
			)
			(layer "F.Fab")
		)
		(fp_line
			(start -0.12065 0.3048)
			(end -0.67945 0.3048)
			(stroke
				(width 0.1)
				(type default)
			)
			(layer "F.Fab")
		)
		(fp_line
			(start 0.120396 0.2794)
			(end -0.12065 0.2794)
			(stroke
				(width 0.1)
				(type default)
			)
			(layer "F.Fab")
		)
		(fp_line
			(start 0.120396 0.3048)
			(end 0.120396 0.2794)
			(stroke
				(width 0.1)
				(type default)
			)
			(layer "F.Fab")
		)
		(fp_line
			(start 0.12065 -0.3048)
			(end 0.67945 -0.3048)
			(stroke
				(width 0.1)
				(type default)
			)
			(layer "F.Fab")
		)
		(fp_line
			(start 0.12065 -0.2794)
			(end 0.12065 -0.3048)
			(stroke
				(width 0.1)
				(type default)
			)
			(layer "F.Fab")
		)
		(fp_line
			(start 0.67945 -0.3048)
			(end 0.67945 0.3048)
			(stroke
				(width 0.1)
				(type default)
			)
			(layer "F.Fab")
		)
		(fp_line
			(start 0.67945 0.3048)
			(end 0.120396 0.3048)
			(stroke
				(width 0.1)
				(type default)
			)
			(layer "F.Fab")
		)
		(pad "1" smd circle
			(at -0.40005 0)
			(size 0 0)
			(layers "F.Cu" "F.Mask" "F.Paste")
			(net "GND")
		)
		(pad "2" smd circle
			(at 0.40005 0)
			(size 0 0)
			(layers "F.Cu" "F.Mask" "F.Paste")
			(net "GPU_HSC_EN")
		)
	)
	(footprint ""
		(layer "F.Cu")
		(at 428.0154 -31.3436 -90)
		(property "Reference" "C9"
			(at 0 0 270)
			(layer "F.SilkS")
			(hide yes)
			(effects
				(font
					(size 1.27 1.27)
				)
			)
		)
		(property "Value" ""
			(at 0 0 270)
			(layer "F.Fab")
			(effects
				(font
					(size 1.27 1.27)
				)
			)
		)
		(duplicate_pad_numbers_are_jumpers no)
		(fp_line
			(start -0.7874 0.4064)
			(end -0.7874 -0.4064)
			(stroke
				(width 0.1524)
				(type default)
			)
			(layer "F.SilkS")
		)
		(fp_line
			(start 0.7874 0.4064)
			(end -0.7874 0.4064)
			(stroke
				(width 0.1524)
				(type default)
			)
			(layer "F.SilkS")
		)
		(fp_line
			(start -0.7874 -0.4064)
			(end 0.7874 -0.4064)
			(stroke
				(width 0.1524)
				(type default)
			)
			(layer "F.SilkS")
		)
		(fp_line
			(start 0.7874 -0.4064)
			(end 0.7874 0.4064)
			(stroke
				(width 0.1524)
				(type default)
			)
			(layer "F.SilkS")
		)
		(fp_line
			(start -0.67945 0.3048)
			(end -0.67945 -0.305054)
			(stroke
				(width 0.1)
				(type default)
			)
			(layer "F.Fab")
		)
		(fp_line
			(start -0.12065 0.3048)
			(end -0.67945 0.3048)
			(stroke
				(width 0.1)
				(type default)
			)
			(layer "F.Fab")
		)
		(fp_line
			(start 0.120396 0.3048)
			(end 0.120396 0.2794)
			(stroke
				(width 0.1)
				(type default)
			)
			(layer "F.Fab")
		)
		(fp_line
			(start 0.67945 0.3048)
			(end 0.120396 0.3048)
			(stroke
				(width 0.1)
				(type default)
			)
			(layer "F.Fab")
		)
		(fp_line
			(start -0.12065 0.2794)
			(end -0.12065 0.3048)
			(stroke
				(width 0.1)
				(type default)
			)
			(layer "F.Fab")
		)
		(fp_line
			(start 0.120396 0.2794)
			(end -0.12065 0.2794)
			(stroke
				(width 0.1)
				(type default)
			)
			(layer "F.Fab")
		)
		(fp_line
			(start -0.12065 -0.2794)
			(end 0.12065 -0.2794)
			(stroke
				(width 0.1)
				(type default)
			)
			(layer "F.Fab")
		)
		(fp_line
			(start 0.12065 -0.2794)
			(end 0.12065 -0.3048)
			(stroke
				(width 0.1)
				(type default)
			)
			(layer "F.Fab")
		)
		(fp_line
			(start 0.12065 -0.3048)
			(end 0.67945 -0.3048)
			(stroke
				(width 0.1)
				(type default)
			)
			(layer "F.Fab")
		)
		(fp_line
			(start 0.67945 -0.3048)
			(end 0.67945 0.3048)
			(stroke
				(width 0.1)
				(type default)
			)
			(layer "F.Fab")
		)
		(fp_line
			(start -0.67945 -0.305054)
			(end -0.12065 -0.305054)
			(stroke
				(width 0.1)
				(type default)
			)
			(layer "F.Fab")
		)
		(fp_line
			(start -0.12065 -0.305054)
			(end -0.12065 -0.2794)
			(stroke
				(width 0.1)
				(type default)
			)
			(layer "F.Fab")
		)
		(pad "1" smd circle
			(at -0.40005 0 270)
			(size 0 0)
			(layers "F.Cu" "F.Mask" "F.Paste")
			(net "GND")
		)
		(pad "2" smd circle
			(at 0.40005 0 270)
			(size 0 0)
			(layers "F.Cu" "F.Mask" "F.Paste")
			(net "P3V3_AUX")
		)
	)
	(footprint ""
		(layer "F.Cu")
		(at 430.276 -40.386 180)
		(property "Reference" "R133"
			(at 0 0 180)
			(layer "F.SilkS")
			(hide yes)
			(effects
				(font
					(size 1.27 1.27)
				)
			)
		)
		(property "Value" ""
			(at 0 0 180)
			(layer "F.Fab")
			(effects
				(font
					(size 1.27 1.27)
				)
			)
		)
		(duplicate_pad_numbers_are_jumpers no)
		(fp_line
			(start 0.7874 0.4064)
			(end -0.7874 0.4064)
			(stroke
				(width 0.1524)
				(type default)
			)
			(layer "F.SilkS")
		)
		(fp_line
			(start 0.7874 -0.4064)
			(end 0.7874 0.4064)
			(stroke
				(width 0.1524)
				(type default)
			)
			(layer "F.SilkS")
		)
		(fp_line
			(start -0.7874 0.4064)
			(end -0.7874 -0.4064)
			(stroke
				(width 0.1524)
				(type default)
			)
			(layer "F.SilkS")
		)
		(fp_line
			(start -0.7874 -0.4064)
			(end 0.7874 -0.4064)
			(stroke
				(width 0.1524)
				(type default)
			)
			(layer "F.SilkS")
		)
		(fp_line
			(start 0.67945 0.3048)
			(end 0.120396 0.3048)
			(stroke
				(width 0.1)
				(type default)
			)
			(layer "F.Fab")
		)
		(fp_line
			(start 0.67945 -0.3048)
			(end 0.67945 0.3048)
			(stroke
				(width 0.1)
				(type default)
			)
			(layer "F.Fab")
		)
		(fp_line
			(start 0.12065 -0.2794)
			(end 0.12065 -0.3048)
			(stroke
				(width 0.1)
				(type default)
			)
			(layer "F.Fab")
		)
		(fp_line
			(start 0.12065 -0.3048)
			(end 0.67945 -0.3048)
			(stroke
				(width 0.1)
				(type default)
			)
			(layer "F.Fab")
		)
		(fp_line
			(start 0.120396 0.3048)
			(end 0.120396 0.2794)
			(stroke
				(width 0.1)
				(type default)
			)
			(layer "F.Fab")
		)
		(fp_line
			(start 0.120396 0.2794)
			(end -0.12065 0.2794)
			(stroke
				(width 0.1)
				(type default)
			)
			(layer "F.Fab")
		)
		(fp_line
			(start -0.12065 0.3048)
			(end -0.67945 0.3048)
			(stroke
				(width 0.1)
				(type default)
			)
			(layer "F.Fab")
		)
		(fp_line
			(start -0.12065 0.2794)
			(end -0.12065 0.3048)
			(stroke
				(width 0.1)
				(type default)
			)
			(layer "F.Fab")
		)
		(fp_line
			(start -0.12065 -0.2794)
			(end 0.12065 -0.2794)
			(stroke
				(width 0.1)
				(type default)
			)
			(layer "F.Fab")
		)
		(fp_line
			(start -0.12065 -0.305054)
			(end -0.12065 -0.2794)
			(stroke
				(width 0.1)
				(type default)
			)
			(layer "F.Fab")
		)
		(fp_line
			(start -0.67945 0.3048)
			(end -0.67945 -0.305054)
			(stroke
				(width 0.1)
				(type default)
			)
			(layer "F.Fab")
		)
		(fp_line
			(start -0.67945 -0.305054)
			(end -0.12065 -0.305054)
			(stroke
				(width 0.1)
				(type default)
			)
			(layer "F.Fab")
		)
		(pad "1" smd circle
			(at -0.40005 0 180)
			(size 0 0)
			(layers "F.Cu" "F.Mask" "F.Paste")
			(net "P3V3_AUX")
		)
		(pad "2" smd circle
			(at 0.40005 0 180)
			(size 0 0)
			(layers "F.Cu" "F.Mask" "F.Paste")
			(net "BOARD_ID_2")
		)
	)
	(footprint ""
		(layer "F.Cu")
		(at 369.000024 -13.499846 180)
		(property "Reference" "H12"
			(at 1.081024 10.476484 0)
			(unlocked yes)
			(layer "F.SilkS")
			(effects
				(font
					(size 0.7874 0.5842)
					(thickness 0.1524)
				)
				(justify left)
			)
		)
		(property "Value" ""
			(at 0 0 180)
			(layer "F.Fab")
			(effects
				(font
					(size 1.27 1.27)
				)
			)
		)
		(duplicate_pad_numbers_are_jumpers no)
		(pad "1" thru_hole oval
			(at 0 0 180)
			(size 9.017 14.0208)
			(drill 3.0226
				(offset 0 2.499868)
			)
			(layers "*.Cu" "*.Mask")
			(remove_unused_layers no)
			(net "GND")
			(clearance -1.500378)
			(padstack
				(mode front_inner_back)
				(layer "Inner"
					(shape circle)
					(size 0 0)
					(clearance 0)
				)
				(layer "B.Cu"
					(shape oval)
					(size 9.017 14.0208)
					(offset 0 2.499868)
					(clearance -1.500378)
				)
			)
		)
	)
	(footprint ""
		(layer "F.Cu")
		(at 449.326 -26.543)
		(property "Reference" "R16"
			(at 0 0 0)
			(layer "F.SilkS")
			(hide yes)
			(effects
				(font
					(size 1.27 1.27)
				)
			)
		)
		(property "Value" ""
			(at 0 0 0)
			(layer "F.Fab")
			(effects
				(font
					(size 1.27 1.27)
				)
			)
		)
		(duplicate_pad_numbers_are_jumpers no)
		(fp_line
			(start -0.7874 -0.4064)
			(end 0.7874 -0.4064)
			(stroke
				(width 0.1524)
				(type default)
			)
			(layer "F.SilkS")
		)
		(fp_line
			(start -0.7874 0.4064)
			(end -0.7874 -0.4064)
			(stroke
				(width 0.1524)
				(type default)
			)
			(layer "F.SilkS")
		)
		(fp_line
			(start 0.7874 -0.4064)
			(end 0.7874 0.4064)
			(stroke
				(width 0.1524)
				(type default)
			)
			(layer "F.SilkS")
		)
		(fp_line
			(start 0.7874 0.4064)
			(end -0.7874 0.4064)
			(stroke
				(width 0.1524)
				(type default)
			)
			(layer "F.SilkS")
		)
		(fp_line
			(start -0.67945 -0.305054)
			(end -0.12065 -0.305054)
			(stroke
				(width 0.1)
				(type default)
			)
			(layer "F.Fab")
		)
		(fp_line
			(start -0.67945 0.3048)
			(end -0.67945 -0.305054)
			(stroke
				(width 0.1)
				(type default)
			)
			(layer "F.Fab")
		)
		(fp_line
			(start -0.12065 -0.305054)
			(end -0.12065 -0.2794)
			(stroke
				(width 0.1)
				(type default)
			)
			(layer "F.Fab")
		)
		(fp_line
			(start -0.12065 -0.2794)
			(end 0.12065 -0.2794)
			(stroke
				(width 0.1)
				(type default)
			)
			(layer "F.Fab")
		)
		(fp_line
			(start -0.12065 0.2794)
			(end -0.12065 0.3048)
			(stroke
				(width 0.1)
				(type default)
			)
			(layer "F.Fab")
		)
		(fp_line
			(start -0.12065 0.3048)
			(end -0.67945 0.3048)
			(stroke
				(width 0.1)
				(type default)
			)
			(layer "F.Fab")
		)
		(fp_line
			(start 0.120396 0.2794)
			(end -0.12065 0.2794)
			(stroke
				(width 0.1)
				(type default)
			)
			(layer "F.Fab")
		)
		(fp_line
			(start 0.120396 0.3048)
			(end 0.120396 0.2794)
			(stroke
				(width 0.1)
				(type default)
			)
			(layer "F.Fab")
		)
		(fp_line
			(start 0.12065 -0.3048)
			(end 0.67945 -0.3048)
			(stroke
				(width 0.1)
				(type default)
			)
			(layer "F.Fab")
		)
		(fp_line
			(start 0.12065 -0.2794)
			(end 0.12065 -0.3048)
			(stroke
				(width 0.1)
				(type default)
			)
			(layer "F.Fab")
		)
		(fp_line
			(start 0.67945 -0.3048)
			(end 0.67945 0.3048)
			(stroke
				(width 0.1)
				(type default)
			)
			(layer "F.Fab")
		)
		(fp_line
			(start 0.67945 0.3048)
			(end 0.120396 0.3048)
			(stroke
				(width 0.1)
				(type default)
			)
			(layer "F.Fab")
		)
		(pad "1" smd circle
			(at -0.40005 0)
			(size 0 0)
			(layers "F.Cu" "F.Mask" "F.Paste")
			(net "PU_9543_1_FAN")
		)
		(pad "2" smd circle
			(at 0.40005 0)
			(size 0 0)
			(layers "F.Cu" "F.Mask" "F.Paste")
			(net "P3V3_AUX")
		)
	)
	(footprint ""
		(layer "F.Cu")
		(at 451.057264 -85.870796 -90)
		(property "Reference" "PR112"
			(at 0 0 270)
			(layer "F.SilkS")
			(hide yes)
			(effects
				(font
					(size 1.27 1.27)
				)
			)
		)
		(property "Value" ""
			(at 0 0 270)
			(layer "F.Fab")
			(effects
				(font
					(size 1.27 1.27)
				)
			)
		)
		(duplicate_pad_numbers_are_jumpers no)
		(fp_line
			(start -0.7874 0.4064)
			(end -0.7874 -0.4064)
			(stroke
				(width 0.1524)
				(type default)
			)
			(layer "F.SilkS")
		)
		(fp_line
			(start 0.7874 0.4064)
			(end -0.7874 0.4064)
			(stroke
				(width 0.1524)
				(type default)
			)
			(layer "F.SilkS")
		)
		(fp_line
			(start -0.7874 -0.4064)
			(end 0.7874 -0.4064)
			(stroke
				(width 0.1524)
				(type default)
			)
			(layer "F.SilkS")
		)
		(fp_line
			(start 0.7874 -0.4064)
			(end 0.7874 0.4064)
			(stroke
				(width 0.1524)
				(type default)
			)
			(layer "F.SilkS")
		)
		(fp_line
			(start -0.67945 0.3048)
			(end -0.67945 -0.305054)
			(stroke
				(width 0.1)
				(type default)
			)
			(layer "F.Fab")
		)
		(fp_line
			(start -0.12065 0.3048)
			(end -0.67945 0.3048)
			(stroke
				(width 0.1)
				(type default)
			)
			(layer "F.Fab")
		)
		(fp_line
			(start 0.120396 0.3048)
			(end 0.120396 0.2794)
			(stroke
				(width 0.1)
				(type default)
			)
			(layer "F.Fab")
		)
		(fp_line
			(start 0.67945 0.3048)
			(end 0.120396 0.3048)
			(stroke
				(width 0.1)
				(type default)
			)
			(layer "F.Fab")
		)
		(fp_line
			(start -0.12065 0.2794)
			(end -0.12065 0.3048)
			(stroke
				(width 0.1)
				(type default)
			)
			(layer "F.Fab")
		)
		(fp_line
			(start 0.120396 0.2794)
			(end -0.12065 0.2794)
			(stroke
				(width 0.1)
				(type default)
			)
			(layer "F.Fab")
		)
		(fp_line
			(start -0.12065 -0.2794)
			(end 0.12065 -0.2794)
			(stroke
				(width 0.1)
				(type default)
			)
			(layer "F.Fab")
		)
		(fp_line
			(start 0.12065 -0.2794)
			(end 0.12065 -0.3048)
			(stroke
				(width 0.1)
				(type default)
			)
			(layer "F.Fab")
		)
		(fp_line
			(start 0.12065 -0.3048)
			(end 0.67945 -0.3048)
			(stroke
				(width 0.1)
				(type default)
			)
			(layer "F.Fab")
		)
		(fp_line
			(start 0.67945 -0.3048)
			(end 0.67945 0.3048)
			(stroke
				(width 0.1)
				(type default)
			)
			(layer "F.Fab")
		)
		(fp_line
			(start -0.67945 -0.305054)
			(end -0.12065 -0.305054)
			(stroke
				(width 0.1)
				(type default)
			)
			(layer "F.Fab")
		)
		(fp_line
			(start -0.12065 -0.305054)
			(end -0.12065 -0.2794)
			(stroke
				(width 0.1)
				(type default)
			)
			(layer "F.Fab")
		)
		(pad "1" smd circle
			(at -0.40005 0 270)
			(size 0 0)
			(layers "F.Cu" "F.Mask" "F.Paste")
			(net "P3V3_HPDB_FB")
		)
		(pad "2" smd circle
			(at 0.40005 0 270)
			(size 0 0)
			(layers "F.Cu" "F.Mask" "F.Paste")
			(net "P3V3_AUX")
		)
	)
	(footprint ""
		(layer "F.Cu")
		(at 448.056 -37.211 90)
		(property "Reference" "R14"
			(at 0 0 90)
			(layer "F.SilkS")
			(hide yes)
			(effects
				(font
					(size 1.27 1.27)
				)
			)
		)
		(property "Value" ""
			(at 0 0 90)
			(layer "F.Fab")
			(effects
				(font
					(size 1.27 1.27)
				)
			)
		)
		(duplicate_pad_numbers_are_jumpers no)
		(fp_line
			(start 0.7874 -0.4064)
			(end 0.7874 0.4064)
			(stroke
				(width 0.1524)
				(type default)
			)
			(layer "F.SilkS")
		)
		(fp_line
			(start -0.7874 -0.4064)
			(end 0.7874 -0.4064)
			(stroke
				(width 0.1524)
				(type default)
			)
			(layer "F.SilkS")
		)
		(fp_line
			(start 0.7874 0.4064)
			(end -0.7874 0.4064)
			(stroke
				(width 0.1524)
				(type default)
			)
			(layer "F.SilkS")
		)
		(fp_line
			(start -0.7874 0.4064)
			(end -0.7874 -0.4064)
			(stroke
				(width 0.1524)
				(type default)
			)
			(layer "F.SilkS")
		)
		(fp_line
			(start -0.12065 -0.305054)
			(end -0.12065 -0.2794)
			(stroke
				(width 0.1)
				(type default)
			)
			(layer "F.Fab")
		)
		(fp_line
			(start -0.67945 -0.305054)
			(end -0.12065 -0.305054)
			(stroke
				(width 0.1)
				(type default)
			)
			(layer "F.Fab")
		)
		(fp_line
			(start 0.67945 -0.3048)
			(end 0.67945 0.3048)
			(stroke
				(width 0.1)
				(type default)
			)
			(layer "F.Fab")
		)
		(fp_line
			(start 0.12065 -0.3048)
			(end 0.67945 -0.3048)
			(stroke
				(width 0.1)
				(type default)
			)
			(layer "F.Fab")
		)
		(fp_line
			(start 0.12065 -0.2794)
			(end 0.12065 -0.3048)
			(stroke
				(width 0.1)
				(type default)
			)
			(layer "F.Fab")
		)
		(fp_line
			(start -0.12065 -0.2794)
			(end 0.12065 -0.2794)
			(stroke
				(width 0.1)
				(type default)
			)
			(layer "F.Fab")
		)
		(fp_line
			(start 0.120396 0.2794)
			(end -0.12065 0.2794)
			(stroke
				(width 0.1)
				(type default)
			)
			(layer "F.Fab")
		)
		(fp_line
			(start -0.12065 0.2794)
			(end -0.12065 0.3048)
			(stroke
				(width 0.1)
				(type default)
			)
			(layer "F.Fab")
		)
		(fp_line
			(start 0.67945 0.3048)
			(end 0.120396 0.3048)
			(stroke
				(width 0.1)
				(type default)
			)
			(layer "F.Fab")
		)
		(fp_line
			(start 0.120396 0.3048)
			(end 0.120396 0.2794)
			(stroke
				(width 0.1)
				(type default)
			)
			(layer "F.Fab")
		)
		(fp_line
			(start -0.12065 0.3048)
			(end -0.67945 0.3048)
			(stroke
				(width 0.1)
				(type default)
			)
			(layer "F.Fab")
		)
		(fp_line
			(start -0.67945 0.3048)
			(end -0.67945 -0.305054)
			(stroke
				(width 0.1)
				(type default)
			)
			(layer "F.Fab")
		)
		(pad "1" smd circle
			(at -0.40005 0 90)
			(size 0 0)
			(layers "F.Cu" "F.Mask" "F.Paste")
			(net "SMB_P52V_SDA")
		)
		(pad "2" smd circle
			(at 0.40005 0 90)
			(size 0 0)
			(layers "F.Cu" "F.Mask" "F.Paste")
			(net "SMB_P52V_PDB_SDA_R")
		)
	)
	(footprint ""
		(layer "F.Cu")
		(at 397.637 -78.74)
		(property "Reference" "PC41"
			(at -8.6106 -4.79933 0)
			(unlocked yes)
			(layer "F.SilkS")
			(effects
				(font
					(size 0.7874 0.5842)
					(thickness 0.1524)
				)
				(justify left)
			)
		)
		(property "Value" ""
			(at 0 0 0)
			(layer "F.Fab")
			(effects
				(font
					(size 1.27 1.27)
				)
			)
		)
		(duplicate_pad_numbers_are_jumpers no)
		(fp_line
			(start -9.253728 3.750056)
			(end 9.249918 3.750056)
			(stroke
				(width 0.1524)
				(type default)
			)
			(layer "F.SilkS")
		)
		(fp_line
			(start 0 3.750056)
			(end -9.253728 3.750056)
			(stroke
				(width 0.1524)
				(type default)
			)
			(layer "F.SilkS")
		)
		(fp_circle
			(center 0 3.750056)
			(end 9.249918 3.750056)
			(stroke
				(width 0.1524)
				(type default)
			)
			(fill no)
			(layer "F.SilkS")
		)
		(fp_poly
			(pts
				(arc
					(start 9.249918 3.750056)
					(mid 0 12.999974)
					(end -9.249918 3.750056)
				)
			)
			(stroke
				(width 0)
				(type default)
			)
			(fill yes)
			(layer "F.SilkS")
		)
		(fp_circle
			(center 0 3.750056)
			(end 9.249918 3.750056)
			(stroke
				(width 0.1)
				(type default)
			)
			(fill no)
			(layer "F.Fab")
		)
		(pad "1" thru_hole rect
			(at 0 0)
			(size 1.778 1.778)
			(drill 1.27)
			(layers "*.Cu" "*.Mask")
			(remove_unused_layers no)
			(net "P52V_HS1")
			(clearance 0)
			(padstack
				(mode front_inner_back)
				(layer "Inner"
					(shape circle)
					(size 1.778 1.778)
					(clearance 0)
				)
				(layer "B.Cu"
					(shape rect)
					(size 1.778 1.778)
					(clearance 0)
				)
			)
		)
		(pad "2" thru_hole circle
			(at 0 7.500112)
			(size 1.778 1.778)
			(drill 1.27)
			(layers "*.Cu" "*.Mask")
			(remove_unused_layers no)
			(net "GND")
			(clearance 0)
		)
	)
	(footprint ""
		(layer "F.Cu")
		(at 281.0764 -74.041)
		(property "Reference" "R373"
			(at 0 0 0)
			(layer "F.SilkS")
			(hide yes)
			(effects
				(font
					(size 1.27 1.27)
				)
			)
		)
		(property "Value" ""
			(at 0 0 0)
			(layer "F.Fab")
			(effects
				(font
					(size 1.27 1.27)
				)
			)
		)
		(duplicate_pad_numbers_are_jumpers no)
		(fp_line
			(start -0.7874 -0.4064)
			(end 0.7874 -0.4064)
			(stroke
				(width 0.1524)
				(type default)
			)
			(layer "F.SilkS")
		)
		(fp_line
			(start -0.7874 0.4064)
			(end -0.7874 -0.4064)
			(stroke
				(width 0.1524)
				(type default)
			)
			(layer "F.SilkS")
		)
		(fp_line
			(start 0.7874 -0.4064)
			(end 0.7874 0.4064)
			(stroke
				(width 0.1524)
				(type default)
			)
			(layer "F.SilkS")
		)
		(fp_line
			(start 0.7874 0.4064)
			(end -0.7874 0.4064)
			(stroke
				(width 0.1524)
				(type default)
			)
			(layer "F.SilkS")
		)
		(fp_line
			(start -0.67945 -0.305054)
			(end -0.12065 -0.305054)
			(stroke
				(width 0.1)
				(type default)
			)
			(layer "F.Fab")
		)
		(fp_line
			(start -0.67945 0.3048)
			(end -0.67945 -0.305054)
			(stroke
				(width 0.1)
				(type default)
			)
			(layer "F.Fab")
		)
		(fp_line
			(start -0.12065 -0.305054)
			(end -0.12065 -0.2794)
			(stroke
				(width 0.1)
				(type default)
			)
			(layer "F.Fab")
		)
		(fp_line
			(start -0.12065 -0.2794)
			(end 0.12065 -0.2794)
			(stroke
				(width 0.1)
				(type default)
			)
			(layer "F.Fab")
		)
		(fp_line
			(start -0.12065 0.2794)
			(end -0.12065 0.3048)
			(stroke
				(width 0.1)
				(type default)
			)
			(layer "F.Fab")
		)
		(fp_line
			(start -0.12065 0.3048)
			(end -0.67945 0.3048)
			(stroke
				(width 0.1)
				(type default)
			)
			(layer "F.Fab")
		)
		(fp_line
			(start 0.120396 0.2794)
			(end -0.12065 0.2794)
			(stroke
				(width 0.1)
				(type default)
			)
			(layer "F.Fab")
		)
		(fp_line
			(start 0.120396 0.3048)
			(end 0.120396 0.2794)
			(stroke
				(width 0.1)
				(type default)
			)
			(layer "F.Fab")
		)
		(fp_line
			(start 0.12065 -0.3048)
			(end 0.67945 -0.3048)
			(stroke
				(width 0.1)
				(type default)
			)
			(layer "F.Fab")
		)
		(fp_line
			(start 0.12065 -0.2794)
			(end 0.12065 -0.3048)
			(stroke
				(width 0.1)
				(type default)
			)
			(layer "F.Fab")
		)
		(fp_line
			(start 0.67945 -0.3048)
			(end 0.67945 0.3048)
			(stroke
				(width 0.1)
				(type default)
			)
			(layer "F.Fab")
		)
		(fp_line
			(start 0.67945 0.3048)
			(end 0.120396 0.3048)
			(stroke
				(width 0.1)
				(type default)
			)
			(layer "F.Fab")
		)
		(pad "1" smd circle
			(at -0.40005 0)
			(size 0 0)
			(layers "F.Cu" "F.Mask" "F.Paste")
			(net "P52V_HS1_ADR0")
		)
		(pad "2" smd circle
			(at 0.40005 0)
			(size 0 0)
			(layers "F.Cu" "F.Mask" "F.Paste")
			(net "GND_FIELD_SIGNAL")
		)
	)
	(footprint ""
		(layer "F.Cu")
		(at 444.373 -50.927)
		(property "Reference" "R5900"
			(at 0 0 0)
			(layer "F.SilkS")
			(hide yes)
			(effects
				(font
					(size 1.27 1.27)
				)
			)
		)
		(property "Value" ""
			(at 0 0 0)
			(layer "F.Fab")
			(effects
				(font
					(size 1.27 1.27)
				)
			)
		)
		(duplicate_pad_numbers_are_jumpers no)
		(fp_line
			(start -0.7874 -0.4064)
			(end 0.7874 -0.4064)
			(stroke
				(width 0.1524)
				(type default)
			)
			(layer "F.SilkS")
		)
		(fp_line
			(start -0.7874 0.4064)
			(end -0.7874 -0.4064)
			(stroke
				(width 0.1524)
				(type default)
			)
			(layer "F.SilkS")
		)
		(fp_line
			(start 0.7874 -0.4064)
			(end 0.7874 0.4064)
			(stroke
				(width 0.1524)
				(type default)
			)
			(layer "F.SilkS")
		)
		(fp_line
			(start 0.7874 0.4064)
			(end -0.7874 0.4064)
			(stroke
				(width 0.1524)
				(type default)
			)
			(layer "F.SilkS")
		)
		(fp_line
			(start -0.67945 -0.305054)
			(end -0.12065 -0.305054)
			(stroke
				(width 0.1)
				(type default)
			)
			(layer "F.Fab")
		)
		(fp_line
			(start -0.67945 0.3048)
			(end -0.67945 -0.305054)
			(stroke
				(width 0.1)
				(type default)
			)
			(layer "F.Fab")
		)
		(fp_line
			(start -0.12065 -0.305054)
			(end -0.12065 -0.2794)
			(stroke
				(width 0.1)
				(type default)
			)
			(layer "F.Fab")
		)
		(fp_line
			(start -0.12065 -0.2794)
			(end 0.12065 -0.2794)
			(stroke
				(width 0.1)
				(type default)
			)
			(layer "F.Fab")
		)
		(fp_line
			(start -0.12065 0.2794)
			(end -0.12065 0.3048)
			(stroke
				(width 0.1)
				(type default)
			)
			(layer "F.Fab")
		)
		(fp_line
			(start -0.12065 0.3048)
			(end -0.67945 0.3048)
			(stroke
				(width 0.1)
				(type default)
			)
			(layer "F.Fab")
		)
		(fp_line
			(start 0.120396 0.2794)
			(end -0.12065 0.2794)
			(stroke
				(width 0.1)
				(type default)
			)
			(layer "F.Fab")
		)
		(fp_line
			(start 0.120396 0.3048)
			(end 0.120396 0.2794)
			(stroke
				(width 0.1)
				(type default)
			)
			(layer "F.Fab")
		)
		(fp_line
			(start 0.12065 -0.3048)
			(end 0.67945 -0.3048)
			(stroke
				(width 0.1)
				(type default)
			)
			(layer "F.Fab")
		)
		(fp_line
			(start 0.12065 -0.2794)
			(end 0.12065 -0.3048)
			(stroke
				(width 0.1)
				(type default)
			)
			(layer "F.Fab")
		)
		(fp_line
			(start 0.67945 -0.3048)
			(end 0.67945 0.3048)
			(stroke
				(width 0.1)
				(type default)
			)
			(layer "F.Fab")
		)
		(fp_line
			(start 0.67945 0.3048)
			(end 0.120396 0.3048)
			(stroke
				(width 0.1)
				(type default)
			)
			(layer "F.Fab")
		)
		(pad "1" smd circle
			(at -0.40005 0)
			(size 0 0)
			(layers "F.Cu" "F.Mask" "F.Paste")
			(net "P3V3_HPDB_PG_R")
		)
		(pad "2" smd circle
			(at 0.40005 0)
			(size 0 0)
			(layers "F.Cu" "F.Mask" "F.Paste")
			(net "P3V3_HPDB_PG")
		)
	)
	(footprint ""
		(layer "F.Cu")
		(at 430.276 -47.371 180)
		(property "Reference" "R50"
			(at 0 0 180)
			(layer "F.SilkS")
			(hide yes)
			(effects
				(font
					(size 1.27 1.27)
				)
			)
		)
		(property "Value" ""
			(at 0 0 180)
			(layer "F.Fab")
			(effects
				(font
					(size 1.27 1.27)
				)
			)
		)
		(duplicate_pad_numbers_are_jumpers no)
		(fp_line
			(start 0.7874 0.4064)
			(end -0.7874 0.4064)
			(stroke
				(width 0.1524)
				(type default)
			)
			(layer "F.SilkS")
		)
		(fp_line
			(start 0.7874 -0.4064)
			(end 0.7874 0.4064)
			(stroke
				(width 0.1524)
				(type default)
			)
			(layer "F.SilkS")
		)
		(fp_line
			(start -0.7874 0.4064)
			(end -0.7874 -0.4064)
			(stroke
				(width 0.1524)
				(type default)
			)
			(layer "F.SilkS")
		)
		(fp_line
			(start -0.7874 -0.4064)
			(end 0.7874 -0.4064)
			(stroke
				(width 0.1524)
				(type default)
			)
			(layer "F.SilkS")
		)
		(fp_line
			(start 0.67945 0.3048)
			(end 0.120396 0.3048)
			(stroke
				(width 0.1)
				(type default)
			)
			(layer "F.Fab")
		)
		(fp_line
			(start 0.67945 -0.3048)
			(end 0.67945 0.3048)
			(stroke
				(width 0.1)
				(type default)
			)
			(layer "F.Fab")
		)
		(fp_line
			(start 0.12065 -0.2794)
			(end 0.12065 -0.3048)
			(stroke
				(width 0.1)
				(type default)
			)
			(layer "F.Fab")
		)
		(fp_line
			(start 0.12065 -0.3048)
			(end 0.67945 -0.3048)
			(stroke
				(width 0.1)
				(type default)
			)
			(layer "F.Fab")
		)
		(fp_line
			(start 0.120396 0.3048)
			(end 0.120396 0.2794)
			(stroke
				(width 0.1)
				(type default)
			)
			(layer "F.Fab")
		)
		(fp_line
			(start 0.120396 0.2794)
			(end -0.12065 0.2794)
			(stroke
				(width 0.1)
				(type default)
			)
			(layer "F.Fab")
		)
		(fp_line
			(start -0.12065 0.3048)
			(end -0.67945 0.3048)
			(stroke
				(width 0.1)
				(type default)
			)
			(layer "F.Fab")
		)
		(fp_line
			(start -0.12065 0.2794)
			(end -0.12065 0.3048)
			(stroke
				(width 0.1)
				(type default)
			)
			(layer "F.Fab")
		)
		(fp_line
			(start -0.12065 -0.2794)
			(end 0.12065 -0.2794)
			(stroke
				(width 0.1)
				(type default)
			)
			(layer "F.Fab")
		)
		(fp_line
			(start -0.12065 -0.305054)
			(end -0.12065 -0.2794)
			(stroke
				(width 0.1)
				(type default)
			)
			(layer "F.Fab")
		)
		(fp_line
			(start -0.67945 0.3048)
			(end -0.67945 -0.305054)
			(stroke
				(width 0.1)
				(type default)
			)
			(layer "F.Fab")
		)
		(fp_line
			(start -0.67945 -0.305054)
			(end -0.12065 -0.305054)
			(stroke
				(width 0.1)
				(type default)
			)
			(layer "F.Fab")
		)
		(pad "1" smd circle
			(at -0.40005 0 180)
			(size 0 0)
			(layers "F.Cu" "F.Mask" "F.Paste")
			(net "SMB_PDB_MISC_SCL")
		)
		(pad "2" smd circle
			(at 0.40005 0 180)
			(size 0 0)
			(layers "F.Cu" "F.Mask" "F.Paste")
			(net "SMB_IOEXP_SCL")
		)
	)
	(footprint ""
		(layer "F.Cu")
		(at 431.8 -137.500106 180)
		(property "Reference" "H20"
			(at -1.8415 -6.094476 0)
			(unlocked yes)
			(layer "F.SilkS")
			(effects
				(font
					(size 0.7874 0.5842)
					(thickness 0.1524)
				)
				(justify left)
			)
		)
		(property "Value" ""
			(at 0 0 180)
			(layer "F.Fab")
			(effects
				(font
					(size 1.27 1.27)
				)
			)
		)
		(duplicate_pad_numbers_are_jumpers no)
		(pad "1" thru_hole circle
			(at 0 0 180)
			(size 10.16 10.16)
			(drill 6.4008
				(offset 0 0)
			)
			(layers "*.Cu" "*.Mask")
			(remove_unused_layers no)
			(net "GND")
			(clearance -1.6256)
			(padstack
				(mode front_inner_back)
				(layer "Inner"
					(shape circle)
					(size 10.16 10.16)
					(clearance -1.6256)
				)
				(layer "B.Cu"
					(shape oval)
					(size 10.0076 17.018)
					(offset 0 3.499866)
					(clearance -1.5494)
				)
			)
		)
	)
	(footprint ""
		(layer "F.Cu")
		(at 165.989 -83.439 90)
		(property "Reference" "C106"
			(at 0 0 90)
			(layer "F.SilkS")
			(hide yes)
			(effects
				(font
					(size 1.27 1.27)
				)
			)
		)
		(property "Value" ""
			(at 0 0 90)
			(layer "F.Fab")
			(effects
				(font
					(size 1.27 1.27)
				)
			)
		)
		(duplicate_pad_numbers_are_jumpers no)
		(fp_line
			(start 0.7874 -0.4064)
			(end 0.7874 0.4064)
			(stroke
				(width 0.1524)
				(type default)
			)
			(layer "F.SilkS")
		)
		(fp_line
			(start -0.7874 -0.4064)
			(end 0.7874 -0.4064)
			(stroke
				(width 0.1524)
				(type default)
			)
			(layer "F.SilkS")
		)
		(fp_line
			(start 0.7874 0.4064)
			(end -0.7874 0.4064)
			(stroke
				(width 0.1524)
				(type default)
			)
			(layer "F.SilkS")
		)
		(fp_line
			(start -0.7874 0.4064)
			(end -0.7874 -0.4064)
			(stroke
				(width 0.1524)
				(type default)
			)
			(layer "F.SilkS")
		)
		(fp_line
			(start -0.12065 -0.305054)
			(end -0.12065 -0.2794)
			(stroke
				(width 0.1)
				(type default)
			)
			(layer "F.Fab")
		)
		(fp_line
			(start -0.67945 -0.305054)
			(end -0.12065 -0.305054)
			(stroke
				(width 0.1)
				(type default)
			)
			(layer "F.Fab")
		)
		(fp_line
			(start 0.67945 -0.3048)
			(end 0.67945 0.3048)
			(stroke
				(width 0.1)
				(type default)
			)
			(layer "F.Fab")
		)
		(fp_line
			(start 0.12065 -0.3048)
			(end 0.67945 -0.3048)
			(stroke
				(width 0.1)
				(type default)
			)
			(layer "F.Fab")
		)
		(fp_line
			(start 0.12065 -0.2794)
			(end 0.12065 -0.3048)
			(stroke
				(width 0.1)
				(type default)
			)
			(layer "F.Fab")
		)
		(fp_line
			(start -0.12065 -0.2794)
			(end 0.12065 -0.2794)
			(stroke
				(width 0.1)
				(type default)
			)
			(layer "F.Fab")
		)
		(fp_line
			(start 0.120396 0.2794)
			(end -0.12065 0.2794)
			(stroke
				(width 0.1)
				(type default)
			)
			(layer "F.Fab")
		)
		(fp_line
			(start -0.12065 0.2794)
			(end -0.12065 0.3048)
			(stroke
				(width 0.1)
				(type default)
			)
			(layer "F.Fab")
		)
		(fp_line
			(start 0.67945 0.3048)
			(end 0.120396 0.3048)
			(stroke
				(width 0.1)
				(type default)
			)
			(layer "F.Fab")
		)
		(fp_line
			(start 0.120396 0.3048)
			(end 0.120396 0.2794)
			(stroke
				(width 0.1)
				(type default)
			)
			(layer "F.Fab")
		)
		(fp_line
			(start -0.12065 0.3048)
			(end -0.67945 0.3048)
			(stroke
				(width 0.1)
				(type default)
			)
			(layer "F.Fab")
		)
		(fp_line
			(start -0.67945 0.3048)
			(end -0.67945 -0.305054)
			(stroke
				(width 0.1)
				(type default)
			)
			(layer "F.Fab")
		)
		(pad "1" smd circle
			(at -0.40005 0 90)
			(size 0 0)
			(layers "F.Cu" "F.Mask" "F.Paste")
			(net "GND")
		)
		(pad "2" smd circle
			(at 0.40005 0 90)
			(size 0 0)
			(layers "F.Cu" "F.Mask" "F.Paste")
			(net "P3V3_AUX")
		)
	)
	(footprint ""
		(layer "F.Cu")
		(at 452.073264 -85.870796 -90)
		(property "Reference" "PC54"
			(at 0 0 270)
			(layer "F.SilkS")
			(hide yes)
			(effects
				(font
					(size 1.27 1.27)
				)
			)
		)
		(property "Value" ""
			(at 0 0 270)
			(layer "F.Fab")
			(effects
				(font
					(size 1.27 1.27)
				)
			)
		)
		(duplicate_pad_numbers_are_jumpers no)
		(fp_line
			(start -0.7874 0.4064)
			(end -0.7874 -0.4064)
			(stroke
				(width 0.1524)
				(type default)
			)
			(layer "F.SilkS")
		)
		(fp_line
			(start 0.7874 0.4064)
			(end -0.7874 0.4064)
			(stroke
				(width 0.1524)
				(type default)
			)
			(layer "F.SilkS")
		)
		(fp_line
			(start -0.7874 -0.4064)
			(end 0.7874 -0.4064)
			(stroke
				(width 0.1524)
				(type default)
			)
			(layer "F.SilkS")
		)
		(fp_line
			(start 0.7874 -0.4064)
			(end 0.7874 0.4064)
			(stroke
				(width 0.1524)
				(type default)
			)
			(layer "F.SilkS")
		)
		(fp_line
			(start -0.67945 0.3048)
			(end -0.67945 -0.305054)
			(stroke
				(width 0.1)
				(type default)
			)
			(layer "F.Fab")
		)
		(fp_line
			(start -0.12065 0.3048)
			(end -0.67945 0.3048)
			(stroke
				(width 0.1)
				(type default)
			)
			(layer "F.Fab")
		)
		(fp_line
			(start 0.120396 0.3048)
			(end 0.120396 0.2794)
			(stroke
				(width 0.1)
				(type default)
			)
			(layer "F.Fab")
		)
		(fp_line
			(start 0.67945 0.3048)
			(end 0.120396 0.3048)
			(stroke
				(width 0.1)
				(type default)
			)
			(layer "F.Fab")
		)
		(fp_line
			(start -0.12065 0.2794)
			(end -0.12065 0.3048)
			(stroke
				(width 0.1)
				(type default)
			)
			(layer "F.Fab")
		)
		(fp_line
			(start 0.120396 0.2794)
			(end -0.12065 0.2794)
			(stroke
				(width 0.1)
				(type default)
			)
			(layer "F.Fab")
		)
		(fp_line
			(start -0.12065 -0.2794)
			(end 0.12065 -0.2794)
			(stroke
				(width 0.1)
				(type default)
			)
			(layer "F.Fab")
		)
		(fp_line
			(start 0.12065 -0.2794)
			(end 0.12065 -0.3048)
			(stroke
				(width 0.1)
				(type default)
			)
			(layer "F.Fab")
		)
		(fp_line
			(start 0.12065 -0.3048)
			(end 0.67945 -0.3048)
			(stroke
				(width 0.1)
				(type default)
			)
			(layer "F.Fab")
		)
		(fp_line
			(start 0.67945 -0.3048)
			(end 0.67945 0.3048)
			(stroke
				(width 0.1)
				(type default)
			)
			(layer "F.Fab")
		)
		(fp_line
			(start -0.67945 -0.305054)
			(end -0.12065 -0.305054)
			(stroke
				(width 0.1)
				(type default)
			)
			(layer "F.Fab")
		)
		(fp_line
			(start -0.12065 -0.305054)
			(end -0.12065 -0.2794)
			(stroke
				(width 0.1)
				(type default)
			)
			(layer "F.Fab")
		)
		(pad "1" smd circle
			(at -0.40005 0 270)
			(size 0 0)
			(layers "F.Cu" "F.Mask" "F.Paste")
			(net "P3V3_HPDB_FB")
		)
		(pad "2" smd circle
			(at 0.40005 0 270)
			(size 0 0)
			(layers "F.Cu" "F.Mask" "F.Paste")
			(net "P3V3_AUX")
		)
	)
	(footprint ""
		(layer "F.Cu")
		(at 283.6164 -75.184)
		(property "Reference" "PC12"
			(at 0 0 0)
			(layer "F.SilkS")
			(hide yes)
			(effects
				(font
					(size 1.27 1.27)
				)
			)
		)
		(property "Value" ""
			(at 0 0 0)
			(layer "F.Fab")
			(effects
				(font
					(size 1.27 1.27)
				)
			)
		)
		(duplicate_pad_numbers_are_jumpers no)
		(fp_line
			(start -0.7874 -0.4064)
			(end 0.7874 -0.4064)
			(stroke
				(width 0.1524)
				(type default)
			)
			(layer "F.SilkS")
		)
		(fp_line
			(start -0.7874 0.4064)
			(end -0.7874 -0.4064)
			(stroke
				(width 0.1524)
				(type default)
			)
			(layer "F.SilkS")
		)
		(fp_line
			(start 0.7874 -0.4064)
			(end 0.7874 0.4064)
			(stroke
				(width 0.1524)
				(type default)
			)
			(layer "F.SilkS")
		)
		(fp_line
			(start 0.7874 0.4064)
			(end -0.7874 0.4064)
			(stroke
				(width 0.1524)
				(type default)
			)
			(layer "F.SilkS")
		)
		(fp_line
			(start -0.67945 -0.305054)
			(end -0.12065 -0.305054)
			(stroke
				(width 0.1)
				(type default)
			)
			(layer "F.Fab")
		)
		(fp_line
			(start -0.67945 0.3048)
			(end -0.67945 -0.305054)
			(stroke
				(width 0.1)
				(type default)
			)
			(layer "F.Fab")
		)
		(fp_line
			(start -0.12065 -0.305054)
			(end -0.12065 -0.2794)
			(stroke
				(width 0.1)
				(type default)
			)
			(layer "F.Fab")
		)
		(fp_line
			(start -0.12065 -0.2794)
			(end 0.12065 -0.2794)
			(stroke
				(width 0.1)
				(type default)
			)
			(layer "F.Fab")
		)
		(fp_line
			(start -0.12065 0.2794)
			(end -0.12065 0.3048)
			(stroke
				(width 0.1)
				(type default)
			)
			(layer "F.Fab")
		)
		(fp_line
			(start -0.12065 0.3048)
			(end -0.67945 0.3048)
			(stroke
				(width 0.1)
				(type default)
			)
			(layer "F.Fab")
		)
		(fp_line
			(start 0.120396 0.2794)
			(end -0.12065 0.2794)
			(stroke
				(width 0.1)
				(type default)
			)
			(layer "F.Fab")
		)
		(fp_line
			(start 0.120396 0.3048)
			(end 0.120396 0.2794)
			(stroke
				(width 0.1)
				(type default)
			)
			(layer "F.Fab")
		)
		(fp_line
			(start 0.12065 -0.3048)
			(end 0.67945 -0.3048)
			(stroke
				(width 0.1)
				(type default)
			)
			(layer "F.Fab")
		)
		(fp_line
			(start 0.12065 -0.2794)
			(end 0.12065 -0.3048)
			(stroke
				(width 0.1)
				(type default)
			)
			(layer "F.Fab")
		)
		(fp_line
			(start 0.67945 -0.3048)
			(end 0.67945 0.3048)
			(stroke
				(width 0.1)
				(type default)
			)
			(layer "F.Fab")
		)
		(fp_line
			(start 0.67945 0.3048)
			(end 0.120396 0.3048)
			(stroke
				(width 0.1)
				(type default)
			)
			(layer "F.Fab")
		)
		(pad "1" smd circle
			(at -0.40005 0)
			(size 0 0)
			(layers "F.Cu" "F.Mask" "F.Paste")
			(net "P52V_HS1_EFAULT")
		)
		(pad "2" smd circle
			(at 0.40005 0)
			(size 0 0)
			(layers "F.Cu" "F.Mask" "F.Paste")
			(net "GND_FIELD_SIGNAL")
		)
	)
	(footprint ""
		(layer "F.Cu")
		(at 409.956 -43.942)
		(property "Reference" "R51"
			(at 0 0 0)
			(layer "F.SilkS")
			(hide yes)
			(effects
				(font
					(size 1.27 1.27)
				)
			)
		)
		(property "Value" ""
			(at 0 0 0)
			(layer "F.Fab")
			(effects
				(font
					(size 1.27 1.27)
				)
			)
		)
		(duplicate_pad_numbers_are_jumpers no)
		(fp_line
			(start -0.7874 -0.4064)
			(end 0.7874 -0.4064)
			(stroke
				(width 0.1524)
				(type default)
			)
			(layer "F.SilkS")
		)
		(fp_line
			(start -0.7874 0.4064)
			(end -0.7874 -0.4064)
			(stroke
				(width 0.1524)
				(type default)
			)
			(layer "F.SilkS")
		)
		(fp_line
			(start 0.7874 -0.4064)
			(end 0.7874 0.4064)
			(stroke
				(width 0.1524)
				(type default)
			)
			(layer "F.SilkS")
		)
		(fp_line
			(start 0.7874 0.4064)
			(end -0.7874 0.4064)
			(stroke
				(width 0.1524)
				(type default)
			)
			(layer "F.SilkS")
		)
		(fp_line
			(start -0.67945 -0.305054)
			(end -0.12065 -0.305054)
			(stroke
				(width 0.1)
				(type default)
			)
			(layer "F.Fab")
		)
		(fp_line
			(start -0.67945 0.3048)
			(end -0.67945 -0.305054)
			(stroke
				(width 0.1)
				(type default)
			)
			(layer "F.Fab")
		)
		(fp_line
			(start -0.12065 -0.305054)
			(end -0.12065 -0.2794)
			(stroke
				(width 0.1)
				(type default)
			)
			(layer "F.Fab")
		)
		(fp_line
			(start -0.12065 -0.2794)
			(end 0.12065 -0.2794)
			(stroke
				(width 0.1)
				(type default)
			)
			(layer "F.Fab")
		)
		(fp_line
			(start -0.12065 0.2794)
			(end -0.12065 0.3048)
			(stroke
				(width 0.1)
				(type default)
			)
			(layer "F.Fab")
		)
		(fp_line
			(start -0.12065 0.3048)
			(end -0.67945 0.3048)
			(stroke
				(width 0.1)
				(type default)
			)
			(layer "F.Fab")
		)
		(fp_line
			(start 0.120396 0.2794)
			(end -0.12065 0.2794)
			(stroke
				(width 0.1)
				(type default)
			)
			(layer "F.Fab")
		)
		(fp_line
			(start 0.120396 0.3048)
			(end 0.120396 0.2794)
			(stroke
				(width 0.1)
				(type default)
			)
			(layer "F.Fab")
		)
		(fp_line
			(start 0.12065 -0.3048)
			(end 0.67945 -0.3048)
			(stroke
				(width 0.1)
				(type default)
			)
			(layer "F.Fab")
		)
		(fp_line
			(start 0.12065 -0.2794)
			(end 0.12065 -0.3048)
			(stroke
				(width 0.1)
				(type default)
			)
			(layer "F.Fab")
		)
		(fp_line
			(start 0.67945 -0.3048)
			(end 0.67945 0.3048)
			(stroke
				(width 0.1)
				(type default)
			)
			(layer "F.Fab")
		)
		(fp_line
			(start 0.67945 0.3048)
			(end 0.120396 0.3048)
			(stroke
				(width 0.1)
				(type default)
			)
			(layer "F.Fab")
		)
		(pad "1" smd circle
			(at -0.40005 0)
			(size 0 0)
			(layers "F.Cu" "F.Mask" "F.Paste")
			(net "P3V3_AUX")
		)
		(pad "2" smd circle
			(at 0.40005 0)
			(size 0 0)
			(layers "F.Cu" "F.Mask" "F.Paste")
			(net "PCA9555_A2")
		)
	)
	(footprint ""
		(layer "F.Cu")
		(at 443.5094 -62.103 -90)
		(property "Reference" "PC137"
			(at 4.61137 2.7813 0)
			(unlocked yes)
			(layer "F.SilkS")
			(effects
				(font
					(size 0.7874 0.5842)
					(thickness 0.1524)
				)
				(justify left)
			)
		)
		(property "Value" ""
			(at 0 0 270)
			(layer "F.Fab")
			(effects
				(font
					(size 1.27 1.27)
				)
			)
		)
		(duplicate_pad_numbers_are_jumpers no)
		(fp_line
			(start -1.988058 2.750058)
			(end 2.750058 2.750058)
			(stroke
				(width 0.1524)
				(type default)
			)
			(layer "F.SilkS")
		)
		(fp_line
			(start 2.750058 2.750058)
			(end 2.750058 0.9398)
			(stroke
				(width 0.1524)
				(type default)
			)
			(layer "F.SilkS")
		)
		(fp_line
			(start -2.750058 1.988058)
			(end -1.988058 2.750058)
			(stroke
				(width 0.1524)
				(type default)
			)
			(layer "F.SilkS")
		)
		(fp_line
			(start -2.750058 0.9398)
			(end -2.750058 1.988058)
			(stroke
				(width 0.1524)
				(type default)
			)
			(layer "F.SilkS")
		)
		(fp_line
			(start 2.750058 -0.9398)
			(end 2.750058 -2.750058)
			(stroke
				(width 0.1524)
				(type default)
			)
			(layer "F.SilkS")
		)
		(fp_line
			(start -2.750058 -1.988058)
			(end -2.750058 -0.9398)
			(stroke
				(width 0.1524)
				(type default)
			)
			(layer "F.SilkS")
		)
		(fp_line
			(start -1.988058 -2.750058)
			(end -2.750058 -1.988058)
			(stroke
				(width 0.1524)
				(type default)
			)
			(layer "F.SilkS")
		)
		(fp_line
			(start 2.750058 -2.750058)
			(end -1.988058 -2.750058)
			(stroke
				(width 0.1524)
				(type default)
			)
			(layer "F.SilkS")
		)
		(fp_line
			(start -2.750058 2.750058)
			(end 2.750058 2.750058)
			(stroke
				(width 0.1)
				(type default)
			)
			(layer "F.Fab")
		)
		(fp_line
			(start 2.750058 2.750058)
			(end 2.750058 -2.750058)
			(stroke
				(width 0.1)
				(type default)
			)
			(layer "F.Fab")
		)
		(fp_line
			(start -2.750058 -2.750058)
			(end -2.750058 2.750058)
			(stroke
				(width 0.1)
				(type default)
			)
			(layer "F.Fab")
		)
		(fp_line
			(start 2.750058 -2.750058)
			(end -2.750058 -2.750058)
			(stroke
				(width 0.1)
				(type default)
			)
			(layer "F.Fab")
		)
		(pad "1" smd rect
			(at -2.199894 0)
			(size 1.6002 3.0226)
			(layers "F.Cu" "F.Mask" "F.Paste")
			(net "P3V3_AUX")
		)
		(pad "2" smd rect
			(at 2.199894 0)
			(size 1.6002 3.0226)
			(layers "F.Cu" "F.Mask" "F.Paste")
			(net "GND")
		)
	)
	(footprint ""
		(layer "F.Cu")
		(at 414.49244 -24.36622)
		(property "Reference" "R5920"
			(at 0 0 0)
			(layer "F.SilkS")
			(hide yes)
			(effects
				(font
					(size 1.27 1.27)
				)
			)
		)
		(property "Value" ""
			(at 0 0 0)
			(layer "F.Fab")
			(effects
				(font
					(size 1.27 1.27)
				)
			)
		)
		(duplicate_pad_numbers_are_jumpers no)
		(fp_line
			(start -1.2954 -0.5842)
			(end 1.2954 -0.5842)
			(stroke
				(width 0.1524)
				(type default)
			)
			(layer "F.SilkS")
		)
		(fp_line
			(start -1.2954 0.5842)
			(end -1.2954 -0.5842)
			(stroke
				(width 0.1524)
				(type default)
			)
			(layer "F.SilkS")
		)
		(fp_line
			(start 1.2954 -0.5842)
			(end 1.2954 0.5842)
			(stroke
				(width 0.1524)
				(type default)
			)
			(layer "F.SilkS")
		)
		(fp_line
			(start 1.2954 0.5842)
			(end -1.2954 0.5842)
			(stroke
				(width 0.1524)
				(type default)
			)
			(layer "F.SilkS")
		)
		(fp_line
			(start -1.1938 -0.406654)
			(end -0.8636 -0.406654)
			(stroke
				(width 0.1)
				(type default)
			)
			(layer "F.Fab")
		)
		(fp_line
			(start -1.1938 0.4064)
			(end -1.1938 -0.406654)
			(stroke
				(width 0.1)
				(type default)
			)
			(layer "F.Fab")
		)
		(fp_line
			(start -0.8636 -0.4572)
			(end 0.8636 -0.4572)
			(stroke
				(width 0.1)
				(type default)
			)
			(layer "F.Fab")
		)
		(fp_line
			(start -0.8636 -0.406654)
			(end -0.8636 -0.4572)
			(stroke
				(width 0.1)
				(type default)
			)
			(layer "F.Fab")
		)
		(fp_line
			(start -0.8636 0.4064)
			(end -1.1938 0.4064)
			(stroke
				(width 0.1)
				(type default)
			)
			(layer "F.Fab")
		)
		(fp_line
			(start -0.8636 0.4318)
			(end -0.8636 0.4064)
			(stroke
				(width 0.1)
				(type default)
			)
			(layer "F.Fab")
		)
		(fp_line
			(start -0.8636 0.4572)
			(end -0.8636 0.4318)
			(stroke
				(width 0.1)
				(type default)
			)
			(layer "F.Fab")
		)
		(fp_line
			(start 0.8636 -0.4572)
			(end 0.8636 -0.406654)
			(stroke
				(width 0.1)
				(type default)
			)
			(layer "F.Fab")
		)
		(fp_line
			(start 0.8636 -0.406654)
			(end 1.1938 -0.406654)
			(stroke
				(width 0.1)
				(type default)
			)
			(layer "F.Fab")
		)
		(fp_line
			(start 0.8636 0.4064)
			(end 0.8636 0.4572)
			(stroke
				(width 0.1)
				(type default)
			)
			(layer "F.Fab")
		)
		(fp_line
			(start 0.8636 0.4572)
			(end -0.8636 0.4572)
			(stroke
				(width 0.1)
				(type default)
			)
			(layer "F.Fab")
		)
		(fp_line
			(start 1.1938 -0.406654)
			(end 1.1938 0.4064)
			(stroke
				(width 0.1)
				(type default)
			)
			(layer "F.Fab")
		)
		(fp_line
			(start 1.1938 0.4064)
			(end 0.8636 0.4064)
			(stroke
				(width 0.1)
				(type default)
			)
			(layer "F.Fab")
		)
		(pad "1" smd rect
			(at -0.7366 0 270)
			(size 0.7112 0.8128)
			(layers "F.Cu" "F.Mask" "F.Paste")
			(net "P12V_HPDB")
		)
		(pad "2" smd rect
			(at 0.7366 0 270)
			(size 0.7112 0.8128)
			(layers "F.Cu" "F.Mask" "F.Paste")
			(net "P12V_LED_PD")
		)
	)
	(footprint ""
		(layer "F.Cu")
		(at 166.543736 -66.167 180)
		(property "Reference" "R5894"
			(at 0 0 180)
			(layer "F.SilkS")
			(hide yes)
			(effects
				(font
					(size 1.27 1.27)
				)
			)
		)
		(property "Value" ""
			(at 0 0 180)
			(layer "F.Fab")
			(effects
				(font
					(size 1.27 1.27)
				)
			)
		)
		(duplicate_pad_numbers_are_jumpers no)
		(fp_line
			(start 0.7874 0.4064)
			(end -0.7874 0.4064)
			(stroke
				(width 0.1524)
				(type default)
			)
			(layer "F.SilkS")
		)
		(fp_line
			(start 0.7874 -0.4064)
			(end 0.7874 0.4064)
			(stroke
				(width 0.1524)
				(type default)
			)
			(layer "F.SilkS")
		)
		(fp_line
			(start -0.7874 0.4064)
			(end -0.7874 -0.4064)
			(stroke
				(width 0.1524)
				(type default)
			)
			(layer "F.SilkS")
		)
		(fp_line
			(start -0.7874 -0.4064)
			(end 0.7874 -0.4064)
			(stroke
				(width 0.1524)
				(type default)
			)
			(layer "F.SilkS")
		)
		(fp_line
			(start 0.67945 0.3048)
			(end 0.120396 0.3048)
			(stroke
				(width 0.1)
				(type default)
			)
			(layer "F.Fab")
		)
		(fp_line
			(start 0.67945 -0.3048)
			(end 0.67945 0.3048)
			(stroke
				(width 0.1)
				(type default)
			)
			(layer "F.Fab")
		)
		(fp_line
			(start 0.12065 -0.2794)
			(end 0.12065 -0.3048)
			(stroke
				(width 0.1)
				(type default)
			)
			(layer "F.Fab")
		)
		(fp_line
			(start 0.12065 -0.3048)
			(end 0.67945 -0.3048)
			(stroke
				(width 0.1)
				(type default)
			)
			(layer "F.Fab")
		)
		(fp_line
			(start 0.120396 0.3048)
			(end 0.120396 0.2794)
			(stroke
				(width 0.1)
				(type default)
			)
			(layer "F.Fab")
		)
		(fp_line
			(start 0.120396 0.2794)
			(end -0.12065 0.2794)
			(stroke
				(width 0.1)
				(type default)
			)
			(layer "F.Fab")
		)
		(fp_line
			(start -0.12065 0.3048)
			(end -0.67945 0.3048)
			(stroke
				(width 0.1)
				(type default)
			)
			(layer "F.Fab")
		)
		(fp_line
			(start -0.12065 0.2794)
			(end -0.12065 0.3048)
			(stroke
				(width 0.1)
				(type default)
			)
			(layer "F.Fab")
		)
		(fp_line
			(start -0.12065 -0.2794)
			(end 0.12065 -0.2794)
			(stroke
				(width 0.1)
				(type default)
			)
			(layer "F.Fab")
		)
		(fp_line
			(start -0.12065 -0.305054)
			(end -0.12065 -0.2794)
			(stroke
				(width 0.1)
				(type default)
			)
			(layer "F.Fab")
		)
		(fp_line
			(start -0.67945 0.3048)
			(end -0.67945 -0.305054)
			(stroke
				(width 0.1)
				(type default)
			)
			(layer "F.Fab")
		)
		(fp_line
			(start -0.67945 -0.305054)
			(end -0.12065 -0.305054)
			(stroke
				(width 0.1)
				(type default)
			)
			(layer "F.Fab")
		)
		(pad "1" smd circle
			(at -0.40005 0 180)
			(size 0 0)
			(layers "F.Cu" "F.Mask" "F.Paste")
			(net "P52V_HS2_ADR0")
		)
		(pad "2" smd circle
			(at 0.40005 0 180)
			(size 0 0)
			(layers "F.Cu" "F.Mask" "F.Paste")
			(net "GND1_FIELD_SIGNAL")
		)
	)
	(footprint ""
		(layer "F.Cu")
		(at 379.660912 -17.907254 -90)
		(property "Reference" "R71"
			(at 0 0 270)
			(layer "F.SilkS")
			(hide yes)
			(effects
				(font
					(size 1.27 1.27)
				)
			)
		)
		(property "Value" ""
			(at 0 0 270)
			(layer "F.Fab")
			(effects
				(font
					(size 1.27 1.27)
				)
			)
		)
		(duplicate_pad_numbers_are_jumpers no)
		(fp_line
			(start -0.7874 0.4064)
			(end -0.7874 -0.4064)
			(stroke
				(width 0.1524)
				(type default)
			)
			(layer "F.SilkS")
		)
		(fp_line
			(start 0.7874 0.4064)
			(end -0.7874 0.4064)
			(stroke
				(width 0.1524)
				(type default)
			)
			(layer "F.SilkS")
		)
		(fp_line
			(start -0.7874 -0.4064)
			(end 0.7874 -0.4064)
			(stroke
				(width 0.1524)
				(type default)
			)
			(layer "F.SilkS")
		)
		(fp_line
			(start 0.7874 -0.4064)
			(end 0.7874 0.4064)
			(stroke
				(width 0.1524)
				(type default)
			)
			(layer "F.SilkS")
		)
		(fp_line
			(start -0.67945 0.3048)
			(end -0.67945 -0.305054)
			(stroke
				(width 0.1)
				(type default)
			)
			(layer "F.Fab")
		)
		(fp_line
			(start -0.12065 0.3048)
			(end -0.67945 0.3048)
			(stroke
				(width 0.1)
				(type default)
			)
			(layer "F.Fab")
		)
		(fp_line
			(start 0.120396 0.3048)
			(end 0.120396 0.2794)
			(stroke
				(width 0.1)
				(type default)
			)
			(layer "F.Fab")
		)
		(fp_line
			(start 0.67945 0.3048)
			(end 0.120396 0.3048)
			(stroke
				(width 0.1)
				(type default)
			)
			(layer "F.Fab")
		)
		(fp_line
			(start -0.12065 0.2794)
			(end -0.12065 0.3048)
			(stroke
				(width 0.1)
				(type default)
			)
			(layer "F.Fab")
		)
		(fp_line
			(start 0.120396 0.2794)
			(end -0.12065 0.2794)
			(stroke
				(width 0.1)
				(type default)
			)
			(layer "F.Fab")
		)
		(fp_line
			(start -0.12065 -0.2794)
			(end 0.12065 -0.2794)
			(stroke
				(width 0.1)
				(type default)
			)
			(layer "F.Fab")
		)
		(fp_line
			(start 0.12065 -0.2794)
			(end 0.12065 -0.3048)
			(stroke
				(width 0.1)
				(type default)
			)
			(layer "F.Fab")
		)
		(fp_line
			(start 0.12065 -0.3048)
			(end 0.67945 -0.3048)
			(stroke
				(width 0.1)
				(type default)
			)
			(layer "F.Fab")
		)
		(fp_line
			(start 0.67945 -0.3048)
			(end 0.67945 0.3048)
			(stroke
				(width 0.1)
				(type default)
			)
			(layer "F.Fab")
		)
		(fp_line
			(start -0.67945 -0.305054)
			(end -0.12065 -0.305054)
			(stroke
				(width 0.1)
				(type default)
			)
			(layer "F.Fab")
		)
		(fp_line
			(start -0.12065 -0.305054)
			(end -0.12065 -0.2794)
			(stroke
				(width 0.1)
				(type default)
			)
			(layer "F.Fab")
		)
		(pad "1" smd circle
			(at -0.40005 0 270)
			(size 0 0)
			(layers "F.Cu" "F.Mask" "F.Paste")
			(net "SMB_PDB_FAN_0_SCL")
		)
		(pad "2" smd circle
			(at 0.40005 0 270)
			(size 0 0)
			(layers "F.Cu" "F.Mask" "F.Paste")
			(net "SMB_PDB_FAN_0_R_SCL")
		)
	)
	(footprint ""
		(layer "F.Cu")
		(at 428.00016 -4.499864 180)
		(property "Reference" "H14"
			(at 1.15316 10.586466 0)
			(unlocked yes)
			(layer "F.SilkS")
			(effects
				(font
					(size 0.7874 0.5842)
					(thickness 0.1524)
				)
				(justify left)
			)
		)
		(property "Value" ""
			(at 0 0 180)
			(layer "F.Fab")
			(effects
				(font
					(size 1.27 1.27)
				)
			)
		)
		(duplicate_pad_numbers_are_jumpers no)
		(pad "1" thru_hole oval
			(at 0 0 180)
			(size 9.017 14.0208)
			(drill 3.0226
				(offset 0 2.499868)
			)
			(layers "*.Cu" "*.Mask")
			(remove_unused_layers no)
			(net "GND")
			(clearance -1.500378)
			(padstack
				(mode front_inner_back)
				(layer "Inner"
					(shape circle)
					(size 0 0)
					(clearance 0)
				)
				(layer "B.Cu"
					(shape oval)
					(size 9.017 14.0208)
					(offset 0 2.499868)
					(clearance -1.500378)
				)
			)
		)
	)
	(footprint ""
		(layer "F.Cu")
		(at 413.45358 -32.75076 90)
		(property "Reference" "R5926"
			(at 0 0 90)
			(layer "F.SilkS")
			(hide yes)
			(effects
				(font
					(size 1.27 1.27)
				)
			)
		)
		(property "Value" ""
			(at 0 0 90)
			(layer "F.Fab")
			(effects
				(font
					(size 1.27 1.27)
				)
			)
		)
		(duplicate_pad_numbers_are_jumpers no)
		(fp_line
			(start 0.7874 -0.4064)
			(end 0.7874 0.4064)
			(stroke
				(width 0.1524)
				(type default)
			)
			(layer "F.SilkS")
		)
		(fp_line
			(start -0.7874 -0.4064)
			(end 0.7874 -0.4064)
			(stroke
				(width 0.1524)
				(type default)
			)
			(layer "F.SilkS")
		)
		(fp_line
			(start 0.7874 0.4064)
			(end -0.7874 0.4064)
			(stroke
				(width 0.1524)
				(type default)
			)
			(layer "F.SilkS")
		)
		(fp_line
			(start -0.7874 0.4064)
			(end -0.7874 -0.4064)
			(stroke
				(width 0.1524)
				(type default)
			)
			(layer "F.SilkS")
		)
		(fp_line
			(start -0.12065 -0.305054)
			(end -0.12065 -0.2794)
			(stroke
				(width 0.1)
				(type default)
			)
			(layer "F.Fab")
		)
		(fp_line
			(start -0.67945 -0.305054)
			(end -0.12065 -0.305054)
			(stroke
				(width 0.1)
				(type default)
			)
			(layer "F.Fab")
		)
		(fp_line
			(start 0.67945 -0.3048)
			(end 0.67945 0.3048)
			(stroke
				(width 0.1)
				(type default)
			)
			(layer "F.Fab")
		)
		(fp_line
			(start 0.12065 -0.3048)
			(end 0.67945 -0.3048)
			(stroke
				(width 0.1)
				(type default)
			)
			(layer "F.Fab")
		)
		(fp_line
			(start 0.12065 -0.2794)
			(end 0.12065 -0.3048)
			(stroke
				(width 0.1)
				(type default)
			)
			(layer "F.Fab")
		)
		(fp_line
			(start -0.12065 -0.2794)
			(end 0.12065 -0.2794)
			(stroke
				(width 0.1)
				(type default)
			)
			(layer "F.Fab")
		)
		(fp_line
			(start 0.120396 0.2794)
			(end -0.12065 0.2794)
			(stroke
				(width 0.1)
				(type default)
			)
			(layer "F.Fab")
		)
		(fp_line
			(start -0.12065 0.2794)
			(end -0.12065 0.3048)
			(stroke
				(width 0.1)
				(type default)
			)
			(layer "F.Fab")
		)
		(fp_line
			(start 0.67945 0.3048)
			(end 0.120396 0.3048)
			(stroke
				(width 0.1)
				(type default)
			)
			(layer "F.Fab")
		)
		(fp_line
			(start 0.120396 0.3048)
			(end 0.120396 0.2794)
			(stroke
				(width 0.1)
				(type default)
			)
			(layer "F.Fab")
		)
		(fp_line
			(start -0.12065 0.3048)
			(end -0.67945 0.3048)
			(stroke
				(width 0.1)
				(type default)
			)
			(layer "F.Fab")
		)
		(fp_line
			(start -0.67945 0.3048)
			(end -0.67945 -0.305054)
			(stroke
				(width 0.1)
				(type default)
			)
			(layer "F.Fab")
		)
		(pad "1" smd circle
			(at -0.40005 0 90)
			(size 0 0)
			(layers "F.Cu" "F.Mask" "F.Paste")
			(net "P12V_LED_IMON")
		)
		(pad "2" smd circle
			(at 0.40005 0 90)
			(size 0 0)
			(layers "F.Cu" "F.Mask" "F.Paste")
			(net "GND")
		)
	)
	(footprint ""
		(layer "F.Cu")
		(at 447.421 -46.101 180)
		(property "Reference" "C26"
			(at 0 0 180)
			(layer "F.SilkS")
			(hide yes)
			(effects
				(font
					(size 1.27 1.27)
				)
			)
		)
		(property "Value" ""
			(at 0 0 180)
			(layer "F.Fab")
			(effects
				(font
					(size 1.27 1.27)
				)
			)
		)
		(duplicate_pad_numbers_are_jumpers no)
		(fp_line
			(start 0.7874 0.4064)
			(end -0.7874 0.4064)
			(stroke
				(width 0.1524)
				(type default)
			)
			(layer "F.SilkS")
		)
		(fp_line
			(start 0.7874 -0.4064)
			(end 0.7874 0.4064)
			(stroke
				(width 0.1524)
				(type default)
			)
			(layer "F.SilkS")
		)
		(fp_line
			(start -0.7874 0.4064)
			(end -0.7874 -0.4064)
			(stroke
				(width 0.1524)
				(type default)
			)
			(layer "F.SilkS")
		)
		(fp_line
			(start -0.7874 -0.4064)
			(end 0.7874 -0.4064)
			(stroke
				(width 0.1524)
				(type default)
			)
			(layer "F.SilkS")
		)
		(fp_line
			(start 0.67945 0.3048)
			(end 0.120396 0.3048)
			(stroke
				(width 0.1)
				(type default)
			)
			(layer "F.Fab")
		)
		(fp_line
			(start 0.67945 -0.3048)
			(end 0.67945 0.3048)
			(stroke
				(width 0.1)
				(type default)
			)
			(layer "F.Fab")
		)
		(fp_line
			(start 0.12065 -0.2794)
			(end 0.12065 -0.3048)
			(stroke
				(width 0.1)
				(type default)
			)
			(layer "F.Fab")
		)
		(fp_line
			(start 0.12065 -0.3048)
			(end 0.67945 -0.3048)
			(stroke
				(width 0.1)
				(type default)
			)
			(layer "F.Fab")
		)
		(fp_line
			(start 0.120396 0.3048)
			(end 0.120396 0.2794)
			(stroke
				(width 0.1)
				(type default)
			)
			(layer "F.Fab")
		)
		(fp_line
			(start 0.120396 0.2794)
			(end -0.12065 0.2794)
			(stroke
				(width 0.1)
				(type default)
			)
			(layer "F.Fab")
		)
		(fp_line
			(start -0.12065 0.3048)
			(end -0.67945 0.3048)
			(stroke
				(width 0.1)
				(type default)
			)
			(layer "F.Fab")
		)
		(fp_line
			(start -0.12065 0.2794)
			(end -0.12065 0.3048)
			(stroke
				(width 0.1)
				(type default)
			)
			(layer "F.Fab")
		)
		(fp_line
			(start -0.12065 -0.2794)
			(end 0.12065 -0.2794)
			(stroke
				(width 0.1)
				(type default)
			)
			(layer "F.Fab")
		)
		(fp_line
			(start -0.12065 -0.305054)
			(end -0.12065 -0.2794)
			(stroke
				(width 0.1)
				(type default)
			)
			(layer "F.Fab")
		)
		(fp_line
			(start -0.67945 0.3048)
			(end -0.67945 -0.305054)
			(stroke
				(width 0.1)
				(type default)
			)
			(layer "F.Fab")
		)
		(fp_line
			(start -0.67945 -0.305054)
			(end -0.12065 -0.305054)
			(stroke
				(width 0.1)
				(type default)
			)
			(layer "F.Fab")
		)
		(pad "1" smd circle
			(at -0.40005 0 180)
			(size 0 0)
			(layers "F.Cu" "F.Mask" "F.Paste")
			(net "GND")
		)
		(pad "2" smd circle
			(at 0.40005 0 180)
			(size 0 0)
			(layers "F.Cu" "F.Mask" "F.Paste")
			(net "P3V3_AUX")
		)
	)
	(footprint ""
		(layer "F.Cu")
		(at 69.760084 -2.035048 -90)
		(property "Reference" "J9"
			(at -9.368282 -10.503916 0)
			(unlocked yes)
			(layer "F.SilkS")
			(effects
				(font
					(size 0.7874 0.5842)
					(thickness 0.1524)
				)
			)
		)
		(property "Value" ""
			(at 0 0 270)
			(layer "F.Fab")
			(effects
				(font
					(size 1.27 1.27)
				)
			)
		)
		(duplicate_pad_numbers_are_jumpers no)
		(fp_line
			(start -8.530082 13.72489)
			(end -8.530082 3.034284)
			(stroke
				(width 0.1524)
				(type default)
			)
			(layer "F.SilkS")
		)
		(fp_line
			(start 1.501648 13.72489)
			(end -8.530082 13.72489)
			(stroke
				(width 0.1524)
				(type default)
			)
			(layer "F.SilkS")
		)
		(fp_line
			(start -5.530088 10.724896)
			(end 1.720088 10.724896)
			(stroke
				(width 0.1524)
				(type default)
			)
			(layer "F.SilkS")
		)
		(fp_line
			(start 1.720088 10.724896)
			(end 1.720088 -8.80491)
			(stroke
				(width 0.1524)
				(type default)
			)
			(layer "F.SilkS")
		)
		(fp_line
			(start -8.530082 -5.068316)
			(end -8.530082 -11.804904)
			(stroke
				(width 0.1524)
				(type default)
			)
			(layer "F.SilkS")
		)
		(fp_line
			(start -5.530088 -8.80491)
			(end -5.530088 10.724896)
			(stroke
				(width 0.1524)
				(type default)
			)
			(layer "F.SilkS")
		)
		(fp_line
			(start 1.720088 -8.80491)
			(end -5.530088 -8.80491)
			(stroke
				(width 0.1524)
				(type default)
			)
			(layer "F.SilkS")
		)
		(fp_line
			(start -8.530082 -11.804904)
			(end 1.577848 -11.804904)
			(stroke
				(width 0.1524)
				(type default)
			)
			(layer "F.SilkS")
		)
		(fp_poly
			(pts
				(xy 1.273048 0.24638) (xy 0.780288 0) (xy 1.273048 -0.24638)
			)
			(stroke
				(width 0)
				(type default)
			)
			(fill yes)
			(layer "F.SilkS")
		)
		(fp_line
			(start -8.530082 13.72489)
			(end -8.530082 -11.804904)
			(stroke
				(width 0.1524)
				(type default)
			)
			(layer "B.SilkS")
		)
		(fp_line
			(start 4.720082 13.72489)
			(end -8.530082 13.72489)
			(stroke
				(width 0.1524)
				(type default)
			)
			(layer "B.SilkS")
		)
		(fp_line
			(start -8.530082 -11.804904)
			(end 4.720082 -11.804904)
			(stroke
				(width 0.1524)
				(type default)
			)
			(layer "B.SilkS")
		)
		(fp_line
			(start 4.720082 -11.804904)
			(end 4.720082 13.72489)
			(stroke
				(width 0.1524)
				(type default)
			)
			(layer "B.SilkS")
		)
		(fp_line
			(start -8.530082 13.72489)
			(end -8.530082 -11.804904)
			(stroke
				(width 0.1)
				(type default)
			)
			(layer "B.Fab")
		)
		(fp_line
			(start 4.720082 13.72489)
			(end -8.530082 13.72489)
			(stroke
				(width 0.1)
				(type default)
			)
			(layer "B.Fab")
		)
		(fp_line
			(start -8.530082 -11.804904)
			(end 4.720082 -11.804904)
			(stroke
				(width 0.1)
				(type default)
			)
			(layer "B.Fab")
		)
		(fp_line
			(start 4.720082 -11.804904)
			(end 4.720082 13.72489)
			(stroke
				(width 0.1)
				(type default)
			)
			(layer "B.Fab")
		)
		(fp_line
			(start -5.530088 10.724896)
			(end 1.720088 10.724896)
			(stroke
				(width 0.1)
				(type default)
			)
			(layer "F.Fab")
		)
		(fp_line
			(start 1.720088 10.724896)
			(end 1.720088 -8.80491)
			(stroke
				(width 0.1)
				(type default)
			)
			(layer "F.Fab")
		)
		(fp_line
			(start -5.530088 -8.80491)
			(end -5.530088 10.724896)
			(stroke
				(width 0.1)
				(type default)
			)
			(layer "F.Fab")
		)
		(fp_line
			(start 1.720088 -8.80491)
			(end -5.530088 -8.80491)
			(stroke
				(width 0.1)
				(type default)
			)
			(layer "F.Fab")
		)
		(fp_poly
			(pts
				(xy 2.939288 0.508) (xy 2.939288 -0.508) (xy 1.923288 0)
			)
			(stroke
				(width 0)
				(type default)
			)
			(fill yes)
			(layer "F.Fab")
		)
		(fp_text user "PRESS-FIT"
			(at -7.045452 13.245084 0)
			(unlocked yes)
			(layer "F.SilkS")
			(effects
				(font
					(size 1.27 0.9652)
					(thickness 0.1524)
				)
				(justify left)
			)
		)
		(fp_text user "PRESS-FIT"
			(at -5.553202 -6.846316 0)
			(unlocked yes)
			(layer "B.SilkS")
			(effects
				(font
					(size 1.905 1.4224)
					(thickness 0.1524)
				)
				(justify left mirror)
			)
		)
		(fp_text user "PRESS-FIT"
			(at -6.86435 -7.1501 0)
			(unlocked yes)
			(layer "B.Fab")
			(effects
				(font
					(size 1.905 1.4224)
					(thickness 0.1524)
				)
				(justify left mirror)
			)
		)
		(fp_text user "PRESS-FIT"
			(at -6.88975 9.5123 0)
			(unlocked yes)
			(layer "F.Fab")
			(effects
				(font
					(size 1.905 1.4224)
					(thickness 0.1524)
				)
				(justify left)
			)
		)
		(pad "" np_thru_hole circle
			(at -1.905 8.58012 270)
			(size 2.413 2.413)
			(drill 2.413)
			(layers "*.Cu" "*.Mask")
			(clearance 0.381)
			(thermal_gap 0.381)
		)
		(pad "" np_thru_hole circle
			(at -0.55499 -6.65988 270)
			(size 2.413 2.413)
			(drill 2.413)
			(layers "*.Cu" "*.Mask")
			(clearance 0.381)
			(thermal_gap 0.381)
		)
		(pad "P1" thru_hole circle
			(at -0.55499 6.04012 270)
			(size 1.156208 1.156208)
			(drill 0.749808)
			(layers "*.Cu" "*.Mask")
			(remove_unused_layers no)
			(net "P52V_FAN")
			(clearance 0.0508)
			(thermal_gap 0.0508)
		)
		(pad "P2" thru_hole circle
			(at -0.55499 3.50012 270)
			(size 1.156208 1.156208)
			(drill 0.749808)
			(layers "*.Cu" "*.Mask")
			(remove_unused_layers no)
			(net "P52V_FAN")
			(clearance 0.0508)
			(thermal_gap 0.0508)
		)
		(pad "P3" thru_hole circle
			(at -3.25501 3.50012 270)
			(size 1.156208 1.156208)
			(drill 0.749808)
			(layers "*.Cu" "*.Mask")
			(remove_unused_layers no)
			(net "GND")
			(clearance 0.0508)
			(thermal_gap 0.0508)
		)
		(pad "P4" thru_hole circle
			(at -3.25501 6.04012 270)
			(size 1.156208 1.156208)
			(drill 0.749808)
			(layers "*.Cu" "*.Mask")
			(remove_unused_layers no)
			(net "GND")
			(clearance 0.0508)
			(thermal_gap 0.0508)
		)
		(pad "S1" thru_hole rect
			(at 0 0 270)
			(size 1.156208 1.156208)
			(drill 0.749808)
			(layers "*.Cu" "*.Mask")
			(remove_unused_layers no)
			(net "RST_SMB_FAN_1_R_N")
			(clearance 0.0508)
			(thermal_gap 0.0508)
			(padstack
				(mode front_inner_back)
				(layer "Inner"
					(shape circle)
					(size 1.156208 1.156208)
					(clearance 0.0508)
				)
				(layer "B.Cu"
					(shape rect)
					(size 1.156208 1.156208)
					(clearance 0.0508)
				)
			)
		)
		(pad "S2" thru_hole circle
			(at -1.27 -1.27 270)
			(size 1.156208 1.156208)
			(drill 0.749808)
			(layers "*.Cu" "*.Mask")
			(remove_unused_layers no)
			(net "FAN_PWR_EN_1_R")
			(clearance 0.0508)
			(thermal_gap 0.0508)
		)
		(pad "S3" thru_hole circle
			(at 0 -2.54 270)
			(size 1.156208 1.156208)
			(drill 0.749808)
			(layers "*.Cu" "*.Mask")
			(remove_unused_layers no)
			(net "P12V_FAN_LED")
			(clearance 0.0508)
			(thermal_gap 0.0508)
		)
		(pad "S4" thru_hole circle
			(at -1.27 -3.81 270)
			(size 1.156208 1.156208)
			(drill 0.749808)
			(layers "*.Cu" "*.Mask")
			(remove_unused_layers no)
			(net "P3V3_AUX")
			(clearance 0.0508)
			(thermal_gap 0.0508)
		)
		(pad "S5" thru_hole circle
			(at -3.81 -3.81 270)
			(size 1.156208 1.156208)
			(drill 0.749808)
			(layers "*.Cu" "*.Mask")
			(remove_unused_layers no)
			(net "PRSNT_FAN_BP1_R_N")
			(clearance 0.0508)
			(thermal_gap 0.0508)
		)
		(pad "S6" thru_hole circle
			(at -2.54 -2.54 270)
			(size 1.156208 1.156208)
			(drill 0.749808)
			(layers "*.Cu" "*.Mask")
			(remove_unused_layers no)
			(net "GND")
			(clearance 0.0508)
			(thermal_gap 0.0508)
		)
		(pad "S7" thru_hole circle
			(at -3.81 -1.27 270)
			(size 1.156208 1.156208)
			(drill 0.749808)
			(layers "*.Cu" "*.Mask")
			(remove_unused_layers no)
			(net "SMB_PDB_FAN_1_R_SCL")
			(clearance 0.0508)
			(thermal_gap 0.0508)
		)
		(pad "S8" thru_hole circle
			(at -2.54 0 270)
			(size 1.156208 1.156208)
			(drill 0.749808)
			(layers "*.Cu" "*.Mask")
			(remove_unused_layers no)
			(net "SMB_PDB_FAN_1_R_SDA")
			(clearance 0.0508)
			(thermal_gap 0.0508)
		)
		(zone
			(layers "F.Cu" "B.Cu" "In1.Cu" "In2.Cu" "In3.Cu" "In4.Cu" "In5.Cu" "In6.Cu"
				"In7.Cu" "In8.Cu"
			)
			(hatch none 0.5)
			(connect_pads
				(clearance 0)
			)
			(min_thickness 0.25)
			(keepout
				(tracks not_allowed)
				(vias allowed)
				(pads allowed)
				(copperpour not_allowed)
				(footprints allowed)
			)
			(placement
				(enabled no)
				(sheetname "")
			)
			(fill
				(thermal_gap 0.5)
				(thermal_bridge_width 0.5)
				(island_removal_mode 0)
			)
			(polygon
				(pts
					(arc
						(start 62.894464 -3.940048)
						(mid 59.465464 -3.940048)
						(end 62.894464 -3.940048)
					)
				)
			)
		)
		(zone
			(layers "F.Cu" "B.Cu" "In1.Cu" "In2.Cu" "In3.Cu" "In4.Cu" "In5.Cu" "In6.Cu"
				"In7.Cu" "In8.Cu"
			)
			(hatch none 0.5)
			(connect_pads
				(clearance 0)
			)
			(min_thickness 0.25)
			(keepout
				(tracks not_allowed)
				(vias allowed)
				(pads allowed)
				(copperpour not_allowed)
				(footprints allowed)
			)
			(placement
				(enabled no)
				(sheetname "")
			)
			(fill
				(thermal_gap 0.5)
				(thermal_bridge_width 0.5)
				(island_removal_mode 0)
			)
			(polygon
				(pts
					(arc
						(start 78.134718 -2.590038)
						(mid 74.70521 -2.590038)
						(end 78.134718 -2.590038)
					)
				)
			)
		)
		(zone
			(layer "B.Cu")
			(hatch none 0.5)
			(connect_pads
				(clearance 0)
			)
			(min_thickness 0.25)
			(keepout
				(tracks allowed)
				(vias not_allowed)
				(pads allowed)
				(copperpour not_allowed)
				(footprints allowed)
			)
			(placement
				(enabled no)
				(sheetname "")
			)
			(fill
				(thermal_gap 0.5)
				(thermal_bridge_width 0.5)
				(island_removal_mode 0)
			)
			(polygon
				(pts
					(xy 66.901568 -5.931662) (xy 63.07836 -5.931662) (xy 63.07836 -1.948434) (xy 66.901568 -1.948434)
				)
			)
		)
		(zone
			(layer "B.Cu")
			(hatch none 0.5)
			(connect_pads
				(clearance 0)
			)
			(min_thickness 0.25)
			(keepout
				(tracks allowed)
				(vias not_allowed)
				(pads allowed)
				(copperpour not_allowed)
				(footprints allowed)
			)
			(placement
				(enabled no)
				(sheetname "")
			)
			(fill
				(thermal_gap 0.5)
				(thermal_bridge_width 0.5)
				(island_removal_mode 0)
			)
			(polygon
				(pts
					(xy 74.211688 -6.486652) (xy 69.11848 -6.486652) (xy 69.11848 -1.393444) (xy 74.211688 -1.393444)
				)
			)
		)
	)
	(footprint ""
		(layer "F.Cu")
		(at 334.631284 -39.0652 -90)
		(property "Reference" "PR16"
			(at 0 0 270)
			(layer "F.SilkS")
			(hide yes)
			(effects
				(font
					(size 1.27 1.27)
				)
			)
		)
		(property "Value" ""
			(at 0 0 270)
			(layer "F.Fab")
			(effects
				(font
					(size 1.27 1.27)
				)
			)
		)
		(duplicate_pad_numbers_are_jumpers no)
		(fp_line
			(start -1.2954 0.5842)
			(end -1.2954 -0.5842)
			(stroke
				(width 0.1524)
				(type default)
			)
			(layer "F.SilkS")
		)
		(fp_line
			(start 1.2954 0.5842)
			(end -1.2954 0.5842)
			(stroke
				(width 0.1524)
				(type default)
			)
			(layer "F.SilkS")
		)
		(fp_line
			(start -1.2954 -0.5842)
			(end 1.2954 -0.5842)
			(stroke
				(width 0.1524)
				(type default)
			)
			(layer "F.SilkS")
		)
		(fp_line
			(start 1.2954 -0.5842)
			(end 1.2954 0.5842)
			(stroke
				(width 0.1524)
				(type default)
			)
			(layer "F.SilkS")
		)
		(fp_line
			(start -0.8636 0.4572)
			(end -0.8636 0.4318)
			(stroke
				(width 0.1)
				(type default)
			)
			(layer "F.Fab")
		)
		(fp_line
			(start 0.8636 0.4572)
			(end -0.8636 0.4572)
			(stroke
				(width 0.1)
				(type default)
			)
			(layer "F.Fab")
		)
		(fp_line
			(start -0.8636 0.4318)
			(end -0.8636 0.4064)
			(stroke
				(width 0.1)
				(type default)
			)
			(layer "F.Fab")
		)
		(fp_line
			(start -1.1938 0.4064)
			(end -1.1938 -0.406654)
			(stroke
				(width 0.1)
				(type default)
			)
			(layer "F.Fab")
		)
		(fp_line
			(start -0.8636 0.4064)
			(end -1.1938 0.4064)
			(stroke
				(width 0.1)
				(type default)
			)
			(layer "F.Fab")
		)
		(fp_line
			(start 0.8636 0.4064)
			(end 0.8636 0.4572)
			(stroke
				(width 0.1)
				(type default)
			)
			(layer "F.Fab")
		)
		(fp_line
			(start 1.1938 0.4064)
			(end 0.8636 0.4064)
			(stroke
				(width 0.1)
				(type default)
			)
			(layer "F.Fab")
		)
		(fp_line
			(start -1.1938 -0.406654)
			(end -0.8636 -0.406654)
			(stroke
				(width 0.1)
				(type default)
			)
			(layer "F.Fab")
		)
		(fp_line
			(start -0.8636 -0.406654)
			(end -0.8636 -0.4572)
			(stroke
				(width 0.1)
				(type default)
			)
			(layer "F.Fab")
		)
		(fp_line
			(start 0.8636 -0.406654)
			(end 1.1938 -0.406654)
			(stroke
				(width 0.1)
				(type default)
			)
			(layer "F.Fab")
		)
		(fp_line
			(start 1.1938 -0.406654)
			(end 1.1938 0.4064)
			(stroke
				(width 0.1)
				(type default)
			)
			(layer "F.Fab")
		)
		(fp_line
			(start -0.8636 -0.4572)
			(end 0.8636 -0.4572)
			(stroke
				(width 0.1)
				(type default)
			)
			(layer "F.Fab")
		)
		(fp_line
			(start 0.8636 -0.4572)
			(end 0.8636 -0.406654)
			(stroke
				(width 0.1)
				(type default)
			)
			(layer "F.Fab")
		)
		(pad "1" smd rect
			(at -0.7366 0 180)
			(size 0.7112 0.8128)
			(layers "F.Cu" "F.Mask" "F.Paste")
			(net "P52V_HS1_GATE2_R")
		)
		(pad "2" smd rect
			(at 0.7366 0 180)
			(size 0.7112 0.8128)
			(layers "F.Cu" "F.Mask" "F.Paste")
			(net "P52V_HS1_GATE6")
		)
	)
	(footprint ""
		(layer "F.Cu")
		(at 448.437 -38.862)
		(property "Reference" "C2"
			(at 0 0 0)
			(layer "F.SilkS")
			(hide yes)
			(effects
				(font
					(size 1.27 1.27)
				)
			)
		)
		(property "Value" ""
			(at 0 0 0)
			(layer "F.Fab")
			(effects
				(font
					(size 1.27 1.27)
				)
			)
		)
		(duplicate_pad_numbers_are_jumpers no)
		(fp_line
			(start -0.7874 -0.4064)
			(end 0.7874 -0.4064)
			(stroke
				(width 0.1524)
				(type default)
			)
			(layer "F.SilkS")
		)
		(fp_line
			(start -0.7874 0.4064)
			(end -0.7874 -0.4064)
			(stroke
				(width 0.1524)
				(type default)
			)
			(layer "F.SilkS")
		)
		(fp_line
			(start 0.7874 -0.4064)
			(end 0.7874 0.4064)
			(stroke
				(width 0.1524)
				(type default)
			)
			(layer "F.SilkS")
		)
		(fp_line
			(start 0.7874 0.4064)
			(end -0.7874 0.4064)
			(stroke
				(width 0.1524)
				(type default)
			)
			(layer "F.SilkS")
		)
		(fp_line
			(start -0.67945 -0.305054)
			(end -0.12065 -0.305054)
			(stroke
				(width 0.1)
				(type default)
			)
			(layer "F.Fab")
		)
		(fp_line
			(start -0.67945 0.3048)
			(end -0.67945 -0.305054)
			(stroke
				(width 0.1)
				(type default)
			)
			(layer "F.Fab")
		)
		(fp_line
			(start -0.12065 -0.305054)
			(end -0.12065 -0.2794)
			(stroke
				(width 0.1)
				(type default)
			)
			(layer "F.Fab")
		)
		(fp_line
			(start -0.12065 -0.2794)
			(end 0.12065 -0.2794)
			(stroke
				(width 0.1)
				(type default)
			)
			(layer "F.Fab")
		)
		(fp_line
			(start -0.12065 0.2794)
			(end -0.12065 0.3048)
			(stroke
				(width 0.1)
				(type default)
			)
			(layer "F.Fab")
		)
		(fp_line
			(start -0.12065 0.3048)
			(end -0.67945 0.3048)
			(stroke
				(width 0.1)
				(type default)
			)
			(layer "F.Fab")
		)
		(fp_line
			(start 0.120396 0.2794)
			(end -0.12065 0.2794)
			(stroke
				(width 0.1)
				(type default)
			)
			(layer "F.Fab")
		)
		(fp_line
			(start 0.120396 0.3048)
			(end 0.120396 0.2794)
			(stroke
				(width 0.1)
				(type default)
			)
			(layer "F.Fab")
		)
		(fp_line
			(start 0.12065 -0.3048)
			(end 0.67945 -0.3048)
			(stroke
				(width 0.1)
				(type default)
			)
			(layer "F.Fab")
		)
		(fp_line
			(start 0.12065 -0.2794)
			(end 0.12065 -0.3048)
			(stroke
				(width 0.1)
				(type default)
			)
			(layer "F.Fab")
		)
		(fp_line
			(start 0.67945 -0.3048)
			(end 0.67945 0.3048)
			(stroke
				(width 0.1)
				(type default)
			)
			(layer "F.Fab")
		)
		(fp_line
			(start 0.67945 0.3048)
			(end 0.120396 0.3048)
			(stroke
				(width 0.1)
				(type default)
			)
			(layer "F.Fab")
		)
		(pad "1" smd circle
			(at -0.40005 0)
			(size 0 0)
			(layers "F.Cu" "F.Mask" "F.Paste")
			(net "P3V3_AUX")
		)
		(pad "2" smd circle
			(at 0.40005 0)
			(size 0 0)
			(layers "F.Cu" "F.Mask" "F.Paste")
			(net "GND")
		)
	)
	(footprint ""
		(layer "F.Cu")
		(at 430.276 -43.18 180)
		(property "Reference" "R97"
			(at 0 0 180)
			(layer "F.SilkS")
			(hide yes)
			(effects
				(font
					(size 1.27 1.27)
				)
			)
		)
		(property "Value" ""
			(at 0 0 180)
			(layer "F.Fab")
			(effects
				(font
					(size 1.27 1.27)
				)
			)
		)
		(duplicate_pad_numbers_are_jumpers no)
		(fp_line
			(start 0.7874 0.4064)
			(end -0.7874 0.4064)
			(stroke
				(width 0.1524)
				(type default)
			)
			(layer "F.SilkS")
		)
		(fp_line
			(start 0.7874 -0.4064)
			(end 0.7874 0.4064)
			(stroke
				(width 0.1524)
				(type default)
			)
			(layer "F.SilkS")
		)
		(fp_line
			(start -0.7874 0.4064)
			(end -0.7874 -0.4064)
			(stroke
				(width 0.1524)
				(type default)
			)
			(layer "F.SilkS")
		)
		(fp_line
			(start -0.7874 -0.4064)
			(end 0.7874 -0.4064)
			(stroke
				(width 0.1524)
				(type default)
			)
			(layer "F.SilkS")
		)
		(fp_line
			(start 0.67945 0.3048)
			(end 0.120396 0.3048)
			(stroke
				(width 0.1)
				(type default)
			)
			(layer "F.Fab")
		)
		(fp_line
			(start 0.67945 -0.3048)
			(end 0.67945 0.3048)
			(stroke
				(width 0.1)
				(type default)
			)
			(layer "F.Fab")
		)
		(fp_line
			(start 0.12065 -0.2794)
			(end 0.12065 -0.3048)
			(stroke
				(width 0.1)
				(type default)
			)
			(layer "F.Fab")
		)
		(fp_line
			(start 0.12065 -0.3048)
			(end 0.67945 -0.3048)
			(stroke
				(width 0.1)
				(type default)
			)
			(layer "F.Fab")
		)
		(fp_line
			(start 0.120396 0.3048)
			(end 0.120396 0.2794)
			(stroke
				(width 0.1)
				(type default)
			)
			(layer "F.Fab")
		)
		(fp_line
			(start 0.120396 0.2794)
			(end -0.12065 0.2794)
			(stroke
				(width 0.1)
				(type default)
			)
			(layer "F.Fab")
		)
		(fp_line
			(start -0.12065 0.3048)
			(end -0.67945 0.3048)
			(stroke
				(width 0.1)
				(type default)
			)
			(layer "F.Fab")
		)
		(fp_line
			(start -0.12065 0.2794)
			(end -0.12065 0.3048)
			(stroke
				(width 0.1)
				(type default)
			)
			(layer "F.Fab")
		)
		(fp_line
			(start -0.12065 -0.2794)
			(end 0.12065 -0.2794)
			(stroke
				(width 0.1)
				(type default)
			)
			(layer "F.Fab")
		)
		(fp_line
			(start -0.12065 -0.305054)
			(end -0.12065 -0.2794)
			(stroke
				(width 0.1)
				(type default)
			)
			(layer "F.Fab")
		)
		(fp_line
			(start -0.67945 0.3048)
			(end -0.67945 -0.305054)
			(stroke
				(width 0.1)
				(type default)
			)
			(layer "F.Fab")
		)
		(fp_line
			(start -0.67945 -0.305054)
			(end -0.12065 -0.305054)
			(stroke
				(width 0.1)
				(type default)
			)
			(layer "F.Fab")
		)
		(pad "1" smd circle
			(at -0.40005 0 180)
			(size 0 0)
			(layers "F.Cu" "F.Mask" "F.Paste")
			(net "P3V3_AUX")
		)
		(pad "2" smd circle
			(at 0.40005 0 180)
			(size 0 0)
			(layers "F.Cu" "F.Mask" "F.Paste")
			(net "SKU_ID_1")
		)
	)
	(footprint ""
		(layer "F.Cu")
		(at 402.717 -21.59)
		(property "Reference" "PR100"
			(at -7.7216 1.55067 0)
			(unlocked yes)
			(layer "F.SilkS")
			(effects
				(font
					(size 0.7874 0.5842)
					(thickness 0.1524)
				)
				(justify left)
			)
		)
		(property "Value" ""
			(at 0 0 0)
			(layer "F.Fab")
			(effects
				(font
					(size 1.27 1.27)
				)
			)
		)
		(duplicate_pad_numbers_are_jumpers no)
		(fp_line
			(start -3.62712 -1.8796)
			(end -3.62712 1.8796)
			(stroke
				(width 0.1524)
				(type default)
			)
			(layer "F.SilkS")
		)
		(fp_line
			(start -3.62712 1.8796)
			(end 3.62712 1.8796)
			(stroke
				(width 0.1524)
				(type default)
			)
			(layer "F.SilkS")
		)
		(fp_line
			(start 3.62712 -1.8796)
			(end -3.62712 -1.8796)
			(stroke
				(width 0.1524)
				(type default)
			)
			(layer "F.SilkS")
		)
		(fp_line
			(start 3.62712 1.8796)
			(end 3.62712 -1.8796)
			(stroke
				(width 0.1524)
				(type default)
			)
			(layer "F.SilkS")
		)
		(fp_line
			(start -3.299968 -1.700022)
			(end -3.299968 1.700022)
			(stroke
				(width 0.1)
				(type default)
			)
			(layer "F.Fab")
		)
		(fp_line
			(start -3.299968 1.700022)
			(end 3.299968 1.700022)
			(stroke
				(width 0.1)
				(type default)
			)
			(layer "F.Fab")
		)
		(fp_line
			(start 3.299968 -1.700022)
			(end -3.299968 -1.700022)
			(stroke
				(width 0.1)
				(type default)
			)
			(layer "F.Fab")
		)
		(fp_line
			(start 3.299968 1.700022)
			(end 3.299968 -1.700022)
			(stroke
				(width 0.1)
				(type default)
			)
			(layer "F.Fab")
		)
		(pad "1" smd rect
			(at -2.70002 0)
			(size 1.6002 3.5052)
			(layers "F.Cu" "F.Mask" "F.Paste")
			(net "P52V_HS1_EN_DISCHARGE_VBE_R")
		)
		(pad "2" smd rect
			(at 2.70002 0)
			(size 1.6002 3.5052)
			(layers "F.Cu" "F.Mask" "F.Paste")
			(net "GND")
		)
	)
	(footprint ""
		(layer "F.Cu")
		(at 427.228 -40.386)
		(property "Reference" "R136"
			(at 0 0 0)
			(layer "F.SilkS")
			(hide yes)
			(effects
				(font
					(size 1.27 1.27)
				)
			)
		)
		(property "Value" ""
			(at 0 0 0)
			(layer "F.Fab")
			(effects
				(font
					(size 1.27 1.27)
				)
			)
		)
		(duplicate_pad_numbers_are_jumpers no)
		(fp_line
			(start -0.7874 -0.4064)
			(end 0.7874 -0.4064)
			(stroke
				(width 0.1524)
				(type default)
			)
			(layer "F.SilkS")
		)
		(fp_line
			(start -0.7874 0.4064)
			(end -0.7874 -0.4064)
			(stroke
				(width 0.1524)
				(type default)
			)
			(layer "F.SilkS")
		)
		(fp_line
			(start 0.7874 -0.4064)
			(end 0.7874 0.4064)
			(stroke
				(width 0.1524)
				(type default)
			)
			(layer "F.SilkS")
		)
		(fp_line
			(start 0.7874 0.4064)
			(end -0.7874 0.4064)
			(stroke
				(width 0.1524)
				(type default)
			)
			(layer "F.SilkS")
		)
		(fp_line
			(start -0.67945 -0.305054)
			(end -0.12065 -0.305054)
			(stroke
				(width 0.1)
				(type default)
			)
			(layer "F.Fab")
		)
		(fp_line
			(start -0.67945 0.3048)
			(end -0.67945 -0.305054)
			(stroke
				(width 0.1)
				(type default)
			)
			(layer "F.Fab")
		)
		(fp_line
			(start -0.12065 -0.305054)
			(end -0.12065 -0.2794)
			(stroke
				(width 0.1)
				(type default)
			)
			(layer "F.Fab")
		)
		(fp_line
			(start -0.12065 -0.2794)
			(end 0.12065 -0.2794)
			(stroke
				(width 0.1)
				(type default)
			)
			(layer "F.Fab")
		)
		(fp_line
			(start -0.12065 0.2794)
			(end -0.12065 0.3048)
			(stroke
				(width 0.1)
				(type default)
			)
			(layer "F.Fab")
		)
		(fp_line
			(start -0.12065 0.3048)
			(end -0.67945 0.3048)
			(stroke
				(width 0.1)
				(type default)
			)
			(layer "F.Fab")
		)
		(fp_line
			(start 0.120396 0.2794)
			(end -0.12065 0.2794)
			(stroke
				(width 0.1)
				(type default)
			)
			(layer "F.Fab")
		)
		(fp_line
			(start 0.120396 0.3048)
			(end 0.120396 0.2794)
			(stroke
				(width 0.1)
				(type default)
			)
			(layer "F.Fab")
		)
		(fp_line
			(start 0.12065 -0.3048)
			(end 0.67945 -0.3048)
			(stroke
				(width 0.1)
				(type default)
			)
			(layer "F.Fab")
		)
		(fp_line
			(start 0.12065 -0.2794)
			(end 0.12065 -0.3048)
			(stroke
				(width 0.1)
				(type default)
			)
			(layer "F.Fab")
		)
		(fp_line
			(start 0.67945 -0.3048)
			(end 0.67945 0.3048)
			(stroke
				(width 0.1)
				(type default)
			)
			(layer "F.Fab")
		)
		(fp_line
			(start 0.67945 0.3048)
			(end 0.120396 0.3048)
			(stroke
				(width 0.1)
				(type default)
			)
			(layer "F.Fab")
		)
		(pad "1" smd circle
			(at -0.40005 0)
			(size 0 0)
			(layers "F.Cu" "F.Mask" "F.Paste")
			(net "BOARD_ID_2")
		)
		(pad "2" smd circle
			(at 0.40005 0)
			(size 0 0)
			(layers "F.Cu" "F.Mask" "F.Paste")
			(net "GND")
		)
	)
	(footprint ""
		(layer "F.Cu")
		(at 378.079 -119.38)
		(property "Reference" "PC30"
			(at 5.3594 -4.67233 0)
			(unlocked yes)
			(layer "F.SilkS")
			(effects
				(font
					(size 0.7874 0.5842)
					(thickness 0.1524)
				)
				(justify left)
			)
		)
		(property "Value" ""
			(at 0 0 0)
			(layer "F.Fab")
			(effects
				(font
					(size 1.27 1.27)
				)
			)
		)
		(duplicate_pad_numbers_are_jumpers no)
		(fp_line
			(start -9.253728 3.750056)
			(end 9.249918 3.750056)
			(stroke
				(width 0.1524)
				(type default)
			)
			(layer "F.SilkS")
		)
		(fp_line
			(start 0 3.750056)
			(end -9.253728 3.750056)
			(stroke
				(width 0.1524)
				(type default)
			)
			(layer "F.SilkS")
		)
		(fp_circle
			(center 0 3.750056)
			(end 9.249918 3.750056)
			(stroke
				(width 0.1524)
				(type default)
			)
			(fill no)
			(layer "F.SilkS")
		)
		(fp_poly
			(pts
				(arc
					(start 9.249918 3.750056)
					(mid 0 12.999974)
					(end -9.249918 3.750056)
				)
			)
			(stroke
				(width 0)
				(type default)
			)
			(fill yes)
			(layer "F.SilkS")
		)
		(fp_circle
			(center 0 3.750056)
			(end 9.249918 3.750056)
			(stroke
				(width 0.1)
				(type default)
			)
			(fill no)
			(layer "F.Fab")
		)
		(pad "1" thru_hole rect
			(at 0 0)
			(size 1.778 1.778)
			(drill 1.27)
			(layers "*.Cu" "*.Mask")
			(remove_unused_layers no)
			(net "P52V_HS1")
			(clearance 0)
			(padstack
				(mode front_inner_back)
				(layer "Inner"
					(shape circle)
					(size 1.778 1.778)
					(clearance 0)
				)
				(layer "B.Cu"
					(shape rect)
					(size 1.778 1.778)
					(clearance 0)
				)
			)
		)
		(pad "2" thru_hole circle
			(at 0 7.500112)
			(size 1.778 1.778)
			(drill 1.27)
			(layers "*.Cu" "*.Mask")
			(remove_unused_layers no)
			(net "GND")
			(clearance 0)
		)
	)
	(footprint ""
		(layer "F.Cu")
		(at 427.228 -44.577)
		(property "Reference" "R99"
			(at 0 0 0)
			(layer "F.SilkS")
			(hide yes)
			(effects
				(font
					(size 1.27 1.27)
				)
			)
		)
		(property "Value" ""
			(at 0 0 0)
			(layer "F.Fab")
			(effects
				(font
					(size 1.27 1.27)
				)
			)
		)
		(duplicate_pad_numbers_are_jumpers no)
		(fp_line
			(start -0.7874 -0.4064)
			(end 0.7874 -0.4064)
			(stroke
				(width 0.1524)
				(type default)
			)
			(layer "F.SilkS")
		)
		(fp_line
			(start -0.7874 0.4064)
			(end -0.7874 -0.4064)
			(stroke
				(width 0.1524)
				(type default)
			)
			(layer "F.SilkS")
		)
		(fp_line
			(start 0.7874 -0.4064)
			(end 0.7874 0.4064)
			(stroke
				(width 0.1524)
				(type default)
			)
			(layer "F.SilkS")
		)
		(fp_line
			(start 0.7874 0.4064)
			(end -0.7874 0.4064)
			(stroke
				(width 0.1524)
				(type default)
			)
			(layer "F.SilkS")
		)
		(fp_line
			(start -0.67945 -0.305054)
			(end -0.12065 -0.305054)
			(stroke
				(width 0.1)
				(type default)
			)
			(layer "F.Fab")
		)
		(fp_line
			(start -0.67945 0.3048)
			(end -0.67945 -0.305054)
			(stroke
				(width 0.1)
				(type default)
			)
			(layer "F.Fab")
		)
		(fp_line
			(start -0.12065 -0.305054)
			(end -0.12065 -0.2794)
			(stroke
				(width 0.1)
				(type default)
			)
			(layer "F.Fab")
		)
		(fp_line
			(start -0.12065 -0.2794)
			(end 0.12065 -0.2794)
			(stroke
				(width 0.1)
				(type default)
			)
			(layer "F.Fab")
		)
		(fp_line
			(start -0.12065 0.2794)
			(end -0.12065 0.3048)
			(stroke
				(width 0.1)
				(type default)
			)
			(layer "F.Fab")
		)
		(fp_line
			(start -0.12065 0.3048)
			(end -0.67945 0.3048)
			(stroke
				(width 0.1)
				(type default)
			)
			(layer "F.Fab")
		)
		(fp_line
			(start 0.120396 0.2794)
			(end -0.12065 0.2794)
			(stroke
				(width 0.1)
				(type default)
			)
			(layer "F.Fab")
		)
		(fp_line
			(start 0.120396 0.3048)
			(end 0.120396 0.2794)
			(stroke
				(width 0.1)
				(type default)
			)
			(layer "F.Fab")
		)
		(fp_line
			(start 0.12065 -0.3048)
			(end 0.67945 -0.3048)
			(stroke
				(width 0.1)
				(type default)
			)
			(layer "F.Fab")
		)
		(fp_line
			(start 0.12065 -0.2794)
			(end 0.12065 -0.3048)
			(stroke
				(width 0.1)
				(type default)
			)
			(layer "F.Fab")
		)
		(fp_line
			(start 0.67945 -0.3048)
			(end 0.67945 0.3048)
			(stroke
				(width 0.1)
				(type default)
			)
			(layer "F.Fab")
		)
		(fp_line
			(start 0.67945 0.3048)
			(end 0.120396 0.3048)
			(stroke
				(width 0.1)
				(type default)
			)
			(layer "F.Fab")
		)
		(pad "1" smd circle
			(at -0.40005 0)
			(size 0 0)
			(layers "F.Cu" "F.Mask" "F.Paste")
			(net "SKU_ID_2")
		)
		(pad "2" smd circle
			(at 0.40005 0)
			(size 0 0)
			(layers "F.Cu" "F.Mask" "F.Paste")
			(net "GND")
		)
	)
	(footprint ""
		(layer "F.Cu")
		(at 80.518 -17.907 -90)
		(property "Reference" "R75"
			(at 0 0 270)
			(layer "F.SilkS")
			(hide yes)
			(effects
				(font
					(size 1.27 1.27)
				)
			)
		)
		(property "Value" ""
			(at 0 0 270)
			(layer "F.Fab")
			(effects
				(font
					(size 1.27 1.27)
				)
			)
		)
		(duplicate_pad_numbers_are_jumpers no)
		(fp_line
			(start -0.7874 0.4064)
			(end -0.7874 -0.4064)
			(stroke
				(width 0.1524)
				(type default)
			)
			(layer "F.SilkS")
		)
		(fp_line
			(start 0.7874 0.4064)
			(end -0.7874 0.4064)
			(stroke
				(width 0.1524)
				(type default)
			)
			(layer "F.SilkS")
		)
		(fp_line
			(start -0.7874 -0.4064)
			(end 0.7874 -0.4064)
			(stroke
				(width 0.1524)
				(type default)
			)
			(layer "F.SilkS")
		)
		(fp_line
			(start 0.7874 -0.4064)
			(end 0.7874 0.4064)
			(stroke
				(width 0.1524)
				(type default)
			)
			(layer "F.SilkS")
		)
		(fp_line
			(start -0.67945 0.3048)
			(end -0.67945 -0.305054)
			(stroke
				(width 0.1)
				(type default)
			)
			(layer "F.Fab")
		)
		(fp_line
			(start -0.12065 0.3048)
			(end -0.67945 0.3048)
			(stroke
				(width 0.1)
				(type default)
			)
			(layer "F.Fab")
		)
		(fp_line
			(start 0.120396 0.3048)
			(end 0.120396 0.2794)
			(stroke
				(width 0.1)
				(type default)
			)
			(layer "F.Fab")
		)
		(fp_line
			(start 0.67945 0.3048)
			(end 0.120396 0.3048)
			(stroke
				(width 0.1)
				(type default)
			)
			(layer "F.Fab")
		)
		(fp_line
			(start -0.12065 0.2794)
			(end -0.12065 0.3048)
			(stroke
				(width 0.1)
				(type default)
			)
			(layer "F.Fab")
		)
		(fp_line
			(start 0.120396 0.2794)
			(end -0.12065 0.2794)
			(stroke
				(width 0.1)
				(type default)
			)
			(layer "F.Fab")
		)
		(fp_line
			(start -0.12065 -0.2794)
			(end 0.12065 -0.2794)
			(stroke
				(width 0.1)
				(type default)
			)
			(layer "F.Fab")
		)
		(fp_line
			(start 0.12065 -0.2794)
			(end 0.12065 -0.3048)
			(stroke
				(width 0.1)
				(type default)
			)
			(layer "F.Fab")
		)
		(fp_line
			(start 0.12065 -0.3048)
			(end 0.67945 -0.3048)
			(stroke
				(width 0.1)
				(type default)
			)
			(layer "F.Fab")
		)
		(fp_line
			(start 0.67945 -0.3048)
			(end 0.67945 0.3048)
			(stroke
				(width 0.1)
				(type default)
			)
			(layer "F.Fab")
		)
		(fp_line
			(start -0.67945 -0.305054)
			(end -0.12065 -0.305054)
			(stroke
				(width 0.1)
				(type default)
			)
			(layer "F.Fab")
		)
		(fp_line
			(start -0.12065 -0.305054)
			(end -0.12065 -0.2794)
			(stroke
				(width 0.1)
				(type default)
			)
			(layer "F.Fab")
		)
		(pad "1" smd circle
			(at -0.40005 0 270)
			(size 0 0)
			(layers "F.Cu" "F.Mask" "F.Paste")
			(net "SMB_PDB_FAN_1_SCL")
		)
		(pad "2" smd circle
			(at 0.40005 0 270)
			(size 0 0)
			(layers "F.Cu" "F.Mask" "F.Paste")
			(net "SMB_PDB_FAN_1_R_SCL")
		)
	)
	(footprint ""
		(layer "F.Cu")
		(at 397.637 -58.42)
		(property "Reference" "PC43"
			(at -8.8646 -4.67233 0)
			(unlocked yes)
			(layer "F.SilkS")
			(effects
				(font
					(size 0.7874 0.5842)
					(thickness 0.1524)
				)
				(justify left)
			)
		)
		(property "Value" ""
			(at 0 0 0)
			(layer "F.Fab")
			(effects
				(font
					(size 1.27 1.27)
				)
			)
		)
		(duplicate_pad_numbers_are_jumpers no)
		(fp_line
			(start -9.253728 3.750056)
			(end 9.249918 3.750056)
			(stroke
				(width 0.1524)
				(type default)
			)
			(layer "F.SilkS")
		)
		(fp_line
			(start 0 3.750056)
			(end -9.253728 3.750056)
			(stroke
				(width 0.1524)
				(type default)
			)
			(layer "F.SilkS")
		)
		(fp_circle
			(center 0 3.750056)
			(end 9.249918 3.750056)
			(stroke
				(width 0.1524)
				(type default)
			)
			(fill no)
			(layer "F.SilkS")
		)
		(fp_poly
			(pts
				(arc
					(start 9.249918 3.750056)
					(mid 0 12.999974)
					(end -9.249918 3.750056)
				)
			)
			(stroke
				(width 0)
				(type default)
			)
			(fill yes)
			(layer "F.SilkS")
		)
		(fp_circle
			(center 0 3.750056)
			(end 9.249918 3.750056)
			(stroke
				(width 0.1)
				(type default)
			)
			(fill no)
			(layer "F.Fab")
		)
		(pad "1" thru_hole rect
			(at 0 0)
			(size 1.778 1.778)
			(drill 1.27)
			(layers "*.Cu" "*.Mask")
			(remove_unused_layers no)
			(net "P52V_HS1")
			(clearance 0)
			(padstack
				(mode front_inner_back)
				(layer "Inner"
					(shape circle)
					(size 1.778 1.778)
					(clearance 0)
				)
				(layer "B.Cu"
					(shape rect)
					(size 1.778 1.778)
					(clearance 0)
				)
			)
		)
		(pad "2" thru_hole circle
			(at 0 7.500112)
			(size 1.778 1.778)
			(drill 1.27)
			(layers "*.Cu" "*.Mask")
			(remove_unused_layers no)
			(net "GND")
			(clearance 0)
		)
	)
	(footprint ""
		(layer "F.Cu")
		(at 278.6634 -73.025 180)
		(property "Reference" "R372"
			(at 0 0 180)
			(layer "F.SilkS")
			(hide yes)
			(effects
				(font
					(size 1.27 1.27)
				)
			)
		)
		(property "Value" ""
			(at 0 0 180)
			(layer "F.Fab")
			(effects
				(font
					(size 1.27 1.27)
				)
			)
		)
		(duplicate_pad_numbers_are_jumpers no)
		(fp_line
			(start 0.7874 0.4064)
			(end -0.7874 0.4064)
			(stroke
				(width 0.1524)
				(type default)
			)
			(layer "F.SilkS")
		)
		(fp_line
			(start 0.7874 -0.4064)
			(end 0.7874 0.4064)
			(stroke
				(width 0.1524)
				(type default)
			)
			(layer "F.SilkS")
		)
		(fp_line
			(start -0.7874 0.4064)
			(end -0.7874 -0.4064)
			(stroke
				(width 0.1524)
				(type default)
			)
			(layer "F.SilkS")
		)
		(fp_line
			(start -0.7874 -0.4064)
			(end 0.7874 -0.4064)
			(stroke
				(width 0.1524)
				(type default)
			)
			(layer "F.SilkS")
		)
		(fp_line
			(start 0.67945 0.3048)
			(end 0.120396 0.3048)
			(stroke
				(width 0.1)
				(type default)
			)
			(layer "F.Fab")
		)
		(fp_line
			(start 0.67945 -0.3048)
			(end 0.67945 0.3048)
			(stroke
				(width 0.1)
				(type default)
			)
			(layer "F.Fab")
		)
		(fp_line
			(start 0.12065 -0.2794)
			(end 0.12065 -0.3048)
			(stroke
				(width 0.1)
				(type default)
			)
			(layer "F.Fab")
		)
		(fp_line
			(start 0.12065 -0.3048)
			(end 0.67945 -0.3048)
			(stroke
				(width 0.1)
				(type default)
			)
			(layer "F.Fab")
		)
		(fp_line
			(start 0.120396 0.3048)
			(end 0.120396 0.2794)
			(stroke
				(width 0.1)
				(type default)
			)
			(layer "F.Fab")
		)
		(fp_line
			(start 0.120396 0.2794)
			(end -0.12065 0.2794)
			(stroke
				(width 0.1)
				(type default)
			)
			(layer "F.Fab")
		)
		(fp_line
			(start -0.12065 0.3048)
			(end -0.67945 0.3048)
			(stroke
				(width 0.1)
				(type default)
			)
			(layer "F.Fab")
		)
		(fp_line
			(start -0.12065 0.2794)
			(end -0.12065 0.3048)
			(stroke
				(width 0.1)
				(type default)
			)
			(layer "F.Fab")
		)
		(fp_line
			(start -0.12065 -0.2794)
			(end 0.12065 -0.2794)
			(stroke
				(width 0.1)
				(type default)
			)
			(layer "F.Fab")
		)
		(fp_line
			(start -0.12065 -0.305054)
			(end -0.12065 -0.2794)
			(stroke
				(width 0.1)
				(type default)
			)
			(layer "F.Fab")
		)
		(fp_line
			(start -0.67945 0.3048)
			(end -0.67945 -0.305054)
			(stroke
				(width 0.1)
				(type default)
			)
			(layer "F.Fab")
		)
		(fp_line
			(start -0.67945 -0.305054)
			(end -0.12065 -0.305054)
			(stroke
				(width 0.1)
				(type default)
			)
			(layer "F.Fab")
		)
		(pad "1" smd circle
			(at -0.40005 0 180)
			(size 0 0)
			(layers "F.Cu" "F.Mask" "F.Paste")
			(net "P52V_HS1_VCAP")
		)
		(pad "2" smd circle
			(at 0.40005 0 180)
			(size 0 0)
			(layers "F.Cu" "F.Mask" "F.Paste")
			(net "P52V_HS1_ADR1")
		)
	)
	(footprint ""
		(layer "F.Cu")
		(at 61.92139 -58.42)
		(property "Reference" "PC47"
			(at -8.17499 -5.05333 0)
			(unlocked yes)
			(layer "F.SilkS")
			(effects
				(font
					(size 0.7874 0.5842)
					(thickness 0.1524)
				)
				(justify left)
			)
		)
		(property "Value" ""
			(at 0 0 0)
			(layer "F.Fab")
			(effects
				(font
					(size 1.27 1.27)
				)
			)
		)
		(duplicate_pad_numbers_are_jumpers no)
		(fp_line
			(start -9.253728 3.750056)
			(end 9.249918 3.750056)
			(stroke
				(width 0.1524)
				(type default)
			)
			(layer "F.SilkS")
		)
		(fp_line
			(start 0 3.750056)
			(end -9.253728 3.750056)
			(stroke
				(width 0.1524)
				(type default)
			)
			(layer "F.SilkS")
		)
		(fp_circle
			(center 0 3.750056)
			(end 9.249918 3.750056)
			(stroke
				(width 0.1524)
				(type default)
			)
			(fill no)
			(layer "F.SilkS")
		)
		(fp_poly
			(pts
				(arc
					(start 9.249918 3.750056)
					(mid 0 12.999974)
					(end -9.249918 3.750056)
				)
			)
			(stroke
				(width 0)
				(type default)
			)
			(fill yes)
			(layer "F.SilkS")
		)
		(fp_circle
			(center 0 3.750056)
			(end 9.249918 3.750056)
			(stroke
				(width 0.1)
				(type default)
			)
			(fill no)
			(layer "F.Fab")
		)
		(pad "1" thru_hole rect
			(at 0 0)
			(size 1.778 1.778)
			(drill 1.27)
			(layers "*.Cu" "*.Mask")
			(remove_unused_layers no)
			(net "P52V_HS2")
			(clearance 0)
			(padstack
				(mode front_inner_back)
				(layer "Inner"
					(shape circle)
					(size 1.778 1.778)
					(clearance 0)
				)
				(layer "B.Cu"
					(shape rect)
					(size 1.778 1.778)
					(clearance 0)
				)
			)
		)
		(pad "2" thru_hole circle
			(at 0 7.500112)
			(size 1.778 1.778)
			(drill 1.27)
			(layers "*.Cu" "*.Mask")
			(remove_unused_layers no)
			(net "GND")
			(clearance 0)
		)
	)
	(footprint ""
		(layer "F.Cu")
		(at 304.616358 -63.373)
		(property "Reference" "PR479"
			(at -3.943858 4.73837 0)
			(unlocked yes)
			(layer "F.SilkS")
			(effects
				(font
					(size 0.7874 0.5842)
					(thickness 0.1524)
				)
				(justify left)
			)
		)
		(property "Value" ""
			(at 0 0 0)
			(layer "F.Fab")
			(effects
				(font
					(size 1.27 1.27)
				)
			)
		)
		(duplicate_pad_numbers_are_jumpers no)
		(fp_line
			(start -3.9878 -3.5814)
			(end 3.9878 -3.5814)
			(stroke
				(width 0.1524)
				(type default)
			)
			(layer "F.SilkS")
		)
		(fp_line
			(start -3.9878 3.5814)
			(end -3.9878 -3.5814)
			(stroke
				(width 0.1524)
				(type default)
			)
			(layer "F.SilkS")
		)
		(fp_line
			(start 3.9878 -3.5814)
			(end 3.9878 3.5814)
			(stroke
				(width 0.1524)
				(type default)
			)
			(layer "F.SilkS")
		)
		(fp_line
			(start 3.9878 3.5814)
			(end -3.9878 3.5814)
			(stroke
				(width 0.1524)
				(type default)
			)
			(layer "F.SilkS")
		)
		(fp_line
			(start -3.5306 -3.353054)
			(end 3.5306 -3.353054)
			(stroke
				(width 0.1)
				(type default)
			)
			(layer "F.Fab")
		)
		(fp_line
			(start -3.5306 3.353054)
			(end -3.5306 -3.353054)
			(stroke
				(width 0.1)
				(type default)
			)
			(layer "F.Fab")
		)
		(fp_line
			(start 3.5306 -3.353054)
			(end 3.5306 3.353054)
			(stroke
				(width 0.1)
				(type default)
			)
			(layer "F.Fab")
		)
		(fp_line
			(start 3.5306 3.353054)
			(end -3.5306 3.353054)
			(stroke
				(width 0.1)
				(type default)
			)
			(layer "F.Fab")
		)
		(pad "1A" smd rect
			(at -2.249932 0 180)
			(size 3.2004 6.858)
			(layers "F.Cu" "F.Mask" "F.Paste")
			(net "P52V_1")
		)
		(pad "1B" smd rect
			(at -0.776732 0)
			(size 0.254 0.508)
			(layers "F.Cu" "F.Mask" "F.Paste")
			(net "P52V_HS1_SENSE_P_R1")
		)
		(pad "2A" smd rect
			(at 2.249932 0 180)
			(size 3.2004 6.858)
			(layers "F.Cu" "F.Mask" "F.Paste")
			(net "P52V_HS1_DRAIN_1")
		)
		(pad "2B" smd rect
			(at 0.776732 0)
			(size 0.254 0.508)
			(layers "F.Cu" "F.Mask" "F.Paste")
			(net "P52V_HS1_SENSE_N_R1")
		)
	)
	(footprint ""
		(layer "F.Cu")
		(at 432.943 -52.832)
		(property "Reference" "R5899"
			(at 0 0 0)
			(layer "F.SilkS")
			(hide yes)
			(effects
				(font
					(size 1.27 1.27)
				)
			)
		)
		(property "Value" ""
			(at 0 0 0)
			(layer "F.Fab")
			(effects
				(font
					(size 1.27 1.27)
				)
			)
		)
		(duplicate_pad_numbers_are_jumpers no)
		(fp_line
			(start -0.7874 -0.4064)
			(end 0.7874 -0.4064)
			(stroke
				(width 0.1524)
				(type default)
			)
			(layer "F.SilkS")
		)
		(fp_line
			(start -0.7874 0.4064)
			(end -0.7874 -0.4064)
			(stroke
				(width 0.1524)
				(type default)
			)
			(layer "F.SilkS")
		)
		(fp_line
			(start 0.7874 -0.4064)
			(end 0.7874 0.4064)
			(stroke
				(width 0.1524)
				(type default)
			)
			(layer "F.SilkS")
		)
		(fp_line
			(start 0.7874 0.4064)
			(end -0.7874 0.4064)
			(stroke
				(width 0.1524)
				(type default)
			)
			(layer "F.SilkS")
		)
		(fp_line
			(start -0.67945 -0.305054)
			(end -0.12065 -0.305054)
			(stroke
				(width 0.1)
				(type default)
			)
			(layer "F.Fab")
		)
		(fp_line
			(start -0.67945 0.3048)
			(end -0.67945 -0.305054)
			(stroke
				(width 0.1)
				(type default)
			)
			(layer "F.Fab")
		)
		(fp_line
			(start -0.12065 -0.305054)
			(end -0.12065 -0.2794)
			(stroke
				(width 0.1)
				(type default)
			)
			(layer "F.Fab")
		)
		(fp_line
			(start -0.12065 -0.2794)
			(end 0.12065 -0.2794)
			(stroke
				(width 0.1)
				(type default)
			)
			(layer "F.Fab")
		)
		(fp_line
			(start -0.12065 0.2794)
			(end -0.12065 0.3048)
			(stroke
				(width 0.1)
				(type default)
			)
			(layer "F.Fab")
		)
		(fp_line
			(start -0.12065 0.3048)
			(end -0.67945 0.3048)
			(stroke
				(width 0.1)
				(type default)
			)
			(layer "F.Fab")
		)
		(fp_line
			(start 0.120396 0.2794)
			(end -0.12065 0.2794)
			(stroke
				(width 0.1)
				(type default)
			)
			(layer "F.Fab")
		)
		(fp_line
			(start 0.120396 0.3048)
			(end 0.120396 0.2794)
			(stroke
				(width 0.1)
				(type default)
			)
			(layer "F.Fab")
		)
		(fp_line
			(start 0.12065 -0.3048)
			(end 0.67945 -0.3048)
			(stroke
				(width 0.1)
				(type default)
			)
			(layer "F.Fab")
		)
		(fp_line
			(start 0.12065 -0.2794)
			(end 0.12065 -0.3048)
			(stroke
				(width 0.1)
				(type default)
			)
			(layer "F.Fab")
		)
		(fp_line
			(start 0.67945 -0.3048)
			(end 0.67945 0.3048)
			(stroke
				(width 0.1)
				(type default)
			)
			(layer "F.Fab")
		)
		(fp_line
			(start 0.67945 0.3048)
			(end 0.120396 0.3048)
			(stroke
				(width 0.1)
				(type default)
			)
			(layer "F.Fab")
		)
		(pad "1" smd circle
			(at -0.40005 0)
			(size 0 0)
			(layers "F.Cu" "F.Mask" "F.Paste")
			(net "GND")
		)
		(pad "2" smd circle
			(at 0.40005 0)
			(size 0 0)
			(layers "F.Cu" "F.Mask" "F.Paste")
			(net "PWRGD_P52V_HS_PG_R2")
		)
	)
	(footprint ""
		(layer "F.Cu")
		(at 142.93342 -39.4462 180)
		(property "Reference" "PR7039"
			(at 0 0 180)
			(layer "F.SilkS")
			(hide yes)
			(effects
				(font
					(size 1.27 1.27)
				)
			)
		)
		(property "Value" ""
			(at 0 0 180)
			(layer "F.Fab")
			(effects
				(font
					(size 1.27 1.27)
				)
			)
		)
		(duplicate_pad_numbers_are_jumpers no)
		(fp_line
			(start 0.7874 0.4064)
			(end -0.7874 0.4064)
			(stroke
				(width 0.1524)
				(type default)
			)
			(layer "F.SilkS")
		)
		(fp_line
			(start 0.7874 -0.4064)
			(end 0.7874 0.4064)
			(stroke
				(width 0.1524)
				(type default)
			)
			(layer "F.SilkS")
		)
		(fp_line
			(start -0.7874 0.4064)
			(end -0.7874 -0.4064)
			(stroke
				(width 0.1524)
				(type default)
			)
			(layer "F.SilkS")
		)
		(fp_line
			(start -0.7874 -0.4064)
			(end 0.7874 -0.4064)
			(stroke
				(width 0.1524)
				(type default)
			)
			(layer "F.SilkS")
		)
		(fp_line
			(start 0.67945 0.3048)
			(end 0.120396 0.3048)
			(stroke
				(width 0.1)
				(type default)
			)
			(layer "F.Fab")
		)
		(fp_line
			(start 0.67945 -0.3048)
			(end 0.67945 0.3048)
			(stroke
				(width 0.1)
				(type default)
			)
			(layer "F.Fab")
		)
		(fp_line
			(start 0.12065 -0.2794)
			(end 0.12065 -0.3048)
			(stroke
				(width 0.1)
				(type default)
			)
			(layer "F.Fab")
		)
		(fp_line
			(start 0.12065 -0.3048)
			(end 0.67945 -0.3048)
			(stroke
				(width 0.1)
				(type default)
			)
			(layer "F.Fab")
		)
		(fp_line
			(start 0.120396 0.3048)
			(end 0.120396 0.2794)
			(stroke
				(width 0.1)
				(type default)
			)
			(layer "F.Fab")
		)
		(fp_line
			(start 0.120396 0.2794)
			(end -0.12065 0.2794)
			(stroke
				(width 0.1)
				(type default)
			)
			(layer "F.Fab")
		)
		(fp_line
			(start -0.12065 0.3048)
			(end -0.67945 0.3048)
			(stroke
				(width 0.1)
				(type default)
			)
			(layer "F.Fab")
		)
		(fp_line
			(start -0.12065 0.2794)
			(end -0.12065 0.3048)
			(stroke
				(width 0.1)
				(type default)
			)
			(layer "F.Fab")
		)
		(fp_line
			(start -0.12065 -0.2794)
			(end 0.12065 -0.2794)
			(stroke
				(width 0.1)
				(type default)
			)
			(layer "F.Fab")
		)
		(fp_line
			(start -0.12065 -0.305054)
			(end -0.12065 -0.2794)
			(stroke
				(width 0.1)
				(type default)
			)
			(layer "F.Fab")
		)
		(fp_line
			(start -0.67945 0.3048)
			(end -0.67945 -0.305054)
			(stroke
				(width 0.1)
				(type default)
			)
			(layer "F.Fab")
		)
		(fp_line
			(start -0.67945 -0.305054)
			(end -0.12065 -0.305054)
			(stroke
				(width 0.1)
				(type default)
			)
			(layer "F.Fab")
		)
		(pad "1" smd circle
			(at -0.40005 0 180)
			(size 0 0)
			(layers "F.Cu" "F.Mask" "F.Paste")
			(net "P52V_HS2_4287_S2P")
		)
		(pad "2" smd circle
			(at 0.40005 0 180)
			(size 0 0)
			(layers "F.Cu" "F.Mask" "F.Paste")
			(net "P52V_HS2_4287_S2N")
		)
	)
	(footprint ""
		(layer "F.Cu")
		(at 450.445632 -89.48547 180)
		(property "Reference" "R392"
			(at 0 0 180)
			(layer "F.SilkS")
			(hide yes)
			(effects
				(font
					(size 1.27 1.27)
				)
			)
		)
		(property "Value" ""
			(at 0 0 180)
			(layer "F.Fab")
			(effects
				(font
					(size 1.27 1.27)
				)
			)
		)
		(duplicate_pad_numbers_are_jumpers no)
		(fp_line
			(start 0.7874 0.4064)
			(end -0.7874 0.4064)
			(stroke
				(width 0.1524)
				(type default)
			)
			(layer "F.SilkS")
		)
		(fp_line
			(start 0.7874 -0.4064)
			(end 0.7874 0.4064)
			(stroke
				(width 0.1524)
				(type default)
			)
			(layer "F.SilkS")
		)
		(fp_line
			(start -0.7874 0.4064)
			(end -0.7874 -0.4064)
			(stroke
				(width 0.1524)
				(type default)
			)
			(layer "F.SilkS")
		)
		(fp_line
			(start -0.7874 -0.4064)
			(end 0.7874 -0.4064)
			(stroke
				(width 0.1524)
				(type default)
			)
			(layer "F.SilkS")
		)
		(fp_line
			(start 0.67945 0.3048)
			(end 0.120396 0.3048)
			(stroke
				(width 0.1)
				(type default)
			)
			(layer "F.Fab")
		)
		(fp_line
			(start 0.67945 -0.3048)
			(end 0.67945 0.3048)
			(stroke
				(width 0.1)
				(type default)
			)
			(layer "F.Fab")
		)
		(fp_line
			(start 0.12065 -0.2794)
			(end 0.12065 -0.3048)
			(stroke
				(width 0.1)
				(type default)
			)
			(layer "F.Fab")
		)
		(fp_line
			(start 0.12065 -0.3048)
			(end 0.67945 -0.3048)
			(stroke
				(width 0.1)
				(type default)
			)
			(layer "F.Fab")
		)
		(fp_line
			(start 0.120396 0.3048)
			(end 0.120396 0.2794)
			(stroke
				(width 0.1)
				(type default)
			)
			(layer "F.Fab")
		)
		(fp_line
			(start 0.120396 0.2794)
			(end -0.12065 0.2794)
			(stroke
				(width 0.1)
				(type default)
			)
			(layer "F.Fab")
		)
		(fp_line
			(start -0.12065 0.3048)
			(end -0.67945 0.3048)
			(stroke
				(width 0.1)
				(type default)
			)
			(layer "F.Fab")
		)
		(fp_line
			(start -0.12065 0.2794)
			(end -0.12065 0.3048)
			(stroke
				(width 0.1)
				(type default)
			)
			(layer "F.Fab")
		)
		(fp_line
			(start -0.12065 -0.2794)
			(end 0.12065 -0.2794)
			(stroke
				(width 0.1)
				(type default)
			)
			(layer "F.Fab")
		)
		(fp_line
			(start -0.12065 -0.305054)
			(end -0.12065 -0.2794)
			(stroke
				(width 0.1)
				(type default)
			)
			(layer "F.Fab")
		)
		(fp_line
			(start -0.67945 0.3048)
			(end -0.67945 -0.305054)
			(stroke
				(width 0.1)
				(type default)
			)
			(layer "F.Fab")
		)
		(fp_line
			(start -0.67945 -0.305054)
			(end -0.12065 -0.305054)
			(stroke
				(width 0.1)
				(type default)
			)
			(layer "F.Fab")
		)
		(pad "1" smd rect
			(at -0.40005 0)
			(size 0.4572 0.508)
			(layers "F.Cu" "F.Mask" "F.Paste")
			(net "P12V_HPDB")
		)
		(pad "2" smd rect
			(at 0.40005 0)
			(size 0.4572 0.508)
			(layers "F.Cu" "F.Mask" "F.Paste")
			(net "P3V3_HPDB_EN")
		)
	)
	(footprint ""
		(layer "F.Cu")
		(at 33.85439 -34.671)
		(property "Reference" "R45"
			(at 0 0 0)
			(layer "F.SilkS")
			(hide yes)
			(effects
				(font
					(size 1.27 1.27)
				)
			)
		)
		(property "Value" ""
			(at 0 0 0)
			(layer "F.Fab")
			(effects
				(font
					(size 1.27 1.27)
				)
			)
		)
		(duplicate_pad_numbers_are_jumpers no)
		(fp_line
			(start -2.234946 -0.9271)
			(end 2.234946 -0.9271)
			(stroke
				(width 0.1524)
				(type default)
			)
			(layer "F.SilkS")
		)
		(fp_line
			(start -2.234946 0.9271)
			(end -2.234946 -0.9271)
			(stroke
				(width 0.1524)
				(type default)
			)
			(layer "F.SilkS")
		)
		(fp_line
			(start 2.234946 -0.9271)
			(end 2.234946 0.9271)
			(stroke
				(width 0.1524)
				(type default)
			)
			(layer "F.SilkS")
		)
		(fp_line
			(start 2.234946 0.9271)
			(end -2.234946 0.9271)
			(stroke
				(width 0.1524)
				(type default)
			)
			(layer "F.SilkS")
		)
		(fp_line
			(start -1.575054 -0.824992)
			(end -1.575054 0.824992)
			(stroke
				(width 0.1)
				(type default)
			)
			(layer "F.Fab")
		)
		(fp_line
			(start -1.575054 0.824992)
			(end 1.575054 0.824992)
			(stroke
				(width 0.1)
				(type default)
			)
			(layer "F.Fab")
		)
		(fp_line
			(start 1.575054 -0.824992)
			(end -1.575054 -0.824992)
			(stroke
				(width 0.1)
				(type default)
			)
			(layer "F.Fab")
		)
		(fp_line
			(start 1.575054 0.824992)
			(end 1.575054 -0.824992)
			(stroke
				(width 0.1)
				(type default)
			)
			(layer "F.Fab")
		)
		(pad "1" smd rect
			(at -1.599946 0)
			(size 1.016 1.6002)
			(layers "F.Cu" "F.Mask" "F.Paste")
			(net "LED_D2_R3")
		)
		(pad "2" smd rect
			(at 1.599946 0)
			(size 1.016 1.6002)
			(layers "F.Cu" "F.Mask" "F.Paste")
			(net "LED_D2_R4")
		)
	)
	(footprint ""
		(layer "F.Cu")
		(at 291.592 -63.881 180)
		(property "Reference" "PC4"
			(at 0 0 180)
			(layer "F.SilkS")
			(hide yes)
			(effects
				(font
					(size 1.27 1.27)
				)
			)
		)
		(property "Value" ""
			(at 0 0 180)
			(layer "F.Fab")
			(effects
				(font
					(size 1.27 1.27)
				)
			)
		)
		(duplicate_pad_numbers_are_jumpers no)
		(fp_line
			(start 0.7874 0.4064)
			(end -0.7874 0.4064)
			(stroke
				(width 0.1524)
				(type default)
			)
			(layer "F.SilkS")
		)
		(fp_line
			(start 0.7874 -0.4064)
			(end 0.7874 0.4064)
			(stroke
				(width 0.1524)
				(type default)
			)
			(layer "F.SilkS")
		)
		(fp_line
			(start -0.7874 0.4064)
			(end -0.7874 -0.4064)
			(stroke
				(width 0.1524)
				(type default)
			)
			(layer "F.SilkS")
		)
		(fp_line
			(start -0.7874 -0.4064)
			(end 0.7874 -0.4064)
			(stroke
				(width 0.1524)
				(type default)
			)
			(layer "F.SilkS")
		)
		(fp_line
			(start 0.67945 0.3048)
			(end 0.120396 0.3048)
			(stroke
				(width 0.1)
				(type default)
			)
			(layer "F.Fab")
		)
		(fp_line
			(start 0.67945 -0.3048)
			(end 0.67945 0.3048)
			(stroke
				(width 0.1)
				(type default)
			)
			(layer "F.Fab")
		)
		(fp_line
			(start 0.12065 -0.2794)
			(end 0.12065 -0.3048)
			(stroke
				(width 0.1)
				(type default)
			)
			(layer "F.Fab")
		)
		(fp_line
			(start 0.12065 -0.3048)
			(end 0.67945 -0.3048)
			(stroke
				(width 0.1)
				(type default)
			)
			(layer "F.Fab")
		)
		(fp_line
			(start 0.120396 0.3048)
			(end 0.120396 0.2794)
			(stroke
				(width 0.1)
				(type default)
			)
			(layer "F.Fab")
		)
		(fp_line
			(start 0.120396 0.2794)
			(end -0.12065 0.2794)
			(stroke
				(width 0.1)
				(type default)
			)
			(layer "F.Fab")
		)
		(fp_line
			(start -0.12065 0.3048)
			(end -0.67945 0.3048)
			(stroke
				(width 0.1)
				(type default)
			)
			(layer "F.Fab")
		)
		(fp_line
			(start -0.12065 0.2794)
			(end -0.12065 0.3048)
			(stroke
				(width 0.1)
				(type default)
			)
			(layer "F.Fab")
		)
		(fp_line
			(start -0.12065 -0.2794)
			(end 0.12065 -0.2794)
			(stroke
				(width 0.1)
				(type default)
			)
			(layer "F.Fab")
		)
		(fp_line
			(start -0.12065 -0.305054)
			(end -0.12065 -0.2794)
			(stroke
				(width 0.1)
				(type default)
			)
			(layer "F.Fab")
		)
		(fp_line
			(start -0.67945 0.3048)
			(end -0.67945 -0.305054)
			(stroke
				(width 0.1)
				(type default)
			)
			(layer "F.Fab")
		)
		(fp_line
			(start -0.67945 -0.305054)
			(end -0.12065 -0.305054)
			(stroke
				(width 0.1)
				(type default)
			)
			(layer "F.Fab")
		)
		(pad "1" smd circle
			(at -0.40005 0 180)
			(size 0 0)
			(layers "F.Cu" "F.Mask" "F.Paste")
			(net "P52V_HS1_INTVCC")
		)
		(pad "2" smd circle
			(at 0.40005 0 180)
			(size 0 0)
			(layers "F.Cu" "F.Mask" "F.Paste")
			(net "GND")
		)
	)
	(footprint ""
		(layer "F.Cu")
		(at 397.637 -119.38)
		(property "Reference" "PC31"
			(at -8.2296 -4.67233 0)
			(unlocked yes)
			(layer "F.SilkS")
			(effects
				(font
					(size 0.7874 0.5842)
					(thickness 0.1524)
				)
				(justify left)
			)
		)
		(property "Value" ""
			(at 0 0 0)
			(layer "F.Fab")
			(effects
				(font
					(size 1.27 1.27)
				)
			)
		)
		(duplicate_pad_numbers_are_jumpers no)
		(fp_line
			(start -9.253728 3.750056)
			(end 9.249918 3.750056)
			(stroke
				(width 0.1524)
				(type default)
			)
			(layer "F.SilkS")
		)
		(fp_line
			(start 0 3.750056)
			(end -9.253728 3.750056)
			(stroke
				(width 0.1524)
				(type default)
			)
			(layer "F.SilkS")
		)
		(fp_circle
			(center 0 3.750056)
			(end 9.249918 3.750056)
			(stroke
				(width 0.1524)
				(type default)
			)
			(fill no)
			(layer "F.SilkS")
		)
		(fp_poly
			(pts
				(arc
					(start 9.249918 3.750056)
					(mid 0 12.999974)
					(end -9.249918 3.750056)
				)
			)
			(stroke
				(width 0)
				(type default)
			)
			(fill yes)
			(layer "F.SilkS")
		)
		(fp_circle
			(center 0 3.750056)
			(end 9.249918 3.750056)
			(stroke
				(width 0.1)
				(type default)
			)
			(fill no)
			(layer "F.Fab")
		)
		(pad "1" thru_hole rect
			(at 0 0)
			(size 1.778 1.778)
			(drill 1.27)
			(layers "*.Cu" "*.Mask")
			(remove_unused_layers no)
			(net "P52V_HS1")
			(clearance 0)
			(padstack
				(mode front_inner_back)
				(layer "Inner"
					(shape circle)
					(size 1.778 1.778)
					(clearance 0)
				)
				(layer "B.Cu"
					(shape rect)
					(size 1.778 1.778)
					(clearance 0)
				)
			)
		)
		(pad "2" thru_hole circle
			(at 0 7.500112)
			(size 1.778 1.778)
			(drill 1.27)
			(layers "*.Cu" "*.Mask")
			(remove_unused_layers no)
			(net "GND")
			(clearance 0)
		)
	)
	(footprint ""
		(layer "F.Cu")
		(at 321.945 -84.709)
		(property "Reference" "PQ37"
			(at -0.4572 -2.24663 0)
			(unlocked yes)
			(layer "F.SilkS")
			(effects
				(font
					(size 0.7874 0.5842)
					(thickness 0.1524)
				)
				(justify left)
			)
		)
		(property "Value" ""
			(at 0 0 0)
			(layer "F.Fab")
			(effects
				(font
					(size 1.27 1.27)
				)
			)
		)
		(duplicate_pad_numbers_are_jumpers no)
		(fp_line
			(start -1.905 -1.651)
			(end 1.905 -1.651)
			(stroke
				(width 0.1524)
				(type default)
			)
			(layer "F.SilkS")
		)
		(fp_line
			(start -1.905 1.651)
			(end -1.905 -1.651)
			(stroke
				(width 0.1524)
				(type default)
			)
			(layer "F.SilkS")
		)
		(fp_line
			(start 1.905 -1.651)
			(end 1.905 1.651)
			(stroke
				(width 0.1524)
				(type default)
			)
			(layer "F.SilkS")
		)
		(fp_line
			(start 1.905 1.651)
			(end -1.905 1.651)
			(stroke
				(width 0.1524)
				(type default)
			)
			(layer "F.SilkS")
		)
		(fp_line
			(start -1.249934 -1.169924)
			(end -0.649986 -1.169924)
			(stroke
				(width 0.1)
				(type default)
			)
			(layer "F.Fab")
		)
		(fp_line
			(start -1.249934 -0.729996)
			(end -1.249934 -1.169924)
			(stroke
				(width 0.1)
				(type default)
			)
			(layer "F.Fab")
		)
		(fp_line
			(start -1.249934 0.729996)
			(end -0.6985 0.729996)
			(stroke
				(width 0.1)
				(type default)
			)
			(layer "F.Fab")
		)
		(fp_line
			(start -1.249934 1.169924)
			(end -1.249934 0.729996)
			(stroke
				(width 0.1)
				(type default)
			)
			(layer "F.Fab")
		)
		(fp_line
			(start -0.6985 -0.729996)
			(end -1.249934 -0.729996)
			(stroke
				(width 0.1)
				(type default)
			)
			(layer "F.Fab")
		)
		(fp_line
			(start -0.6985 0.729996)
			(end -0.6985 -0.729996)
			(stroke
				(width 0.1)
				(type default)
			)
			(layer "F.Fab")
		)
		(fp_line
			(start -0.649986 -1.524)
			(end 0.6985 -1.524)
			(stroke
				(width 0.1)
				(type default)
			)
			(layer "F.Fab")
		)
		(fp_line
			(start -0.649986 -1.169924)
			(end -0.649986 -1.524)
			(stroke
				(width 0.1)
				(type default)
			)
			(layer "F.Fab")
		)
		(fp_line
			(start -0.649986 1.169924)
			(end -1.249934 1.169924)
			(stroke
				(width 0.1)
				(type default)
			)
			(layer "F.Fab")
		)
		(fp_line
			(start -0.649986 1.524)
			(end -0.649986 1.169924)
			(stroke
				(width 0.1)
				(type default)
			)
			(layer "F.Fab")
		)
		(fp_line
			(start 0.6985 -1.524)
			(end 0.6985 -0.219964)
			(stroke
				(width 0.1)
				(type default)
			)
			(layer "F.Fab")
		)
		(fp_line
			(start 0.6985 -0.219964)
			(end 1.249934 -0.219964)
			(stroke
				(width 0.1)
				(type default)
			)
			(layer "F.Fab")
		)
		(fp_line
			(start 0.6985 0.219964)
			(end 0.6985 1.524)
			(stroke
				(width 0.1)
				(type default)
			)
			(layer "F.Fab")
		)
		(fp_line
			(start 0.6985 1.524)
			(end -0.649986 1.524)
			(stroke
				(width 0.1)
				(type default)
			)
			(layer "F.Fab")
		)
		(fp_line
			(start 1.249934 -0.219964)
			(end 1.249934 0.219964)
			(stroke
				(width 0.1)
				(type default)
			)
			(layer "F.Fab")
		)
		(fp_line
			(start 1.249934 0.219964)
			(end 0.6985 0.219964)
			(stroke
				(width 0.1)
				(type default)
			)
			(layer "F.Fab")
		)
		(pad "B" smd rect
			(at -1.1176 -1.016 270)
			(size 1.016 1.27)
			(layers "F.Cu" "F.Mask" "F.Paste")
			(net "P52V_HS1_TEMP_R")
		)
		(pad "C" smd rect
			(at 1.1176 0 270)
			(size 1.016 1.27)
			(layers "F.Cu" "F.Mask" "F.Paste")
			(net "P52V_HS1_TEMP_R")
		)
		(pad "E" smd rect
			(at -1.1176 1.016 270)
			(size 1.016 1.27)
			(layers "F.Cu" "F.Mask" "F.Paste")
			(net "P52V_HS1_TEMPN_R")
		)
	)
	(footprint ""
		(layer "F.Cu")
		(at 271.2974 -78.105 180)
		(property "Reference" "PR483"
			(at 0 0 180)
			(layer "F.SilkS")
			(hide yes)
			(effects
				(font
					(size 1.27 1.27)
				)
			)
		)
		(property "Value" ""
			(at 0 0 180)
			(layer "F.Fab")
			(effects
				(font
					(size 1.27 1.27)
				)
			)
		)
		(duplicate_pad_numbers_are_jumpers no)
		(fp_line
			(start 0.7874 0.4064)
			(end -0.7874 0.4064)
			(stroke
				(width 0.1524)
				(type default)
			)
			(layer "F.SilkS")
		)
		(fp_line
			(start 0.7874 -0.4064)
			(end 0.7874 0.4064)
			(stroke
				(width 0.1524)
				(type default)
			)
			(layer "F.SilkS")
		)
		(fp_line
			(start -0.7874 0.4064)
			(end -0.7874 -0.4064)
			(stroke
				(width 0.1524)
				(type default)
			)
			(layer "F.SilkS")
		)
		(fp_line
			(start -0.7874 -0.4064)
			(end 0.7874 -0.4064)
			(stroke
				(width 0.1524)
				(type default)
			)
			(layer "F.SilkS")
		)
		(fp_line
			(start 0.67945 0.3048)
			(end 0.120396 0.3048)
			(stroke
				(width 0.1)
				(type default)
			)
			(layer "F.Fab")
		)
		(fp_line
			(start 0.67945 -0.3048)
			(end 0.67945 0.3048)
			(stroke
				(width 0.1)
				(type default)
			)
			(layer "F.Fab")
		)
		(fp_line
			(start 0.12065 -0.2794)
			(end 0.12065 -0.3048)
			(stroke
				(width 0.1)
				(type default)
			)
			(layer "F.Fab")
		)
		(fp_line
			(start 0.12065 -0.3048)
			(end 0.67945 -0.3048)
			(stroke
				(width 0.1)
				(type default)
			)
			(layer "F.Fab")
		)
		(fp_line
			(start 0.120396 0.3048)
			(end 0.120396 0.2794)
			(stroke
				(width 0.1)
				(type default)
			)
			(layer "F.Fab")
		)
		(fp_line
			(start 0.120396 0.2794)
			(end -0.12065 0.2794)
			(stroke
				(width 0.1)
				(type default)
			)
			(layer "F.Fab")
		)
		(fp_line
			(start -0.12065 0.3048)
			(end -0.67945 0.3048)
			(stroke
				(width 0.1)
				(type default)
			)
			(layer "F.Fab")
		)
		(fp_line
			(start -0.12065 0.2794)
			(end -0.12065 0.3048)
			(stroke
				(width 0.1)
				(type default)
			)
			(layer "F.Fab")
		)
		(fp_line
			(start -0.12065 -0.2794)
			(end 0.12065 -0.2794)
			(stroke
				(width 0.1)
				(type default)
			)
			(layer "F.Fab")
		)
		(fp_line
			(start -0.12065 -0.305054)
			(end -0.12065 -0.2794)
			(stroke
				(width 0.1)
				(type default)
			)
			(layer "F.Fab")
		)
		(fp_line
			(start -0.67945 0.3048)
			(end -0.67945 -0.305054)
			(stroke
				(width 0.1)
				(type default)
			)
			(layer "F.Fab")
		)
		(fp_line
			(start -0.67945 -0.305054)
			(end -0.12065 -0.305054)
			(stroke
				(width 0.1)
				(type default)
			)
			(layer "F.Fab")
		)
		(pad "1" smd circle
			(at -0.40005 0 180)
			(size 0 0)
			(layers "F.Cu" "F.Mask" "F.Paste")
			(net "P52V_HS1_UVLO_EN")
		)
		(pad "2" smd circle
			(at 0.40005 0 180)
			(size 0 0)
			(layers "F.Cu" "F.Mask" "F.Paste")
			(net "GND_FIELD_SIGNAL")
		)
	)
	(footprint ""
		(layer "F.Cu")
		(at 124.483876 -74.6506)
		(property "Reference" "PQ38"
			(at 8.913114 -3.609848 0)
			(unlocked yes)
			(layer "F.SilkS")
			(effects
				(font
					(size 0.7874 0.5842)
					(thickness 0.1524)
				)
				(justify left)
			)
		)
		(property "Value" ""
			(at 0 0 0)
			(layer "F.Fab")
			(effects
				(font
					(size 1.27 1.27)
				)
			)
		)
		(duplicate_pad_numbers_are_jumpers no)
		(fp_line
			(start -7.649972 -4.99999)
			(end -7.649972 -3.3274)
			(stroke
				(width 0.1524)
				(type default)
			)
			(layer "F.SilkS")
		)
		(fp_line
			(start -7.649972 -1.7526)
			(end -7.649972 1.7526)
			(stroke
				(width 0.1524)
				(type default)
			)
			(layer "F.SilkS")
		)
		(fp_line
			(start -7.649972 3.3274)
			(end -7.649972 4.99999)
			(stroke
				(width 0.1524)
				(type default)
			)
			(layer "F.SilkS")
		)
		(fp_line
			(start -7.649972 4.99999)
			(end 5.115814 4.99999)
			(stroke
				(width 0.1524)
				(type default)
			)
			(layer "F.SilkS")
		)
		(fp_line
			(start 5.115814 -4.99999)
			(end -7.649972 -4.99999)
			(stroke
				(width 0.1524)
				(type default)
			)
			(layer "F.SilkS")
		)
		(fp_line
			(start 7.630414 4.99999)
			(end 7.649972 4.99999)
			(stroke
				(width 0.1524)
				(type default)
			)
			(layer "F.SilkS")
		)
		(fp_line
			(start 7.649972 -4.99999)
			(end 7.630414 -4.99999)
			(stroke
				(width 0.1524)
				(type default)
			)
			(layer "F.SilkS")
		)
		(fp_line
			(start 7.649972 4.99999)
			(end 7.649972 -4.99999)
			(stroke
				(width 0.1524)
				(type default)
			)
			(layer "F.SilkS")
		)
		(fp_line
			(start -7.649972 -4.99999)
			(end -7.649972 4.99999)
			(stroke
				(width 0.1)
				(type default)
			)
			(layer "F.Fab")
		)
		(fp_line
			(start -7.649972 4.99999)
			(end 7.649972 4.99999)
			(stroke
				(width 0.1)
				(type default)
			)
			(layer "F.Fab")
		)
		(fp_line
			(start 7.649972 -4.99999)
			(end -7.649972 -4.99999)
			(stroke
				(width 0.1)
				(type default)
			)
			(layer "F.Fab")
		)
		(fp_line
			(start 7.649972 4.99999)
			(end 7.649972 -4.99999)
			(stroke
				(width 0.1)
				(type default)
			)
			(layer "F.Fab")
		)
		(pad "D" smd circle
			(at 2.15011 0)
			(size 0 0)
			(layers "F.Cu" "F.Mask" "F.Paste")
			(net "P52V_HS2_DRAIN_1")
		)
		(pad "G" smd rect
			(at -7.050024 -2.54 270)
			(size 1.3208 3.0988)
			(layers "F.Cu" "F.Mask" "F.Paste")
			(net "P52V_HS2_GATE1")
		)
		(pad "S" smd rect
			(at -7.050024 2.54 270)
			(size 1.3208 3.0988)
			(layers "F.Cu" "F.Mask" "F.Paste")
			(net "P52V_HS2")
		)
		(zone
			(layer "F.Cu")
			(hatch none 0.5)
			(connect_pads
				(clearance 0)
			)
			(min_thickness 0.25)
			(keepout
				(tracks not_allowed)
				(vias allowed)
				(pads allowed)
				(copperpour not_allowed)
				(footprints allowed)
			)
			(placement
				(enabled no)
				(sheetname "")
			)
			(fill
				(thermal_gap 0.5)
				(thermal_bridge_width 0.5)
				(island_removal_mode 0)
			)
			(polygon
				(pts
					(xy 129.665476 -79.629) (xy 116.838476 -79.629) (xy 116.838476 -77.9018) (xy 119.048276 -77.9018)
					(xy 119.048276 -76.4794) (xy 116.838476 -76.4794) (xy 116.838476 -72.8218) (xy 119.048276 -72.8218)
					(xy 119.048276 -71.3994) (xy 116.838476 -71.3994) (xy 116.838476 -69.6722) (xy 129.665476 -69.6722)
					(xy 129.665476 -70.8406) (xy 123.467876 -70.8406) (xy 123.467876 -78.4606) (xy 129.665476 -78.4606)
				)
			)
		)
	)
	(footprint ""
		(layer "F.Cu")
		(at 185.928 -78.486 -90)
		(property "Reference" "C107"
			(at 0 0 270)
			(layer "F.SilkS")
			(hide yes)
			(effects
				(font
					(size 1.27 1.27)
				)
			)
		)
		(property "Value" ""
			(at 0 0 270)
			(layer "F.Fab")
			(effects
				(font
					(size 1.27 1.27)
				)
			)
		)
		(duplicate_pad_numbers_are_jumpers no)
		(fp_line
			(start -0.7874 0.4064)
			(end -0.7874 -0.4064)
			(stroke
				(width 0.1524)
				(type default)
			)
			(layer "F.SilkS")
		)
		(fp_line
			(start 0.7874 0.4064)
			(end -0.7874 0.4064)
			(stroke
				(width 0.1524)
				(type default)
			)
			(layer "F.SilkS")
		)
		(fp_line
			(start -0.7874 -0.4064)
			(end 0.7874 -0.4064)
			(stroke
				(width 0.1524)
				(type default)
			)
			(layer "F.SilkS")
		)
		(fp_line
			(start 0.7874 -0.4064)
			(end 0.7874 0.4064)
			(stroke
				(width 0.1524)
				(type default)
			)
			(layer "F.SilkS")
		)
		(fp_line
			(start -0.67945 0.3048)
			(end -0.67945 -0.305054)
			(stroke
				(width 0.1)
				(type default)
			)
			(layer "F.Fab")
		)
		(fp_line
			(start -0.12065 0.3048)
			(end -0.67945 0.3048)
			(stroke
				(width 0.1)
				(type default)
			)
			(layer "F.Fab")
		)
		(fp_line
			(start 0.120396 0.3048)
			(end 0.120396 0.2794)
			(stroke
				(width 0.1)
				(type default)
			)
			(layer "F.Fab")
		)
		(fp_line
			(start 0.67945 0.3048)
			(end 0.120396 0.3048)
			(stroke
				(width 0.1)
				(type default)
			)
			(layer "F.Fab")
		)
		(fp_line
			(start -0.12065 0.2794)
			(end -0.12065 0.3048)
			(stroke
				(width 0.1)
				(type default)
			)
			(layer "F.Fab")
		)
		(fp_line
			(start 0.120396 0.2794)
			(end -0.12065 0.2794)
			(stroke
				(width 0.1)
				(type default)
			)
			(layer "F.Fab")
		)
		(fp_line
			(start -0.12065 -0.2794)
			(end 0.12065 -0.2794)
			(stroke
				(width 0.1)
				(type default)
			)
			(layer "F.Fab")
		)
		(fp_line
			(start 0.12065 -0.2794)
			(end 0.12065 -0.3048)
			(stroke
				(width 0.1)
				(type default)
			)
			(layer "F.Fab")
		)
		(fp_line
			(start 0.12065 -0.3048)
			(end 0.67945 -0.3048)
			(stroke
				(width 0.1)
				(type default)
			)
			(layer "F.Fab")
		)
		(fp_line
			(start 0.67945 -0.3048)
			(end 0.67945 0.3048)
			(stroke
				(width 0.1)
				(type default)
			)
			(layer "F.Fab")
		)
		(fp_line
			(start -0.67945 -0.305054)
			(end -0.12065 -0.305054)
			(stroke
				(width 0.1)
				(type default)
			)
			(layer "F.Fab")
		)
		(fp_line
			(start -0.12065 -0.305054)
			(end -0.12065 -0.2794)
			(stroke
				(width 0.1)
				(type default)
			)
			(layer "F.Fab")
		)
		(pad "1" smd circle
			(at -0.40005 0 270)
			(size 0 0)
			(layers "F.Cu" "F.Mask" "F.Paste")
			(net "GND")
		)
		(pad "2" smd circle
			(at 0.40005 0 270)
			(size 0 0)
			(layers "F.Cu" "F.Mask" "F.Paste")
			(net "P3V3_AUX")
		)
	)
	(footprint ""
		(layer "F.Cu")
		(at 427.228 -45.974)
		(property "Reference" "R56"
			(at 0 0 0)
			(layer "F.SilkS")
			(hide yes)
			(effects
				(font
					(size 1.27 1.27)
				)
			)
		)
		(property "Value" ""
			(at 0 0 0)
			(layer "F.Fab")
			(effects
				(font
					(size 1.27 1.27)
				)
			)
		)
		(duplicate_pad_numbers_are_jumpers no)
		(fp_line
			(start -0.7874 -0.4064)
			(end 0.7874 -0.4064)
			(stroke
				(width 0.1524)
				(type default)
			)
			(layer "F.SilkS")
		)
		(fp_line
			(start -0.7874 0.4064)
			(end -0.7874 -0.4064)
			(stroke
				(width 0.1524)
				(type default)
			)
			(layer "F.SilkS")
		)
		(fp_line
			(start 0.7874 -0.4064)
			(end 0.7874 0.4064)
			(stroke
				(width 0.1524)
				(type default)
			)
			(layer "F.SilkS")
		)
		(fp_line
			(start 0.7874 0.4064)
			(end -0.7874 0.4064)
			(stroke
				(width 0.1524)
				(type default)
			)
			(layer "F.SilkS")
		)
		(fp_line
			(start -0.67945 -0.305054)
			(end -0.12065 -0.305054)
			(stroke
				(width 0.1)
				(type default)
			)
			(layer "F.Fab")
		)
		(fp_line
			(start -0.67945 0.3048)
			(end -0.67945 -0.305054)
			(stroke
				(width 0.1)
				(type default)
			)
			(layer "F.Fab")
		)
		(fp_line
			(start -0.12065 -0.305054)
			(end -0.12065 -0.2794)
			(stroke
				(width 0.1)
				(type default)
			)
			(layer "F.Fab")
		)
		(fp_line
			(start -0.12065 -0.2794)
			(end 0.12065 -0.2794)
			(stroke
				(width 0.1)
				(type default)
			)
			(layer "F.Fab")
		)
		(fp_line
			(start -0.12065 0.2794)
			(end -0.12065 0.3048)
			(stroke
				(width 0.1)
				(type default)
			)
			(layer "F.Fab")
		)
		(fp_line
			(start -0.12065 0.3048)
			(end -0.67945 0.3048)
			(stroke
				(width 0.1)
				(type default)
			)
			(layer "F.Fab")
		)
		(fp_line
			(start 0.120396 0.2794)
			(end -0.12065 0.2794)
			(stroke
				(width 0.1)
				(type default)
			)
			(layer "F.Fab")
		)
		(fp_line
			(start 0.120396 0.3048)
			(end 0.120396 0.2794)
			(stroke
				(width 0.1)
				(type default)
			)
			(layer "F.Fab")
		)
		(fp_line
			(start 0.12065 -0.3048)
			(end 0.67945 -0.3048)
			(stroke
				(width 0.1)
				(type default)
			)
			(layer "F.Fab")
		)
		(fp_line
			(start 0.12065 -0.2794)
			(end 0.12065 -0.3048)
			(stroke
				(width 0.1)
				(type default)
			)
			(layer "F.Fab")
		)
		(fp_line
			(start 0.67945 -0.3048)
			(end 0.67945 0.3048)
			(stroke
				(width 0.1)
				(type default)
			)
			(layer "F.Fab")
		)
		(fp_line
			(start 0.67945 0.3048)
			(end 0.120396 0.3048)
			(stroke
				(width 0.1)
				(type default)
			)
			(layer "F.Fab")
		)
		(pad "1" smd circle
			(at -0.40005 0)
			(size 0 0)
			(layers "F.Cu" "F.Mask" "F.Paste")
			(net "PCA9555_A0")
		)
		(pad "2" smd circle
			(at 0.40005 0)
			(size 0 0)
			(layers "F.Cu" "F.Mask" "F.Paste")
			(net "GND")
		)
	)
	(footprint ""
		(layer "F.Cu")
		(at 82.804 -17.907 90)
		(property "Reference" "R76"
			(at 0 0 90)
			(layer "F.SilkS")
			(hide yes)
			(effects
				(font
					(size 1.27 1.27)
				)
			)
		)
		(property "Value" ""
			(at 0 0 90)
			(layer "F.Fab")
			(effects
				(font
					(size 1.27 1.27)
				)
			)
		)
		(duplicate_pad_numbers_are_jumpers no)
		(fp_line
			(start 0.7874 -0.4064)
			(end 0.7874 0.4064)
			(stroke
				(width 0.1524)
				(type default)
			)
			(layer "F.SilkS")
		)
		(fp_line
			(start -0.7874 -0.4064)
			(end 0.7874 -0.4064)
			(stroke
				(width 0.1524)
				(type default)
			)
			(layer "F.SilkS")
		)
		(fp_line
			(start 0.7874 0.4064)
			(end -0.7874 0.4064)
			(stroke
				(width 0.1524)
				(type default)
			)
			(layer "F.SilkS")
		)
		(fp_line
			(start -0.7874 0.4064)
			(end -0.7874 -0.4064)
			(stroke
				(width 0.1524)
				(type default)
			)
			(layer "F.SilkS")
		)
		(fp_line
			(start -0.12065 -0.305054)
			(end -0.12065 -0.2794)
			(stroke
				(width 0.1)
				(type default)
			)
			(layer "F.Fab")
		)
		(fp_line
			(start -0.67945 -0.305054)
			(end -0.12065 -0.305054)
			(stroke
				(width 0.1)
				(type default)
			)
			(layer "F.Fab")
		)
		(fp_line
			(start 0.67945 -0.3048)
			(end 0.67945 0.3048)
			(stroke
				(width 0.1)
				(type default)
			)
			(layer "F.Fab")
		)
		(fp_line
			(start 0.12065 -0.3048)
			(end 0.67945 -0.3048)
			(stroke
				(width 0.1)
				(type default)
			)
			(layer "F.Fab")
		)
		(fp_line
			(start 0.12065 -0.2794)
			(end 0.12065 -0.3048)
			(stroke
				(width 0.1)
				(type default)
			)
			(layer "F.Fab")
		)
		(fp_line
			(start -0.12065 -0.2794)
			(end 0.12065 -0.2794)
			(stroke
				(width 0.1)
				(type default)
			)
			(layer "F.Fab")
		)
		(fp_line
			(start 0.120396 0.2794)
			(end -0.12065 0.2794)
			(stroke
				(width 0.1)
				(type default)
			)
			(layer "F.Fab")
		)
		(fp_line
			(start -0.12065 0.2794)
			(end -0.12065 0.3048)
			(stroke
				(width 0.1)
				(type default)
			)
			(layer "F.Fab")
		)
		(fp_line
			(start 0.67945 0.3048)
			(end 0.120396 0.3048)
			(stroke
				(width 0.1)
				(type default)
			)
			(layer "F.Fab")
		)
		(fp_line
			(start 0.120396 0.3048)
			(end 0.120396 0.2794)
			(stroke
				(width 0.1)
				(type default)
			)
			(layer "F.Fab")
		)
		(fp_line
			(start -0.12065 0.3048)
			(end -0.67945 0.3048)
			(stroke
				(width 0.1)
				(type default)
			)
			(layer "F.Fab")
		)
		(fp_line
			(start -0.67945 0.3048)
			(end -0.67945 -0.305054)
			(stroke
				(width 0.1)
				(type default)
			)
			(layer "F.Fab")
		)
		(pad "1" smd circle
			(at -0.40005 0 90)
			(size 0 0)
			(layers "F.Cu" "F.Mask" "F.Paste")
			(net "FAN_PWR_EN_1_R")
		)
		(pad "2" smd circle
			(at 0.40005 0 90)
			(size 0 0)
			(layers "F.Cu" "F.Mask" "F.Paste")
			(net "FAN_PWR_EN_BUF")
		)
	)
	(footprint ""
		(layer "F.Cu")
		(at 442.849 -99.695 180)
		(property "Reference" "PC138"
			(at 3.302 4.29133 0)
			(unlocked yes)
			(layer "F.SilkS")
			(effects
				(font
					(size 0.7874 0.5842)
					(thickness 0.1524)
				)
				(justify left)
			)
		)
		(property "Value" ""
			(at 0 0 180)
			(layer "F.Fab")
			(effects
				(font
					(size 1.27 1.27)
				)
			)
		)
		(duplicate_pad_numbers_are_jumpers no)
		(fp_line
			(start 3.400044 3.400044)
			(end -2.146046 3.400044)
			(stroke
				(width 0.1524)
				(type default)
			)
			(layer "F.SilkS")
		)
		(fp_line
			(start 3.400044 0.9398)
			(end 3.400044 3.400044)
			(stroke
				(width 0.1524)
				(type default)
			)
			(layer "F.SilkS")
		)
		(fp_line
			(start 3.400044 -0.9398)
			(end 3.400044 -3.400044)
			(stroke
				(width 0.1524)
				(type default)
			)
			(layer "F.SilkS")
		)
		(fp_line
			(start 3.400044 -3.400044)
			(end -2.146046 -3.400044)
			(stroke
				(width 0.1524)
				(type default)
			)
			(layer "F.SilkS")
		)
		(fp_line
			(start -2.146046 3.400044)
			(end -3.400044 2.146046)
			(stroke
				(width 0.1524)
				(type default)
			)
			(layer "F.SilkS")
		)
		(fp_line
			(start -2.146046 -3.400044)
			(end -3.400044 -2.146046)
			(stroke
				(width 0.1524)
				(type default)
			)
			(layer "F.SilkS")
		)
		(fp_line
			(start -3.400044 2.146046)
			(end -3.400044 0.9398)
			(stroke
				(width 0.1524)
				(type default)
			)
			(layer "F.SilkS")
		)
		(fp_line
			(start -3.400044 -2.146046)
			(end -3.400044 -0.9398)
			(stroke
				(width 0.1524)
				(type default)
			)
			(layer "F.SilkS")
		)
		(fp_line
			(start 3.400044 3.400044)
			(end 3.400044 -3.400044)
			(stroke
				(width 0.1)
				(type default)
			)
			(layer "F.Fab")
		)
		(fp_line
			(start 3.400044 -3.400044)
			(end -3.400044 -3.400044)
			(stroke
				(width 0.1)
				(type default)
			)
			(layer "F.Fab")
		)
		(fp_line
			(start -3.400044 3.400044)
			(end 3.400044 3.400044)
			(stroke
				(width 0.1)
				(type default)
			)
			(layer "F.Fab")
		)
		(fp_line
			(start -3.400044 -3.400044)
			(end -3.400044 3.400044)
			(stroke
				(width 0.1)
				(type default)
			)
			(layer "F.Fab")
		)
		(pad "1" smd rect
			(at -2.70002 0 90)
			(size 1.6002 3.5052)
			(layers "F.Cu" "F.Mask" "F.Paste")
			(net "SW_P3V3_HPDB_FLT")
		)
		(pad "2" smd rect
			(at 2.70002 0 90)
			(size 1.6002 3.5052)
			(layers "F.Cu" "F.Mask" "F.Paste")
			(net "GND")
		)
	)
	(footprint ""
		(layer "F.Cu")
		(at 178.0794 -49.149)
		(property "Reference" "U25"
			(at 2.0066 -1.24333 0)
			(unlocked yes)
			(layer "F.SilkS")
			(effects
				(font
					(size 0.7874 0.5842)
					(thickness 0.1524)
				)
				(justify left)
			)
		)
		(property "Value" ""
			(at 0 0 0)
			(layer "F.Fab")
			(effects
				(font
					(size 1.27 1.27)
				)
			)
		)
		(duplicate_pad_numbers_are_jumpers no)
		(fp_line
			(start -1.603248 -1.500124)
			(end 1.603248 -1.500124)
			(stroke
				(width 0.1524)
				(type default)
			)
			(layer "F.SilkS")
		)
		(fp_line
			(start -1.603248 1.500124)
			(end -1.603248 -1.500124)
			(stroke
				(width 0.1524)
				(type default)
			)
			(layer "F.SilkS")
		)
		(fp_line
			(start 1.603248 -1.500124)
			(end 1.603248 1.500124)
			(stroke
				(width 0.1524)
				(type default)
			)
			(layer "F.SilkS")
		)
		(fp_line
			(start 1.603248 1.500124)
			(end -1.603248 1.500124)
			(stroke
				(width 0.1524)
				(type default)
			)
			(layer "F.SilkS")
		)
		(fp_line
			(start -1.249934 -1.169924)
			(end -1.249934 -0.729996)
			(stroke
				(width 0.1)
				(type default)
			)
			(layer "F.Fab")
		)
		(fp_line
			(start -1.249934 -0.729996)
			(end -0.6985 -0.729996)
			(stroke
				(width 0.1)
				(type default)
			)
			(layer "F.Fab")
		)
		(fp_line
			(start -1.249934 0.729996)
			(end -1.249934 1.169924)
			(stroke
				(width 0.1)
				(type default)
			)
			(layer "F.Fab")
		)
		(fp_line
			(start -1.249934 1.169924)
			(end -0.700024 1.169924)
			(stroke
				(width 0.1)
				(type default)
			)
			(layer "F.Fab")
		)
		(fp_line
			(start -0.700024 -1.500124)
			(end -0.700024 -1.169924)
			(stroke
				(width 0.1)
				(type default)
			)
			(layer "F.Fab")
		)
		(fp_line
			(start -0.700024 -1.169924)
			(end -1.249934 -1.169924)
			(stroke
				(width 0.1)
				(type default)
			)
			(layer "F.Fab")
		)
		(fp_line
			(start -0.700024 1.169924)
			(end -0.700024 1.500124)
			(stroke
				(width 0.1)
				(type default)
			)
			(layer "F.Fab")
		)
		(fp_line
			(start -0.700024 1.500124)
			(end 0.700024 1.500124)
			(stroke
				(width 0.1)
				(type default)
			)
			(layer "F.Fab")
		)
		(fp_line
			(start -0.6985 -0.729996)
			(end -0.6985 0.729996)
			(stroke
				(width 0.1)
				(type default)
			)
			(layer "F.Fab")
		)
		(fp_line
			(start -0.6985 0.729996)
			(end -1.249934 0.729996)
			(stroke
				(width 0.1)
				(type default)
			)
			(layer "F.Fab")
		)
		(fp_line
			(start 0.700024 -1.500124)
			(end -0.700024 -1.500124)
			(stroke
				(width 0.1)
				(type default)
			)
			(layer "F.Fab")
		)
		(fp_line
			(start 0.700024 -0.219964)
			(end 0.700024 -1.500124)
			(stroke
				(width 0.1)
				(type default)
			)
			(layer "F.Fab")
		)
		(fp_line
			(start 0.700024 0.219964)
			(end 1.249934 0.219964)
			(stroke
				(width 0.1)
				(type default)
			)
			(layer "F.Fab")
		)
		(fp_line
			(start 0.700024 1.500124)
			(end 0.700024 0.219964)
			(stroke
				(width 0.1)
				(type default)
			)
			(layer "F.Fab")
		)
		(fp_line
			(start 1.249934 -0.219964)
			(end 0.700024 -0.219964)
			(stroke
				(width 0.1)
				(type default)
			)
			(layer "F.Fab")
		)
		(fp_line
			(start 1.249934 0.219964)
			(end 1.249934 -0.219964)
			(stroke
				(width 0.1)
				(type default)
			)
			(layer "F.Fab")
		)
		(fp_rect
			(start -0.700024 1.500124)
			(end 0.700024 -1.500124)
			(stroke
				(width 0)
				(type default)
			)
			(fill no)
			(layer "F.Fab")
		)
		(pad "D" smd rect
			(at 0.999998 0 270)
			(size 0.8128 0.9144)
			(layers "F.Cu" "F.Mask" "F.Paste")
			(net "GPU_HSC2_BUF_EN")
		)
		(pad "G" smd rect
			(at -0.999998 -0.94996 270)
			(size 0.8128 0.9144)
			(layers "F.Cu" "F.Mask" "F.Paste")
			(net "GPU_HSC2_BUF_EN_N")
		)
		(pad "S" smd rect
			(at -0.999998 0.94996 270)
			(size 0.8128 0.9144)
			(layers "F.Cu" "F.Mask" "F.Paste")
			(net "GND")
		)
	)
	(footprint ""
		(layer "F.Cu")
		(at 414.8582 -20.2692)
		(property "Reference" "D5"
			(at -3.429 -2.29743 0)
			(unlocked yes)
			(layer "F.SilkS")
			(effects
				(font
					(size 0.7874 0.5842)
					(thickness 0.1524)
				)
				(justify left)
			)
		)
		(property "Value" ""
			(at 0 0 0)
			(layer "F.Fab")
			(effects
				(font
					(size 1.27 1.27)
				)
			)
		)
		(duplicate_pad_numbers_are_jumpers no)
		(fp_line
			(start -3.400044 -1.459992)
			(end 4.107942 -1.459992)
			(stroke
				(width 0.1524)
				(type default)
			)
			(layer "F.SilkS")
		)
		(fp_line
			(start -3.400044 1.459992)
			(end -3.400044 -1.459992)
			(stroke
				(width 0.1524)
				(type default)
			)
			(layer "F.SilkS")
		)
		(fp_line
			(start 4.107942 -1.459992)
			(end 4.107942 1.459992)
			(stroke
				(width 0.1524)
				(type default)
			)
			(layer "F.SilkS")
		)
		(fp_line
			(start 4.107942 1.459992)
			(end -3.400044 1.459992)
			(stroke
				(width 0.1524)
				(type default)
			)
			(layer "F.SilkS")
		)
		(fp_poly
			(pts
				(xy 4.107942 -1.459992) (xy 4.107942 1.459992) (xy 3.308096 1.459992) (xy 3.308096 -1.459992)
			)
			(stroke
				(width 0)
				(type default)
			)
			(fill yes)
			(layer "F.SilkS")
		)
		(fp_line
			(start -2.29997 -1.459992)
			(end 2.29997 -1.459992)
			(stroke
				(width 0.1)
				(type default)
			)
			(layer "F.Fab")
		)
		(fp_line
			(start -2.29997 1.459992)
			(end -2.29997 -1.459992)
			(stroke
				(width 0.1)
				(type default)
			)
			(layer "F.Fab")
		)
		(fp_line
			(start 2.29997 -1.459992)
			(end 2.29997 1.459992)
			(stroke
				(width 0.1)
				(type default)
			)
			(layer "F.Fab")
		)
		(fp_line
			(start 2.29997 1.459992)
			(end -2.29997 1.459992)
			(stroke
				(width 0.1)
				(type default)
			)
			(layer "F.Fab")
		)
		(fp_text user "+"
			(at -5.842 -0.19685 0)
			(unlocked yes)
			(layer "F.SilkS")
			(effects
				(font
					(size 1.905 1.4224)
					(thickness 0.1524)
				)
				(justify left)
			)
		)
		(fp_text user "-"
			(at 5.4102 0.29845 180)
			(unlocked yes)
			(layer "F.SilkS")
			(effects
				(font
					(size 1.905 1.4224)
					(thickness 0.1524)
				)
				(justify left)
			)
		)
		(fp_text user "+"
			(at -4.7752 -0.12065 0)
			(unlocked yes)
			(layer "F.Fab")
			(effects
				(font
					(size 1.905 1.4224)
					(thickness 0.1524)
				)
				(justify left)
			)
		)
		(fp_text user "-"
			(at 5.4102 0.29845 180)
			(unlocked yes)
			(layer "F.Fab")
			(effects
				(font
					(size 1.905 1.4224)
					(thickness 0.1524)
				)
				(justify left)
			)
		)
		(pad "A" smd rect
			(at -1.999996 0 90)
			(size 1.7018 2.5146)
			(layers "F.Cu" "F.Mask" "F.Paste")
			(net "GND")
		)
		(pad "C" smd rect
			(at 1.999996 0 90)
			(size 1.7018 2.5146)
			(layers "F.Cu" "F.Mask" "F.Paste")
			(net "P12V_FAN_LED")
		)
	)
	(footprint ""
		(layer "F.Cu")
		(at 387.223 -25.527 90)
		(property "Reference" "PR102"
			(at 0 0 90)
			(layer "F.SilkS")
			(hide yes)
			(effects
				(font
					(size 1.27 1.27)
				)
			)
		)
		(property "Value" ""
			(at 0 0 90)
			(layer "F.Fab")
			(effects
				(font
					(size 1.27 1.27)
				)
			)
		)
		(duplicate_pad_numbers_are_jumpers no)
		(fp_line
			(start 0.7874 -0.4064)
			(end 0.7874 0.4064)
			(stroke
				(width 0.1524)
				(type default)
			)
			(layer "F.SilkS")
		)
		(fp_line
			(start -0.7874 -0.4064)
			(end 0.7874 -0.4064)
			(stroke
				(width 0.1524)
				(type default)
			)
			(layer "F.SilkS")
		)
		(fp_line
			(start 0.7874 0.4064)
			(end -0.7874 0.4064)
			(stroke
				(width 0.1524)
				(type default)
			)
			(layer "F.SilkS")
		)
		(fp_line
			(start -0.7874 0.4064)
			(end -0.7874 -0.4064)
			(stroke
				(width 0.1524)
				(type default)
			)
			(layer "F.SilkS")
		)
		(fp_line
			(start -0.12065 -0.305054)
			(end -0.12065 -0.2794)
			(stroke
				(width 0.1)
				(type default)
			)
			(layer "F.Fab")
		)
		(fp_line
			(start -0.67945 -0.305054)
			(end -0.12065 -0.305054)
			(stroke
				(width 0.1)
				(type default)
			)
			(layer "F.Fab")
		)
		(fp_line
			(start 0.67945 -0.3048)
			(end 0.67945 0.3048)
			(stroke
				(width 0.1)
				(type default)
			)
			(layer "F.Fab")
		)
		(fp_line
			(start 0.12065 -0.3048)
			(end 0.67945 -0.3048)
			(stroke
				(width 0.1)
				(type default)
			)
			(layer "F.Fab")
		)
		(fp_line
			(start 0.12065 -0.2794)
			(end 0.12065 -0.3048)
			(stroke
				(width 0.1)
				(type default)
			)
			(layer "F.Fab")
		)
		(fp_line
			(start -0.12065 -0.2794)
			(end 0.12065 -0.2794)
			(stroke
				(width 0.1)
				(type default)
			)
			(layer "F.Fab")
		)
		(fp_line
			(start 0.120396 0.2794)
			(end -0.12065 0.2794)
			(stroke
				(width 0.1)
				(type default)
			)
			(layer "F.Fab")
		)
		(fp_line
			(start -0.12065 0.2794)
			(end -0.12065 0.3048)
			(stroke
				(width 0.1)
				(type default)
			)
			(layer "F.Fab")
		)
		(fp_line
			(start 0.67945 0.3048)
			(end 0.120396 0.3048)
			(stroke
				(width 0.1)
				(type default)
			)
			(layer "F.Fab")
		)
		(fp_line
			(start 0.120396 0.3048)
			(end 0.120396 0.2794)
			(stroke
				(width 0.1)
				(type default)
			)
			(layer "F.Fab")
		)
		(fp_line
			(start -0.12065 0.3048)
			(end -0.67945 0.3048)
			(stroke
				(width 0.1)
				(type default)
			)
			(layer "F.Fab")
		)
		(fp_line
			(start -0.67945 0.3048)
			(end -0.67945 -0.305054)
			(stroke
				(width 0.1)
				(type default)
			)
			(layer "F.Fab")
		)
		(pad "1" smd circle
			(at -0.40005 0 90)
			(size 0 0)
			(layers "F.Cu" "F.Mask" "F.Paste")
			(net "P52V_HS1_EN")
		)
		(pad "2" smd circle
			(at 0.40005 0 90)
			(size 0 0)
			(layers "F.Cu" "F.Mask" "F.Paste")
			(net "P52V_HS1_EN_DISCHARGE")
		)
	)
	(footprint ""
		(layer "F.Cu")
		(at 208.810098 -22.474936)
		(property "Reference" "H33"
			(at -1.9812 -4.079748 0)
			(unlocked yes)
			(layer "B.SilkS")
			(effects
				(font
					(size 0.7874 0.5842)
					(thickness 0.1524)
				)
				(justify left mirror)
			)
		)
		(property "Value" ""
			(at 0 0 0)
			(layer "F.Fab")
			(effects
				(font
					(size 1.27 1.27)
				)
			)
		)
		(duplicate_pad_numbers_are_jumpers no)
		(pad "1" thru_hole circle
			(at 0 0)
			(size 8.001 8.001)
			(drill 4.2418)
			(layers "*.Cu" "*.Mask")
			(remove_unused_layers no)
			(net "TP_H33")
			(clearance -1.6256)
			(padstack
				(mode front_inner_back)
				(layer "Inner"
					(shape circle)
					(size 6.0198 6.0198)
					(clearance -0.635)
				)
				(layer "B.Cu"
					(shape circle)
					(size 8.001 8.001)
					(clearance -1.6256)
				)
			)
		)
		(zone
			(layers "F.Cu" "B.Cu" "In1.Cu" "In2.Cu" "In3.Cu" "In4.Cu" "In5.Cu" "In6.Cu"
				"In7.Cu" "In8.Cu"
			)
			(hatch none 0.5)
			(connect_pads
				(clearance 0)
			)
			(min_thickness 0.25)
			(keepout
				(tracks not_allowed)
				(vias allowed)
				(pads allowed)
				(copperpour not_allowed)
				(footprints allowed)
			)
			(placement
				(enabled no)
				(sheetname "")
			)
			(fill
				(thermal_gap 0.5)
				(thermal_bridge_width 0.5)
				(island_removal_mode 0)
			)
			(polygon
				(pts
					(arc
						(start 212.320124 -22.474936)
						(mid 205.300072 -22.474936)
						(end 212.320124 -22.474936)
					)
				)
			)
		)
	)
	(footprint ""
		(layer "F.Cu")
		(at 397.637 -33.529778 90)
		(property "Reference" "PQ15"
			(at -9.680448 -5.0546 0)
			(unlocked yes)
			(layer "F.SilkS")
			(effects
				(font
					(size 0.7874 0.5842)
					(thickness 0.1524)
				)
				(justify left)
			)
		)
		(property "Value" ""
			(at 0 0 90)
			(layer "F.Fab")
			(effects
				(font
					(size 1.27 1.27)
				)
			)
		)
		(duplicate_pad_numbers_are_jumpers no)
		(fp_line
			(start 7.649972 -4.99999)
			(end 7.630414 -4.99999)
			(stroke
				(width 0.1524)
				(type default)
			)
			(layer "F.SilkS")
		)
		(fp_line
			(start 5.115814 -4.99999)
			(end -7.649972 -4.99999)
			(stroke
				(width 0.1524)
				(type default)
			)
			(layer "F.SilkS")
		)
		(fp_line
			(start -7.649972 -4.99999)
			(end -7.649972 -3.3274)
			(stroke
				(width 0.1524)
				(type default)
			)
			(layer "F.SilkS")
		)
		(fp_line
			(start -7.649972 -1.7526)
			(end -7.649972 1.7526)
			(stroke
				(width 0.1524)
				(type default)
			)
			(layer "F.SilkS")
		)
		(fp_line
			(start -7.649972 3.3274)
			(end -7.649972 4.99999)
			(stroke
				(width 0.1524)
				(type default)
			)
			(layer "F.SilkS")
		)
		(fp_line
			(start 7.649972 4.99999)
			(end 7.649972 -4.99999)
			(stroke
				(width 0.1524)
				(type default)
			)
			(layer "F.SilkS")
		)
		(fp_line
			(start 7.630414 4.99999)
			(end 7.649972 4.99999)
			(stroke
				(width 0.1524)
				(type default)
			)
			(layer "F.SilkS")
		)
		(fp_line
			(start -7.649972 4.99999)
			(end 5.115814 4.99999)
			(stroke
				(width 0.1524)
				(type default)
			)
			(layer "F.SilkS")
		)
		(fp_line
			(start 7.649972 -4.99999)
			(end -7.649972 -4.99999)
			(stroke
				(width 0.1)
				(type default)
			)
			(layer "F.Fab")
		)
		(fp_line
			(start -7.649972 -4.99999)
			(end -7.649972 4.99999)
			(stroke
				(width 0.1)
				(type default)
			)
			(layer "F.Fab")
		)
		(fp_line
			(start 7.649972 4.99999)
			(end 7.649972 -4.99999)
			(stroke
				(width 0.1)
				(type default)
			)
			(layer "F.Fab")
		)
		(fp_line
			(start -7.649972 4.99999)
			(end 7.649972 4.99999)
			(stroke
				(width 0.1)
				(type default)
			)
			(layer "F.Fab")
		)
		(pad "D" smd circle
			(at 2.15011 0 90)
			(size 0 0)
			(layers "F.Cu" "F.Mask" "F.Paste")
			(net "P52V_HS1")
		)
		(pad "G" smd rect
			(at -7.050024 -2.54)
			(size 1.3208 3.0988)
			(layers "F.Cu" "F.Mask" "F.Paste")
			(net "P52V_HS1_EN_DISCHARGE_N")
		)
		(pad "S" smd rect
			(at -7.050024 2.54)
			(size 1.3208 3.0988)
			(layers "F.Cu" "F.Mask" "F.Paste")
			(net "P52V_HS1_EN_DISCHARGE_VBE_R")
		)
		(zone
			(layer "F.Cu")
			(hatch none 0.5)
			(connect_pads
				(clearance 0)
			)
			(min_thickness 0.25)
			(keepout
				(tracks not_allowed)
				(vias allowed)
				(pads allowed)
				(copperpour not_allowed)
				(footprints allowed)
			)
			(placement
				(enabled no)
				(sheetname "")
			)
			(fill
				(thermal_gap 0.5)
				(thermal_bridge_width 0.5)
				(island_removal_mode 0)
			)
			(polygon
				(pts
					(xy 392.6586 -38.711378) (xy 392.6586 -25.884378) (xy 394.3858 -25.884378) (xy 394.3858 -28.094178)
					(xy 395.8082 -28.094178) (xy 395.8082 -25.884378) (xy 399.4658 -25.884378) (xy 399.4658 -28.094178)
					(xy 400.8882 -28.094178) (xy 400.8882 -25.884378) (xy 402.6154 -25.884378) (xy 402.6154 -38.711378)
					(xy 401.447 -38.711378) (xy 401.447 -32.513778) (xy 393.827 -32.513778) (xy 393.827 -38.711378)
				)
			)
		)
	)
	(footprint ""
		(layer "F.Cu")
		(at 451.612 -49.276 -90)
		(property "Reference" "R5915"
			(at 0 0 270)
			(layer "F.SilkS")
			(hide yes)
			(effects
				(font
					(size 1.27 1.27)
				)
			)
		)
		(property "Value" ""
			(at 0 0 270)
			(layer "F.Fab")
			(effects
				(font
					(size 1.27 1.27)
				)
			)
		)
		(duplicate_pad_numbers_are_jumpers no)
		(fp_line
			(start -0.7874 0.4064)
			(end -0.7874 -0.4064)
			(stroke
				(width 0.1524)
				(type default)
			)
			(layer "F.SilkS")
		)
		(fp_line
			(start 0.7874 0.4064)
			(end -0.7874 0.4064)
			(stroke
				(width 0.1524)
				(type default)
			)
			(layer "F.SilkS")
		)
		(fp_line
			(start -0.7874 -0.4064)
			(end 0.7874 -0.4064)
			(stroke
				(width 0.1524)
				(type default)
			)
			(layer "F.SilkS")
		)
		(fp_line
			(start 0.7874 -0.4064)
			(end 0.7874 0.4064)
			(stroke
				(width 0.1524)
				(type default)
			)
			(layer "F.SilkS")
		)
		(fp_line
			(start -0.67945 0.3048)
			(end -0.67945 -0.305054)
			(stroke
				(width 0.1)
				(type default)
			)
			(layer "F.Fab")
		)
		(fp_line
			(start -0.12065 0.3048)
			(end -0.67945 0.3048)
			(stroke
				(width 0.1)
				(type default)
			)
			(layer "F.Fab")
		)
		(fp_line
			(start 0.120396 0.3048)
			(end 0.120396 0.2794)
			(stroke
				(width 0.1)
				(type default)
			)
			(layer "F.Fab")
		)
		(fp_line
			(start 0.67945 0.3048)
			(end 0.120396 0.3048)
			(stroke
				(width 0.1)
				(type default)
			)
			(layer "F.Fab")
		)
		(fp_line
			(start -0.12065 0.2794)
			(end -0.12065 0.3048)
			(stroke
				(width 0.1)
				(type default)
			)
			(layer "F.Fab")
		)
		(fp_line
			(start 0.120396 0.2794)
			(end -0.12065 0.2794)
			(stroke
				(width 0.1)
				(type default)
			)
			(layer "F.Fab")
		)
		(fp_line
			(start -0.12065 -0.2794)
			(end 0.12065 -0.2794)
			(stroke
				(width 0.1)
				(type default)
			)
			(layer "F.Fab")
		)
		(fp_line
			(start 0.12065 -0.2794)
			(end 0.12065 -0.3048)
			(stroke
				(width 0.1)
				(type default)
			)
			(layer "F.Fab")
		)
		(fp_line
			(start 0.12065 -0.3048)
			(end 0.67945 -0.3048)
			(stroke
				(width 0.1)
				(type default)
			)
			(layer "F.Fab")
		)
		(fp_line
			(start 0.67945 -0.3048)
			(end 0.67945 0.3048)
			(stroke
				(width 0.1)
				(type default)
			)
			(layer "F.Fab")
		)
		(fp_line
			(start -0.67945 -0.305054)
			(end -0.12065 -0.305054)
			(stroke
				(width 0.1)
				(type default)
			)
			(layer "F.Fab")
		)
		(fp_line
			(start -0.12065 -0.305054)
			(end -0.12065 -0.2794)
			(stroke
				(width 0.1)
				(type default)
			)
			(layer "F.Fab")
		)
		(pad "1" smd circle
			(at -0.40005 0 270)
			(size 0 0)
			(layers "F.Cu" "F.Mask" "F.Paste")
			(net "PWRGD_P3V3_HPDB_R")
		)
		(pad "2" smd circle
			(at 0.40005 0 270)
			(size 0 0)
			(layers "F.Cu" "F.Mask" "F.Paste")
			(net "PWRGD_P3V3_HPDB")
		)
	)
	(footprint ""
		(layer "F.Cu")
		(at 140.79982 -37.9222 180)
		(property "Reference" "PR6993"
			(at 0 0 180)
			(layer "F.SilkS")
			(hide yes)
			(effects
				(font
					(size 1.27 1.27)
				)
			)
		)
		(property "Value" ""
			(at 0 0 180)
			(layer "F.Fab")
			(effects
				(font
					(size 1.27 1.27)
				)
			)
		)
		(duplicate_pad_numbers_are_jumpers no)
		(fp_line
			(start 1.2954 0.5842)
			(end -1.2954 0.5842)
			(stroke
				(width 0.1524)
				(type default)
			)
			(layer "F.SilkS")
		)
		(fp_line
			(start 1.2954 -0.5842)
			(end 1.2954 0.5842)
			(stroke
				(width 0.1524)
				(type default)
			)
			(layer "F.SilkS")
		)
		(fp_line
			(start -1.2954 0.5842)
			(end -1.2954 -0.5842)
			(stroke
				(width 0.1524)
				(type default)
			)
			(layer "F.SilkS")
		)
		(fp_line
			(start -1.2954 -0.5842)
			(end 1.2954 -0.5842)
			(stroke
				(width 0.1524)
				(type default)
			)
			(layer "F.SilkS")
		)
		(fp_line
			(start 1.1938 0.4064)
			(end 0.8636 0.4064)
			(stroke
				(width 0.1)
				(type default)
			)
			(layer "F.Fab")
		)
		(fp_line
			(start 1.1938 -0.406654)
			(end 1.1938 0.4064)
			(stroke
				(width 0.1)
				(type default)
			)
			(layer "F.Fab")
		)
		(fp_line
			(start 0.8636 0.4572)
			(end -0.8636 0.4572)
			(stroke
				(width 0.1)
				(type default)
			)
			(layer "F.Fab")
		)
		(fp_line
			(start 0.8636 0.4064)
			(end 0.8636 0.4572)
			(stroke
				(width 0.1)
				(type default)
			)
			(layer "F.Fab")
		)
		(fp_line
			(start 0.8636 -0.406654)
			(end 1.1938 -0.406654)
			(stroke
				(width 0.1)
				(type default)
			)
			(layer "F.Fab")
		)
		(fp_line
			(start 0.8636 -0.4572)
			(end 0.8636 -0.406654)
			(stroke
				(width 0.1)
				(type default)
			)
			(layer "F.Fab")
		)
		(fp_line
			(start -0.8636 0.4572)
			(end -0.8636 0.4318)
			(stroke
				(width 0.1)
				(type default)
			)
			(layer "F.Fab")
		)
		(fp_line
			(start -0.8636 0.4318)
			(end -0.8636 0.4064)
			(stroke
				(width 0.1)
				(type default)
			)
			(layer "F.Fab")
		)
		(fp_line
			(start -0.8636 0.4064)
			(end -1.1938 0.4064)
			(stroke
				(width 0.1)
				(type default)
			)
			(layer "F.Fab")
		)
		(fp_line
			(start -0.8636 -0.406654)
			(end -0.8636 -0.4572)
			(stroke
				(width 0.1)
				(type default)
			)
			(layer "F.Fab")
		)
		(fp_line
			(start -0.8636 -0.4572)
			(end 0.8636 -0.4572)
			(stroke
				(width 0.1)
				(type default)
			)
			(layer "F.Fab")
		)
		(fp_line
			(start -1.1938 0.4064)
			(end -1.1938 -0.406654)
			(stroke
				(width 0.1)
				(type default)
			)
			(layer "F.Fab")
		)
		(fp_line
			(start -1.1938 -0.406654)
			(end -0.8636 -0.406654)
			(stroke
				(width 0.1)
				(type default)
			)
			(layer "F.Fab")
		)
		(pad "1" smd rect
			(at -0.7366 0 90)
			(size 0.7112 0.8128)
			(layers "F.Cu" "F.Mask" "F.Paste")
			(net "P52V_HS2_4287_S2N")
		)
		(pad "2" smd rect
			(at 0.7366 0 90)
			(size 0.7112 0.8128)
			(layers "F.Cu" "F.Mask" "F.Paste")
			(net "P52V_HS2_SENSE_N_R2")
		)
	)
	(footprint ""
		(layer "F.Cu")
		(at 448.056 -41.148 90)
		(property "Reference" "R7"
			(at 0 0 90)
			(layer "F.SilkS")
			(hide yes)
			(effects
				(font
					(size 1.27 1.27)
				)
			)
		)
		(property "Value" ""
			(at 0 0 90)
			(layer "F.Fab")
			(effects
				(font
					(size 1.27 1.27)
				)
			)
		)
		(duplicate_pad_numbers_are_jumpers no)
		(fp_line
			(start 0.7874 -0.4064)
			(end 0.7874 0.4064)
			(stroke
				(width 0.1524)
				(type default)
			)
			(layer "F.SilkS")
		)
		(fp_line
			(start -0.7874 -0.4064)
			(end 0.7874 -0.4064)
			(stroke
				(width 0.1524)
				(type default)
			)
			(layer "F.SilkS")
		)
		(fp_line
			(start 0.7874 0.4064)
			(end -0.7874 0.4064)
			(stroke
				(width 0.1524)
				(type default)
			)
			(layer "F.SilkS")
		)
		(fp_line
			(start -0.7874 0.4064)
			(end -0.7874 -0.4064)
			(stroke
				(width 0.1524)
				(type default)
			)
			(layer "F.SilkS")
		)
		(fp_line
			(start -0.12065 -0.305054)
			(end -0.12065 -0.2794)
			(stroke
				(width 0.1)
				(type default)
			)
			(layer "F.Fab")
		)
		(fp_line
			(start -0.67945 -0.305054)
			(end -0.12065 -0.305054)
			(stroke
				(width 0.1)
				(type default)
			)
			(layer "F.Fab")
		)
		(fp_line
			(start 0.67945 -0.3048)
			(end 0.67945 0.3048)
			(stroke
				(width 0.1)
				(type default)
			)
			(layer "F.Fab")
		)
		(fp_line
			(start 0.12065 -0.3048)
			(end 0.67945 -0.3048)
			(stroke
				(width 0.1)
				(type default)
			)
			(layer "F.Fab")
		)
		(fp_line
			(start 0.12065 -0.2794)
			(end 0.12065 -0.3048)
			(stroke
				(width 0.1)
				(type default)
			)
			(layer "F.Fab")
		)
		(fp_line
			(start -0.12065 -0.2794)
			(end 0.12065 -0.2794)
			(stroke
				(width 0.1)
				(type default)
			)
			(layer "F.Fab")
		)
		(fp_line
			(start 0.120396 0.2794)
			(end -0.12065 0.2794)
			(stroke
				(width 0.1)
				(type default)
			)
			(layer "F.Fab")
		)
		(fp_line
			(start -0.12065 0.2794)
			(end -0.12065 0.3048)
			(stroke
				(width 0.1)
				(type default)
			)
			(layer "F.Fab")
		)
		(fp_line
			(start 0.67945 0.3048)
			(end 0.120396 0.3048)
			(stroke
				(width 0.1)
				(type default)
			)
			(layer "F.Fab")
		)
		(fp_line
			(start 0.120396 0.3048)
			(end 0.120396 0.2794)
			(stroke
				(width 0.1)
				(type default)
			)
			(layer "F.Fab")
		)
		(fp_line
			(start -0.12065 0.3048)
			(end -0.67945 0.3048)
			(stroke
				(width 0.1)
				(type default)
			)
			(layer "F.Fab")
		)
		(fp_line
			(start -0.67945 0.3048)
			(end -0.67945 -0.305054)
			(stroke
				(width 0.1)
				(type default)
			)
			(layer "F.Fab")
		)
		(pad "1" smd circle
			(at -0.40005 0 90)
			(size 0 0)
			(layers "F.Cu" "F.Mask" "F.Paste")
			(net "SMB_PDB_SDA")
		)
		(pad "2" smd circle
			(at 0.40005 0 90)
			(size 0 0)
			(layers "F.Cu" "F.Mask" "F.Paste")
			(net "SMB_PDB_MISC_SDA_R")
		)
	)
	(footprint ""
		(layer "F.Cu")
		(at 260.321298 -58.907426)
		(property "Reference" ""
			(at 0 0 0)
			(layer "F.SilkS")
			(hide yes)
			(effects
				(font
					(size 1.27 1.27)
				)
			)
		)
		(property "Value" ""
			(at 0 0 0)
			(layer "F.Fab")
			(effects
				(font
					(size 1.27 1.27)
				)
			)
		)
		(duplicate_pad_numbers_are_jumpers no)
		(pad "1" smd circle
			(at 0 0)
			(size 0.9906 0.9906)
			(layers "F.Cu" "F.Mask" "F.Paste")
			(net "Net_241")
		)
		(zone
			(layer "F.Cu")
			(hatch none 0.5)
			(connect_pads
				(clearance 0)
			)
			(min_thickness 0.25)
			(keepout
				(tracks not_allowed)
				(vias allowed)
				(pads allowed)
				(copperpour not_allowed)
				(footprints allowed)
			)
			(placement
				(enabled no)
				(sheetname "")
			)
			(fill
				(thermal_gap 0.5)
				(thermal_bridge_width 0.5)
				(island_removal_mode 0)
			)
			(polygon
				(pts
					(arc
						(start 261.946898 -58.907426)
						(mid 258.695698 -58.907426)
						(end 261.946898 -58.907426)
					)
				)
			)
		)
	)
	(footprint ""
		(layer "F.Cu")
		(at 167.767 -81.915 180)
		(property "Reference" "R5944"
			(at 0 0 180)
			(layer "F.SilkS")
			(hide yes)
			(effects
				(font
					(size 1.27 1.27)
				)
			)
		)
		(property "Value" ""
			(at 0 0 180)
			(layer "F.Fab")
			(effects
				(font
					(size 1.27 1.27)
				)
			)
		)
		(duplicate_pad_numbers_are_jumpers no)
		(fp_line
			(start 0.7874 0.4064)
			(end -0.7874 0.4064)
			(stroke
				(width 0.1524)
				(type default)
			)
			(layer "F.SilkS")
		)
		(fp_line
			(start 0.7874 -0.4064)
			(end 0.7874 0.4064)
			(stroke
				(width 0.1524)
				(type default)
			)
			(layer "F.SilkS")
		)
		(fp_line
			(start -0.7874 0.4064)
			(end -0.7874 -0.4064)
			(stroke
				(width 0.1524)
				(type default)
			)
			(layer "F.SilkS")
		)
		(fp_line
			(start -0.7874 -0.4064)
			(end 0.7874 -0.4064)
			(stroke
				(width 0.1524)
				(type default)
			)
			(layer "F.SilkS")
		)
		(fp_line
			(start 0.67945 0.3048)
			(end 0.120396 0.3048)
			(stroke
				(width 0.1)
				(type default)
			)
			(layer "F.Fab")
		)
		(fp_line
			(start 0.67945 -0.3048)
			(end 0.67945 0.3048)
			(stroke
				(width 0.1)
				(type default)
			)
			(layer "F.Fab")
		)
		(fp_line
			(start 0.12065 -0.2794)
			(end 0.12065 -0.3048)
			(stroke
				(width 0.1)
				(type default)
			)
			(layer "F.Fab")
		)
		(fp_line
			(start 0.12065 -0.3048)
			(end 0.67945 -0.3048)
			(stroke
				(width 0.1)
				(type default)
			)
			(layer "F.Fab")
		)
		(fp_line
			(start 0.120396 0.3048)
			(end 0.120396 0.2794)
			(stroke
				(width 0.1)
				(type default)
			)
			(layer "F.Fab")
		)
		(fp_line
			(start 0.120396 0.2794)
			(end -0.12065 0.2794)
			(stroke
				(width 0.1)
				(type default)
			)
			(layer "F.Fab")
		)
		(fp_line
			(start -0.12065 0.3048)
			(end -0.67945 0.3048)
			(stroke
				(width 0.1)
				(type default)
			)
			(layer "F.Fab")
		)
		(fp_line
			(start -0.12065 0.2794)
			(end -0.12065 0.3048)
			(stroke
				(width 0.1)
				(type default)
			)
			(layer "F.Fab")
		)
		(fp_line
			(start -0.12065 -0.2794)
			(end 0.12065 -0.2794)
			(stroke
				(width 0.1)
				(type default)
			)
			(layer "F.Fab")
		)
		(fp_line
			(start -0.12065 -0.305054)
			(end -0.12065 -0.2794)
			(stroke
				(width 0.1)
				(type default)
			)
			(layer "F.Fab")
		)
		(fp_line
			(start -0.67945 0.3048)
			(end -0.67945 -0.305054)
			(stroke
				(width 0.1)
				(type default)
			)
			(layer "F.Fab")
		)
		(fp_line
			(start -0.67945 -0.305054)
			(end -0.12065 -0.305054)
			(stroke
				(width 0.1)
				(type default)
			)
			(layer "F.Fab")
		)
		(pad "1" smd circle
			(at -0.40005 0 180)
			(size 0 0)
			(layers "F.Cu" "F.Mask" "F.Paste")
			(net "P3V3_AUX")
		)
		(pad "2" smd circle
			(at 0.40005 0 180)
			(size 0 0)
			(layers "F.Cu" "F.Mask" "F.Paste")
			(net "FM_HS2_EN_BUSBAR_BUF")
		)
	)
	(footprint ""
		(layer "F.Cu")
		(at 386.969 -29.083)
		(property "Reference" "PR99"
			(at 0 0 0)
			(layer "F.SilkS")
			(hide yes)
			(effects
				(font
					(size 1.27 1.27)
				)
			)
		)
		(property "Value" ""
			(at 0 0 0)
			(layer "F.Fab")
			(effects
				(font
					(size 1.27 1.27)
				)
			)
		)
		(duplicate_pad_numbers_are_jumpers no)
		(fp_line
			(start -0.7874 -0.4064)
			(end 0.7874 -0.4064)
			(stroke
				(width 0.1524)
				(type default)
			)
			(layer "F.SilkS")
		)
		(fp_line
			(start -0.7874 0.4064)
			(end -0.7874 -0.4064)
			(stroke
				(width 0.1524)
				(type default)
			)
			(layer "F.SilkS")
		)
		(fp_line
			(start 0.7874 -0.4064)
			(end 0.7874 0.4064)
			(stroke
				(width 0.1524)
				(type default)
			)
			(layer "F.SilkS")
		)
		(fp_line
			(start 0.7874 0.4064)
			(end -0.7874 0.4064)
			(stroke
				(width 0.1524)
				(type default)
			)
			(layer "F.SilkS")
		)
		(fp_line
			(start -0.67945 -0.305054)
			(end -0.12065 -0.305054)
			(stroke
				(width 0.1)
				(type default)
			)
			(layer "F.Fab")
		)
		(fp_line
			(start -0.67945 0.3048)
			(end -0.67945 -0.305054)
			(stroke
				(width 0.1)
				(type default)
			)
			(layer "F.Fab")
		)
		(fp_line
			(start -0.12065 -0.305054)
			(end -0.12065 -0.2794)
			(stroke
				(width 0.1)
				(type default)
			)
			(layer "F.Fab")
		)
		(fp_line
			(start -0.12065 -0.2794)
			(end 0.12065 -0.2794)
			(stroke
				(width 0.1)
				(type default)
			)
			(layer "F.Fab")
		)
		(fp_line
			(start -0.12065 0.2794)
			(end -0.12065 0.3048)
			(stroke
				(width 0.1)
				(type default)
			)
			(layer "F.Fab")
		)
		(fp_line
			(start -0.12065 0.3048)
			(end -0.67945 0.3048)
			(stroke
				(width 0.1)
				(type default)
			)
			(layer "F.Fab")
		)
		(fp_line
			(start 0.120396 0.2794)
			(end -0.12065 0.2794)
			(stroke
				(width 0.1)
				(type default)
			)
			(layer "F.Fab")
		)
		(fp_line
			(start 0.120396 0.3048)
			(end 0.120396 0.2794)
			(stroke
				(width 0.1)
				(type default)
			)
			(layer "F.Fab")
		)
		(fp_line
			(start 0.12065 -0.3048)
			(end 0.67945 -0.3048)
			(stroke
				(width 0.1)
				(type default)
			)
			(layer "F.Fab")
		)
		(fp_line
			(start 0.12065 -0.2794)
			(end 0.12065 -0.3048)
			(stroke
				(width 0.1)
				(type default)
			)
			(layer "F.Fab")
		)
		(fp_line
			(start 0.67945 -0.3048)
			(end 0.67945 0.3048)
			(stroke
				(width 0.1)
				(type default)
			)
			(layer "F.Fab")
		)
		(fp_line
			(start 0.67945 0.3048)
			(end 0.120396 0.3048)
			(stroke
				(width 0.1)
				(type default)
			)
			(layer "F.Fab")
		)
		(pad "1" smd circle
			(at -0.40005 0)
			(size 0 0)
			(layers "F.Cu" "F.Mask" "F.Paste")
			(net "P52V_HS1_EN_DISCHARGE_VBE")
		)
		(pad "2" smd circle
			(at 0.40005 0)
			(size 0 0)
			(layers "F.Cu" "F.Mask" "F.Paste")
			(net "P52V_HS1_EN_DISCHARGE_VBE_R")
		)
	)
	(footprint ""
		(layer "F.Cu")
		(at 450.041264 -85.870796 -90)
		(property "Reference" "PR114"
			(at 0 0 270)
			(layer "F.SilkS")
			(hide yes)
			(effects
				(font
					(size 1.27 1.27)
				)
			)
		)
		(property "Value" ""
			(at 0 0 270)
			(layer "F.Fab")
			(effects
				(font
					(size 1.27 1.27)
				)
			)
		)
		(duplicate_pad_numbers_are_jumpers no)
		(fp_line
			(start -0.7874 0.4064)
			(end -0.7874 -0.4064)
			(stroke
				(width 0.1524)
				(type default)
			)
			(layer "F.SilkS")
		)
		(fp_line
			(start 0.7874 0.4064)
			(end -0.7874 0.4064)
			(stroke
				(width 0.1524)
				(type default)
			)
			(layer "F.SilkS")
		)
		(fp_line
			(start -0.7874 -0.4064)
			(end 0.7874 -0.4064)
			(stroke
				(width 0.1524)
				(type default)
			)
			(layer "F.SilkS")
		)
		(fp_line
			(start 0.7874 -0.4064)
			(end 0.7874 0.4064)
			(stroke
				(width 0.1524)
				(type default)
			)
			(layer "F.SilkS")
		)
		(fp_line
			(start -0.67945 0.3048)
			(end -0.67945 -0.305054)
			(stroke
				(width 0.1)
				(type default)
			)
			(layer "F.Fab")
		)
		(fp_line
			(start -0.12065 0.3048)
			(end -0.67945 0.3048)
			(stroke
				(width 0.1)
				(type default)
			)
			(layer "F.Fab")
		)
		(fp_line
			(start 0.120396 0.3048)
			(end 0.120396 0.2794)
			(stroke
				(width 0.1)
				(type default)
			)
			(layer "F.Fab")
		)
		(fp_line
			(start 0.67945 0.3048)
			(end 0.120396 0.3048)
			(stroke
				(width 0.1)
				(type default)
			)
			(layer "F.Fab")
		)
		(fp_line
			(start -0.12065 0.2794)
			(end -0.12065 0.3048)
			(stroke
				(width 0.1)
				(type default)
			)
			(layer "F.Fab")
		)
		(fp_line
			(start 0.120396 0.2794)
			(end -0.12065 0.2794)
			(stroke
				(width 0.1)
				(type default)
			)
			(layer "F.Fab")
		)
		(fp_line
			(start -0.12065 -0.2794)
			(end 0.12065 -0.2794)
			(stroke
				(width 0.1)
				(type default)
			)
			(layer "F.Fab")
		)
		(fp_line
			(start 0.12065 -0.2794)
			(end 0.12065 -0.3048)
			(stroke
				(width 0.1)
				(type default)
			)
			(layer "F.Fab")
		)
		(fp_line
			(start 0.12065 -0.3048)
			(end 0.67945 -0.3048)
			(stroke
				(width 0.1)
				(type default)
			)
			(layer "F.Fab")
		)
		(fp_line
			(start 0.67945 -0.3048)
			(end 0.67945 0.3048)
			(stroke
				(width 0.1)
				(type default)
			)
			(layer "F.Fab")
		)
		(fp_line
			(start -0.67945 -0.305054)
			(end -0.12065 -0.305054)
			(stroke
				(width 0.1)
				(type default)
			)
			(layer "F.Fab")
		)
		(fp_line
			(start -0.12065 -0.305054)
			(end -0.12065 -0.2794)
			(stroke
				(width 0.1)
				(type default)
			)
			(layer "F.Fab")
		)
		(pad "1" smd circle
			(at -0.40005 0 270)
			(size 0 0)
			(layers "F.Cu" "F.Mask" "F.Paste")
			(net "P3V3_HPDB_FB")
		)
		(pad "2" smd circle
			(at 0.40005 0 270)
			(size 0 0)
			(layers "F.Cu" "F.Mask" "F.Paste")
			(net "GND")
		)
	)
	(footprint ""
		(layer "F.Cu")
		(at 304.546 -73.279)
		(property "Reference" "PR7040"
			(at 0 0 0)
			(layer "F.SilkS")
			(hide yes)
			(effects
				(font
					(size 1.27 1.27)
				)
			)
		)
		(property "Value" ""
			(at 0 0 0)
			(layer "F.Fab")
			(effects
				(font
					(size 1.27 1.27)
				)
			)
		)
		(duplicate_pad_numbers_are_jumpers no)
		(fp_line
			(start -0.7874 -0.4064)
			(end 0.7874 -0.4064)
			(stroke
				(width 0.1524)
				(type default)
			)
			(layer "F.SilkS")
		)
		(fp_line
			(start -0.7874 0.4064)
			(end -0.7874 -0.4064)
			(stroke
				(width 0.1524)
				(type default)
			)
			(layer "F.SilkS")
		)
		(fp_line
			(start 0.7874 -0.4064)
			(end 0.7874 0.4064)
			(stroke
				(width 0.1524)
				(type default)
			)
			(layer "F.SilkS")
		)
		(fp_line
			(start 0.7874 0.4064)
			(end -0.7874 0.4064)
			(stroke
				(width 0.1524)
				(type default)
			)
			(layer "F.SilkS")
		)
		(fp_line
			(start -0.67945 -0.305054)
			(end -0.12065 -0.305054)
			(stroke
				(width 0.1)
				(type default)
			)
			(layer "F.Fab")
		)
		(fp_line
			(start -0.67945 0.3048)
			(end -0.67945 -0.305054)
			(stroke
				(width 0.1)
				(type default)
			)
			(layer "F.Fab")
		)
		(fp_line
			(start -0.12065 -0.305054)
			(end -0.12065 -0.2794)
			(stroke
				(width 0.1)
				(type default)
			)
			(layer "F.Fab")
		)
		(fp_line
			(start -0.12065 -0.2794)
			(end 0.12065 -0.2794)
			(stroke
				(width 0.1)
				(type default)
			)
			(layer "F.Fab")
		)
		(fp_line
			(start -0.12065 0.2794)
			(end -0.12065 0.3048)
			(stroke
				(width 0.1)
				(type default)
			)
			(layer "F.Fab")
		)
		(fp_line
			(start -0.12065 0.3048)
			(end -0.67945 0.3048)
			(stroke
				(width 0.1)
				(type default)
			)
			(layer "F.Fab")
		)
		(fp_line
			(start 0.120396 0.2794)
			(end -0.12065 0.2794)
			(stroke
				(width 0.1)
				(type default)
			)
			(layer "F.Fab")
		)
		(fp_line
			(start 0.120396 0.3048)
			(end 0.120396 0.2794)
			(stroke
				(width 0.1)
				(type default)
			)
			(layer "F.Fab")
		)
		(fp_line
			(start 0.12065 -0.3048)
			(end 0.67945 -0.3048)
			(stroke
				(width 0.1)
				(type default)
			)
			(layer "F.Fab")
		)
		(fp_line
			(start 0.12065 -0.2794)
			(end 0.12065 -0.3048)
			(stroke
				(width 0.1)
				(type default)
			)
			(layer "F.Fab")
		)
		(fp_line
			(start 0.67945 -0.3048)
			(end 0.67945 0.3048)
			(stroke
				(width 0.1)
				(type default)
			)
			(layer "F.Fab")
		)
		(fp_line
			(start 0.67945 0.3048)
			(end 0.120396 0.3048)
			(stroke
				(width 0.1)
				(type default)
			)
			(layer "F.Fab")
		)
		(pad "1" smd circle
			(at -0.40005 0)
			(size 0 0)
			(layers "F.Cu" "F.Mask" "F.Paste")
			(net "P52V_HS_4287_S1P")
		)
		(pad "2" smd circle
			(at 0.40005 0)
			(size 0 0)
			(layers "F.Cu" "F.Mask" "F.Paste")
			(net "P52V_HS_4287_S1N")
		)
	)
	(footprint ""
		(layer "F.Cu")
		(at 140.79982 -34.3662)
		(property "Reference" "PR6988"
			(at 0 0 0)
			(layer "F.SilkS")
			(hide yes)
			(effects
				(font
					(size 1.27 1.27)
				)
			)
		)
		(property "Value" ""
			(at 0 0 0)
			(layer "F.Fab")
			(effects
				(font
					(size 1.27 1.27)
				)
			)
		)
		(duplicate_pad_numbers_are_jumpers no)
		(fp_line
			(start -1.2954 -0.5842)
			(end 1.2954 -0.5842)
			(stroke
				(width 0.1524)
				(type default)
			)
			(layer "F.SilkS")
		)
		(fp_line
			(start -1.2954 0.5842)
			(end -1.2954 -0.5842)
			(stroke
				(width 0.1524)
				(type default)
			)
			(layer "F.SilkS")
		)
		(fp_line
			(start 1.2954 -0.5842)
			(end 1.2954 0.5842)
			(stroke
				(width 0.1524)
				(type default)
			)
			(layer "F.SilkS")
		)
		(fp_line
			(start 1.2954 0.5842)
			(end -1.2954 0.5842)
			(stroke
				(width 0.1524)
				(type default)
			)
			(layer "F.SilkS")
		)
		(fp_line
			(start -1.1938 -0.406654)
			(end -0.8636 -0.406654)
			(stroke
				(width 0.1)
				(type default)
			)
			(layer "F.Fab")
		)
		(fp_line
			(start -1.1938 0.4064)
			(end -1.1938 -0.406654)
			(stroke
				(width 0.1)
				(type default)
			)
			(layer "F.Fab")
		)
		(fp_line
			(start -0.8636 -0.4572)
			(end 0.8636 -0.4572)
			(stroke
				(width 0.1)
				(type default)
			)
			(layer "F.Fab")
		)
		(fp_line
			(start -0.8636 -0.406654)
			(end -0.8636 -0.4572)
			(stroke
				(width 0.1)
				(type default)
			)
			(layer "F.Fab")
		)
		(fp_line
			(start -0.8636 0.4064)
			(end -1.1938 0.4064)
			(stroke
				(width 0.1)
				(type default)
			)
			(layer "F.Fab")
		)
		(fp_line
			(start -0.8636 0.4318)
			(end -0.8636 0.4064)
			(stroke
				(width 0.1)
				(type default)
			)
			(layer "F.Fab")
		)
		(fp_line
			(start -0.8636 0.4572)
			(end -0.8636 0.4318)
			(stroke
				(width 0.1)
				(type default)
			)
			(layer "F.Fab")
		)
		(fp_line
			(start 0.8636 -0.4572)
			(end 0.8636 -0.406654)
			(stroke
				(width 0.1)
				(type default)
			)
			(layer "F.Fab")
		)
		(fp_line
			(start 0.8636 -0.406654)
			(end 1.1938 -0.406654)
			(stroke
				(width 0.1)
				(type default)
			)
			(layer "F.Fab")
		)
		(fp_line
			(start 0.8636 0.4064)
			(end 0.8636 0.4572)
			(stroke
				(width 0.1)
				(type default)
			)
			(layer "F.Fab")
		)
		(fp_line
			(start 0.8636 0.4572)
			(end -0.8636 0.4572)
			(stroke
				(width 0.1)
				(type default)
			)
			(layer "F.Fab")
		)
		(fp_line
			(start 1.1938 -0.406654)
			(end 1.1938 0.4064)
			(stroke
				(width 0.1)
				(type default)
			)
			(layer "F.Fab")
		)
		(fp_line
			(start 1.1938 0.4064)
			(end 0.8636 0.4064)
			(stroke
				(width 0.1)
				(type default)
			)
			(layer "F.Fab")
		)
		(pad "1" smd rect
			(at -0.7366 0 270)
			(size 0.7112 0.8128)
			(layers "F.Cu" "F.Mask" "F.Paste")
			(net "P52V_HS2_SENSE_N_R2")
		)
		(pad "2" smd rect
			(at 0.7366 0 270)
			(size 0.7112 0.8128)
			(layers "F.Cu" "F.Mask" "F.Paste")
			(net "P52V_HS2_4287_ADC_N")
		)
	)
	(footprint ""
		(layer "F.Cu")
		(at 145.11782 -69.977)
		(property "Reference" "PR6983"
			(at 0 0 0)
			(layer "F.SilkS")
			(hide yes)
			(effects
				(font
					(size 1.27 1.27)
				)
			)
		)
		(property "Value" ""
			(at 0 0 0)
			(layer "F.Fab")
			(effects
				(font
					(size 1.27 1.27)
				)
			)
		)
		(duplicate_pad_numbers_are_jumpers no)
		(fp_line
			(start -1.2954 -0.5842)
			(end 1.2954 -0.5842)
			(stroke
				(width 0.1524)
				(type default)
			)
			(layer "F.SilkS")
		)
		(fp_line
			(start -1.2954 0.5842)
			(end -1.2954 -0.5842)
			(stroke
				(width 0.1524)
				(type default)
			)
			(layer "F.SilkS")
		)
		(fp_line
			(start 1.2954 -0.5842)
			(end 1.2954 0.5842)
			(stroke
				(width 0.1524)
				(type default)
			)
			(layer "F.SilkS")
		)
		(fp_line
			(start 1.2954 0.5842)
			(end -1.2954 0.5842)
			(stroke
				(width 0.1524)
				(type default)
			)
			(layer "F.SilkS")
		)
		(fp_line
			(start -1.1938 -0.406654)
			(end -0.8636 -0.406654)
			(stroke
				(width 0.1)
				(type default)
			)
			(layer "F.Fab")
		)
		(fp_line
			(start -1.1938 0.4064)
			(end -1.1938 -0.406654)
			(stroke
				(width 0.1)
				(type default)
			)
			(layer "F.Fab")
		)
		(fp_line
			(start -0.8636 -0.4572)
			(end 0.8636 -0.4572)
			(stroke
				(width 0.1)
				(type default)
			)
			(layer "F.Fab")
		)
		(fp_line
			(start -0.8636 -0.406654)
			(end -0.8636 -0.4572)
			(stroke
				(width 0.1)
				(type default)
			)
			(layer "F.Fab")
		)
		(fp_line
			(start -0.8636 0.4064)
			(end -1.1938 0.4064)
			(stroke
				(width 0.1)
				(type default)
			)
			(layer "F.Fab")
		)
		(fp_line
			(start -0.8636 0.4318)
			(end -0.8636 0.4064)
			(stroke
				(width 0.1)
				(type default)
			)
			(layer "F.Fab")
		)
		(fp_line
			(start -0.8636 0.4572)
			(end -0.8636 0.4318)
			(stroke
				(width 0.1)
				(type default)
			)
			(layer "F.Fab")
		)
		(fp_line
			(start 0.8636 -0.4572)
			(end 0.8636 -0.406654)
			(stroke
				(width 0.1)
				(type default)
			)
			(layer "F.Fab")
		)
		(fp_line
			(start 0.8636 -0.406654)
			(end 1.1938 -0.406654)
			(stroke
				(width 0.1)
				(type default)
			)
			(layer "F.Fab")
		)
		(fp_line
			(start 0.8636 0.4064)
			(end 0.8636 0.4572)
			(stroke
				(width 0.1)
				(type default)
			)
			(layer "F.Fab")
		)
		(fp_line
			(start 0.8636 0.4572)
			(end -0.8636 0.4572)
			(stroke
				(width 0.1)
				(type default)
			)
			(layer "F.Fab")
		)
		(fp_line
			(start 1.1938 -0.406654)
			(end 1.1938 0.4064)
			(stroke
				(width 0.1)
				(type default)
			)
			(layer "F.Fab")
		)
		(fp_line
			(start 1.1938 0.4064)
			(end 0.8636 0.4064)
			(stroke
				(width 0.1)
				(type default)
			)
			(layer "F.Fab")
		)
		(pad "1" smd rect
			(at -0.7366 0 270)
			(size 0.7112 0.8128)
			(layers "F.Cu" "F.Mask" "F.Paste")
			(net "P52V_HS2_4287_ADC_P")
		)
		(pad "2" smd rect
			(at 0.7366 0 270)
			(size 0.7112 0.8128)
			(layers "F.Cu" "F.Mask" "F.Paste")
			(net "P52V_HS2_SENSE_P_R1")
		)
	)
	(footprint ""
		(layer "F.Cu")
		(at 423.291 -47.371)
		(property "Reference" "C8"
			(at 0 0 0)
			(layer "F.SilkS")
			(hide yes)
			(effects
				(font
					(size 1.27 1.27)
				)
			)
		)
		(property "Value" ""
			(at 0 0 0)
			(layer "F.Fab")
			(effects
				(font
					(size 1.27 1.27)
				)
			)
		)
		(duplicate_pad_numbers_are_jumpers no)
		(fp_line
			(start -0.7874 -0.4064)
			(end 0.7874 -0.4064)
			(stroke
				(width 0.1524)
				(type default)
			)
			(layer "F.SilkS")
		)
		(fp_line
			(start -0.7874 0.4064)
			(end -0.7874 -0.4064)
			(stroke
				(width 0.1524)
				(type default)
			)
			(layer "F.SilkS")
		)
		(fp_line
			(start 0.7874 -0.4064)
			(end 0.7874 0.4064)
			(stroke
				(width 0.1524)
				(type default)
			)
			(layer "F.SilkS")
		)
		(fp_line
			(start 0.7874 0.4064)
			(end -0.7874 0.4064)
			(stroke
				(width 0.1524)
				(type default)
			)
			(layer "F.SilkS")
		)
		(fp_line
			(start -0.67945 -0.305054)
			(end -0.12065 -0.305054)
			(stroke
				(width 0.1)
				(type default)
			)
			(layer "F.Fab")
		)
		(fp_line
			(start -0.67945 0.3048)
			(end -0.67945 -0.305054)
			(stroke
				(width 0.1)
				(type default)
			)
			(layer "F.Fab")
		)
		(fp_line
			(start -0.12065 -0.305054)
			(end -0.12065 -0.2794)
			(stroke
				(width 0.1)
				(type default)
			)
			(layer "F.Fab")
		)
		(fp_line
			(start -0.12065 -0.2794)
			(end 0.12065 -0.2794)
			(stroke
				(width 0.1)
				(type default)
			)
			(layer "F.Fab")
		)
		(fp_line
			(start -0.12065 0.2794)
			(end -0.12065 0.3048)
			(stroke
				(width 0.1)
				(type default)
			)
			(layer "F.Fab")
		)
		(fp_line
			(start -0.12065 0.3048)
			(end -0.67945 0.3048)
			(stroke
				(width 0.1)
				(type default)
			)
			(layer "F.Fab")
		)
		(fp_line
			(start 0.120396 0.2794)
			(end -0.12065 0.2794)
			(stroke
				(width 0.1)
				(type default)
			)
			(layer "F.Fab")
		)
		(fp_line
			(start 0.120396 0.3048)
			(end 0.120396 0.2794)
			(stroke
				(width 0.1)
				(type default)
			)
			(layer "F.Fab")
		)
		(fp_line
			(start 0.12065 -0.3048)
			(end 0.67945 -0.3048)
			(stroke
				(width 0.1)
				(type default)
			)
			(layer "F.Fab")
		)
		(fp_line
			(start 0.12065 -0.2794)
			(end 0.12065 -0.3048)
			(stroke
				(width 0.1)
				(type default)
			)
			(layer "F.Fab")
		)
		(fp_line
			(start 0.67945 -0.3048)
			(end 0.67945 0.3048)
			(stroke
				(width 0.1)
				(type default)
			)
			(layer "F.Fab")
		)
		(fp_line
			(start 0.67945 0.3048)
			(end 0.120396 0.3048)
			(stroke
				(width 0.1)
				(type default)
			)
			(layer "F.Fab")
		)
		(pad "1" smd circle
			(at -0.40005 0)
			(size 0 0)
			(layers "F.Cu" "F.Mask" "F.Paste")
			(net "P3V3_AUX")
		)
		(pad "2" smd circle
			(at 0.40005 0)
			(size 0 0)
			(layers "F.Cu" "F.Mask" "F.Paste")
			(net "GND")
		)
	)
	(footprint ""
		(layer "F.Cu")
		(at 456.999848 -121.499884 180)
		(property "Reference" "H15"
			(at 0.917448 -5.448554 0)
			(unlocked yes)
			(layer "F.SilkS")
			(effects
				(font
					(size 0.7874 0.5842)
					(thickness 0.1524)
				)
				(justify left)
			)
		)
		(property "Value" ""
			(at 0 0 180)
			(layer "F.Fab")
			(effects
				(font
					(size 1.27 1.27)
				)
			)
		)
		(duplicate_pad_numbers_are_jumpers no)
		(pad "1" thru_hole oval
			(at 0 0 180)
			(size 9.017 14.0208)
			(drill 3.0226
				(offset 0 2.499868)
			)
			(layers "*.Cu" "*.Mask")
			(remove_unused_layers no)
			(net "GND")
			(clearance -1.500378)
			(padstack
				(mode front_inner_back)
				(layer "Inner"
					(shape circle)
					(size 0 0)
					(clearance 0)
				)
				(layer "B.Cu"
					(shape oval)
					(size 9.017 14.0208)
					(offset 0 2.499868)
					(clearance -1.500378)
				)
			)
		)
	)
	(footprint ""
		(layer "F.Cu")
		(at 323.13626 -29.5402 180)
		(property "Reference" "PQ35"
			(at -9.628886 -3.917188 0)
			(unlocked yes)
			(layer "F.SilkS")
			(effects
				(font
					(size 0.7874 0.5842)
					(thickness 0.1524)
				)
				(justify left)
			)
		)
		(property "Value" ""
			(at 0 0 180)
			(layer "F.Fab")
			(effects
				(font
					(size 1.27 1.27)
				)
			)
		)
		(duplicate_pad_numbers_are_jumpers no)
		(fp_line
			(start 7.649972 4.99999)
			(end 7.649972 -4.99999)
			(stroke
				(width 0.1524)
				(type default)
			)
			(layer "F.SilkS")
		)
		(fp_line
			(start 7.649972 -4.99999)
			(end 7.630414 -4.99999)
			(stroke
				(width 0.1524)
				(type default)
			)
			(layer "F.SilkS")
		)
		(fp_line
			(start 7.630414 4.99999)
			(end 7.649972 4.99999)
			(stroke
				(width 0.1524)
				(type default)
			)
			(layer "F.SilkS")
		)
		(fp_line
			(start 5.115814 -4.99999)
			(end -7.649972 -4.99999)
			(stroke
				(width 0.1524)
				(type default)
			)
			(layer "F.SilkS")
		)
		(fp_line
			(start -7.649972 4.99999)
			(end 5.115814 4.99999)
			(stroke
				(width 0.1524)
				(type default)
			)
			(layer "F.SilkS")
		)
		(fp_line
			(start -7.649972 3.3274)
			(end -7.649972 4.99999)
			(stroke
				(width 0.1524)
				(type default)
			)
			(layer "F.SilkS")
		)
		(fp_line
			(start -7.649972 -1.7526)
			(end -7.649972 1.7526)
			(stroke
				(width 0.1524)
				(type default)
			)
			(layer "F.SilkS")
		)
		(fp_line
			(start -7.649972 -4.99999)
			(end -7.649972 -3.3274)
			(stroke
				(width 0.1524)
				(type default)
			)
			(layer "F.SilkS")
		)
		(fp_line
			(start 7.649972 4.99999)
			(end 7.649972 -4.99999)
			(stroke
				(width 0.1)
				(type default)
			)
			(layer "F.Fab")
		)
		(fp_line
			(start 7.649972 -4.99999)
			(end -7.649972 -4.99999)
			(stroke
				(width 0.1)
				(type default)
			)
			(layer "F.Fab")
		)
		(fp_line
			(start -7.649972 4.99999)
			(end 7.649972 4.99999)
			(stroke
				(width 0.1)
				(type default)
			)
			(layer "F.Fab")
		)
		(fp_line
			(start -7.649972 -4.99999)
			(end -7.649972 4.99999)
			(stroke
				(width 0.1)
				(type default)
			)
			(layer "F.Fab")
		)
		(pad "D" smd circle
			(at 2.15011 0 180)
			(size 0 0)
			(layers "F.Cu" "F.Mask" "F.Paste")
			(net "P52V_HS1_DRAIN_2")
		)
		(pad "G" smd rect
			(at -7.050024 -2.54 90)
			(size 1.3208 3.0988)
			(layers "F.Cu" "F.Mask" "F.Paste")
			(net "P52V_HS1_GATE4")
		)
		(pad "S" smd rect
			(at -7.050024 2.54 90)
			(size 1.3208 3.0988)
			(layers "F.Cu" "F.Mask" "F.Paste")
			(net "P52V_HS1")
		)
		(zone
			(layer "F.Cu")
			(hatch none 0.5)
			(connect_pads
				(clearance 0)
			)
			(min_thickness 0.25)
			(keepout
				(tracks not_allowed)
				(vias allowed)
				(pads allowed)
				(copperpour not_allowed)
				(footprints allowed)
			)
			(placement
				(enabled no)
				(sheetname "")
			)
			(fill
				(thermal_gap 0.5)
				(thermal_bridge_width 0.5)
				(island_removal_mode 0)
			)
			(polygon
				(pts
					(xy 317.95466 -24.5618) (xy 330.78166 -24.5618) (xy 330.78166 -26.289) (xy 328.57186 -26.289) (xy 328.57186 -27.7114)
					(xy 330.78166 -27.7114) (xy 330.78166 -31.369) (xy 328.57186 -31.369) (xy 328.57186 -32.7914) (xy 330.78166 -32.7914)
					(xy 330.78166 -34.5186) (xy 317.95466 -34.5186) (xy 317.95466 -33.3502) (xy 324.15226 -33.3502)
					(xy 324.15226 -25.7302) (xy 317.95466 -25.7302)
				)
			)
		)
	)
	(footprint ""
		(layer "F.Cu")
		(at 413.07258 -30.26156 180)
		(property "Reference" "R5922"
			(at 0 0 180)
			(layer "F.SilkS")
			(hide yes)
			(effects
				(font
					(size 1.27 1.27)
				)
			)
		)
		(property "Value" ""
			(at 0 0 180)
			(layer "F.Fab")
			(effects
				(font
					(size 1.27 1.27)
				)
			)
		)
		(duplicate_pad_numbers_are_jumpers no)
		(fp_line
			(start 0.7874 0.4064)
			(end -0.7874 0.4064)
			(stroke
				(width 0.1524)
				(type default)
			)
			(layer "F.SilkS")
		)
		(fp_line
			(start 0.7874 -0.4064)
			(end 0.7874 0.4064)
			(stroke
				(width 0.1524)
				(type default)
			)
			(layer "F.SilkS")
		)
		(fp_line
			(start -0.7874 0.4064)
			(end -0.7874 -0.4064)
			(stroke
				(width 0.1524)
				(type default)
			)
			(layer "F.SilkS")
		)
		(fp_line
			(start -0.7874 -0.4064)
			(end 0.7874 -0.4064)
			(stroke
				(width 0.1524)
				(type default)
			)
			(layer "F.SilkS")
		)
		(fp_line
			(start 0.67945 0.3048)
			(end 0.120396 0.3048)
			(stroke
				(width 0.1)
				(type default)
			)
			(layer "F.Fab")
		)
		(fp_line
			(start 0.67945 -0.3048)
			(end 0.67945 0.3048)
			(stroke
				(width 0.1)
				(type default)
			)
			(layer "F.Fab")
		)
		(fp_line
			(start 0.12065 -0.2794)
			(end 0.12065 -0.3048)
			(stroke
				(width 0.1)
				(type default)
			)
			(layer "F.Fab")
		)
		(fp_line
			(start 0.12065 -0.3048)
			(end 0.67945 -0.3048)
			(stroke
				(width 0.1)
				(type default)
			)
			(layer "F.Fab")
		)
		(fp_line
			(start 0.120396 0.3048)
			(end 0.120396 0.2794)
			(stroke
				(width 0.1)
				(type default)
			)
			(layer "F.Fab")
		)
		(fp_line
			(start 0.120396 0.2794)
			(end -0.12065 0.2794)
			(stroke
				(width 0.1)
				(type default)
			)
			(layer "F.Fab")
		)
		(fp_line
			(start -0.12065 0.3048)
			(end -0.67945 0.3048)
			(stroke
				(width 0.1)
				(type default)
			)
			(layer "F.Fab")
		)
		(fp_line
			(start -0.12065 0.2794)
			(end -0.12065 0.3048)
			(stroke
				(width 0.1)
				(type default)
			)
			(layer "F.Fab")
		)
		(fp_line
			(start -0.12065 -0.2794)
			(end 0.12065 -0.2794)
			(stroke
				(width 0.1)
				(type default)
			)
			(layer "F.Fab")
		)
		(fp_line
			(start -0.12065 -0.305054)
			(end -0.12065 -0.2794)
			(stroke
				(width 0.1)
				(type default)
			)
			(layer "F.Fab")
		)
		(fp_line
			(start -0.67945 0.3048)
			(end -0.67945 -0.305054)
			(stroke
				(width 0.1)
				(type default)
			)
			(layer "F.Fab")
		)
		(fp_line
			(start -0.67945 -0.305054)
			(end -0.12065 -0.305054)
			(stroke
				(width 0.1)
				(type default)
			)
			(layer "F.Fab")
		)
		(pad "1" smd circle
			(at -0.40005 0 180)
			(size 0 0)
			(layers "F.Cu" "F.Mask" "F.Paste")
			(net "P12V_LED_FLTB")
		)
		(pad "2" smd circle
			(at 0.40005 0 180)
			(size 0 0)
			(layers "F.Cu" "F.Mask" "F.Paste")
			(net "P3V3_AUX")
		)
	)
	(footprint ""
		(layer "F.Cu")
		(at 145.11782 -71.755)
		(property "Reference" "PR6981"
			(at 0 0 0)
			(layer "F.SilkS")
			(hide yes)
			(effects
				(font
					(size 1.27 1.27)
				)
			)
		)
		(property "Value" ""
			(at 0 0 0)
			(layer "F.Fab")
			(effects
				(font
					(size 1.27 1.27)
				)
			)
		)
		(duplicate_pad_numbers_are_jumpers no)
		(fp_line
			(start -1.2954 -0.5842)
			(end 1.2954 -0.5842)
			(stroke
				(width 0.1524)
				(type default)
			)
			(layer "F.SilkS")
		)
		(fp_line
			(start -1.2954 0.5842)
			(end -1.2954 -0.5842)
			(stroke
				(width 0.1524)
				(type default)
			)
			(layer "F.SilkS")
		)
		(fp_line
			(start 1.2954 -0.5842)
			(end 1.2954 0.5842)
			(stroke
				(width 0.1524)
				(type default)
			)
			(layer "F.SilkS")
		)
		(fp_line
			(start 1.2954 0.5842)
			(end -1.2954 0.5842)
			(stroke
				(width 0.1524)
				(type default)
			)
			(layer "F.SilkS")
		)
		(fp_line
			(start -1.1938 -0.406654)
			(end -0.8636 -0.406654)
			(stroke
				(width 0.1)
				(type default)
			)
			(layer "F.Fab")
		)
		(fp_line
			(start -1.1938 0.4064)
			(end -1.1938 -0.406654)
			(stroke
				(width 0.1)
				(type default)
			)
			(layer "F.Fab")
		)
		(fp_line
			(start -0.8636 -0.4572)
			(end 0.8636 -0.4572)
			(stroke
				(width 0.1)
				(type default)
			)
			(layer "F.Fab")
		)
		(fp_line
			(start -0.8636 -0.406654)
			(end -0.8636 -0.4572)
			(stroke
				(width 0.1)
				(type default)
			)
			(layer "F.Fab")
		)
		(fp_line
			(start -0.8636 0.4064)
			(end -1.1938 0.4064)
			(stroke
				(width 0.1)
				(type default)
			)
			(layer "F.Fab")
		)
		(fp_line
			(start -0.8636 0.4318)
			(end -0.8636 0.4064)
			(stroke
				(width 0.1)
				(type default)
			)
			(layer "F.Fab")
		)
		(fp_line
			(start -0.8636 0.4572)
			(end -0.8636 0.4318)
			(stroke
				(width 0.1)
				(type default)
			)
			(layer "F.Fab")
		)
		(fp_line
			(start 0.8636 -0.4572)
			(end 0.8636 -0.406654)
			(stroke
				(width 0.1)
				(type default)
			)
			(layer "F.Fab")
		)
		(fp_line
			(start 0.8636 -0.406654)
			(end 1.1938 -0.406654)
			(stroke
				(width 0.1)
				(type default)
			)
			(layer "F.Fab")
		)
		(fp_line
			(start 0.8636 0.4064)
			(end 0.8636 0.4572)
			(stroke
				(width 0.1)
				(type default)
			)
			(layer "F.Fab")
		)
		(fp_line
			(start 0.8636 0.4572)
			(end -0.8636 0.4572)
			(stroke
				(width 0.1)
				(type default)
			)
			(layer "F.Fab")
		)
		(fp_line
			(start 1.1938 -0.406654)
			(end 1.1938 0.4064)
			(stroke
				(width 0.1)
				(type default)
			)
			(layer "F.Fab")
		)
		(fp_line
			(start 1.1938 0.4064)
			(end 0.8636 0.4064)
			(stroke
				(width 0.1)
				(type default)
			)
			(layer "F.Fab")
		)
		(pad "1" smd rect
			(at -0.7366 0 270)
			(size 0.7112 0.8128)
			(layers "F.Cu" "F.Mask" "F.Paste")
			(net "P52V_HS2_4287_S1P")
		)
		(pad "2" smd rect
			(at 0.7366 0 270)
			(size 0.7112 0.8128)
			(layers "F.Cu" "F.Mask" "F.Paste")
			(net "P52V_HS2_SENSE_P_R1")
		)
	)
	(footprint ""
		(layer "F.Cu")
		(at 317.2079 -83.82 180)
		(property "Reference" "PR6969"
			(at 0 0 180)
			(layer "F.SilkS")
			(hide yes)
			(effects
				(font
					(size 1.27 1.27)
				)
			)
		)
		(property "Value" ""
			(at 0 0 180)
			(layer "F.Fab")
			(effects
				(font
					(size 1.27 1.27)
				)
			)
		)
		(duplicate_pad_numbers_are_jumpers no)
		(fp_line
			(start 0.7874 0.4064)
			(end -0.7874 0.4064)
			(stroke
				(width 0.1524)
				(type default)
			)
			(layer "F.SilkS")
		)
		(fp_line
			(start 0.7874 -0.4064)
			(end 0.7874 0.4064)
			(stroke
				(width 0.1524)
				(type default)
			)
			(layer "F.SilkS")
		)
		(fp_line
			(start -0.7874 0.4064)
			(end -0.7874 -0.4064)
			(stroke
				(width 0.1524)
				(type default)
			)
			(layer "F.SilkS")
		)
		(fp_line
			(start -0.7874 -0.4064)
			(end 0.7874 -0.4064)
			(stroke
				(width 0.1524)
				(type default)
			)
			(layer "F.SilkS")
		)
		(fp_line
			(start 0.67945 0.3048)
			(end 0.120396 0.3048)
			(stroke
				(width 0.1)
				(type default)
			)
			(layer "F.Fab")
		)
		(fp_line
			(start 0.67945 -0.3048)
			(end 0.67945 0.3048)
			(stroke
				(width 0.1)
				(type default)
			)
			(layer "F.Fab")
		)
		(fp_line
			(start 0.12065 -0.2794)
			(end 0.12065 -0.3048)
			(stroke
				(width 0.1)
				(type default)
			)
			(layer "F.Fab")
		)
		(fp_line
			(start 0.12065 -0.3048)
			(end 0.67945 -0.3048)
			(stroke
				(width 0.1)
				(type default)
			)
			(layer "F.Fab")
		)
		(fp_line
			(start 0.120396 0.3048)
			(end 0.120396 0.2794)
			(stroke
				(width 0.1)
				(type default)
			)
			(layer "F.Fab")
		)
		(fp_line
			(start 0.120396 0.2794)
			(end -0.12065 0.2794)
			(stroke
				(width 0.1)
				(type default)
			)
			(layer "F.Fab")
		)
		(fp_line
			(start -0.12065 0.3048)
			(end -0.67945 0.3048)
			(stroke
				(width 0.1)
				(type default)
			)
			(layer "F.Fab")
		)
		(fp_line
			(start -0.12065 0.2794)
			(end -0.12065 0.3048)
			(stroke
				(width 0.1)
				(type default)
			)
			(layer "F.Fab")
		)
		(fp_line
			(start -0.12065 -0.2794)
			(end 0.12065 -0.2794)
			(stroke
				(width 0.1)
				(type default)
			)
			(layer "F.Fab")
		)
		(fp_line
			(start -0.12065 -0.305054)
			(end -0.12065 -0.2794)
			(stroke
				(width 0.1)
				(type default)
			)
			(layer "F.Fab")
		)
		(fp_line
			(start -0.67945 0.3048)
			(end -0.67945 -0.305054)
			(stroke
				(width 0.1)
				(type default)
			)
			(layer "F.Fab")
		)
		(fp_line
			(start -0.67945 -0.305054)
			(end -0.12065 -0.305054)
			(stroke
				(width 0.1)
				(type default)
			)
			(layer "F.Fab")
		)
		(pad "1" smd rect
			(at -0.40005 0)
			(size 0.4572 0.508)
			(layers "F.Cu" "F.Mask" "F.Paste")
			(net "P52V_HS1_TEMPN_R")
		)
		(pad "2" smd rect
			(at 0.40005 0)
			(size 0.4572 0.508)
			(layers "F.Cu" "F.Mask" "F.Paste")
			(net "GND_FIELD_SIGNAL")
		)
	)
	(footprint ""
		(layer "F.Cu")
		(at 445.741806 -94.799658 180)
		(property "Reference" "PC618"
			(at 0 0 180)
			(layer "F.SilkS")
			(hide yes)
			(effects
				(font
					(size 1.27 1.27)
				)
			)
		)
		(property "Value" ""
			(at 0 0 180)
			(layer "F.Fab")
			(effects
				(font
					(size 1.27 1.27)
				)
			)
		)
		(duplicate_pad_numbers_are_jumpers no)
		(fp_line
			(start 1.524 0.762)
			(end -1.524 0.762)
			(stroke
				(width 0.1524)
				(type default)
			)
			(layer "F.SilkS")
		)
		(fp_line
			(start 1.524 -0.762)
			(end 1.524 0.762)
			(stroke
				(width 0.1524)
				(type default)
			)
			(layer "F.SilkS")
		)
		(fp_line
			(start -1.524 0.762)
			(end -1.524 -0.762)
			(stroke
				(width 0.1524)
				(type default)
			)
			(layer "F.SilkS")
		)
		(fp_line
			(start -1.524 -0.762)
			(end 1.524 -0.762)
			(stroke
				(width 0.1524)
				(type default)
			)
			(layer "F.SilkS")
		)
		(fp_line
			(start 1.1049 0.724916)
			(end 1.1049 -0.724916)
			(stroke
				(width 0.1)
				(type default)
			)
			(layer "F.Fab")
		)
		(fp_line
			(start 1.1049 -0.724916)
			(end -1.1049 -0.724916)
			(stroke
				(width 0.1)
				(type default)
			)
			(layer "F.Fab")
		)
		(fp_line
			(start -1.1049 0.724916)
			(end 1.1049 0.724916)
			(stroke
				(width 0.1)
				(type default)
			)
			(layer "F.Fab")
		)
		(fp_line
			(start -1.1049 -0.724916)
			(end -1.1049 0.724916)
			(stroke
				(width 0.1)
				(type default)
			)
			(layer "F.Fab")
		)
		(pad "1" smd rect
			(at -0.889 0)
			(size 1.016 1.27)
			(layers "F.Cu" "F.Mask" "F.Paste")
			(net "SW_P3V3_HPDB_FLT")
		)
		(pad "2" smd rect
			(at 0.889 0)
			(size 1.016 1.27)
			(layers "F.Cu" "F.Mask" "F.Paste")
			(net "GND")
		)
	)
	(footprint ""
		(layer "F.Cu")
		(at 449.199 -37.211 -90)
		(property "Reference" "R9"
			(at 0 0 270)
			(layer "F.SilkS")
			(hide yes)
			(effects
				(font
					(size 1.27 1.27)
				)
			)
		)
		(property "Value" ""
			(at 0 0 270)
			(layer "F.Fab")
			(effects
				(font
					(size 1.27 1.27)
				)
			)
		)
		(duplicate_pad_numbers_are_jumpers no)
		(fp_line
			(start -0.7874 0.4064)
			(end -0.7874 -0.4064)
			(stroke
				(width 0.1524)
				(type default)
			)
			(layer "F.SilkS")
		)
		(fp_line
			(start 0.7874 0.4064)
			(end -0.7874 0.4064)
			(stroke
				(width 0.1524)
				(type default)
			)
			(layer "F.SilkS")
		)
		(fp_line
			(start -0.7874 -0.4064)
			(end 0.7874 -0.4064)
			(stroke
				(width 0.1524)
				(type default)
			)
			(layer "F.SilkS")
		)
		(fp_line
			(start 0.7874 -0.4064)
			(end 0.7874 0.4064)
			(stroke
				(width 0.1524)
				(type default)
			)
			(layer "F.SilkS")
		)
		(fp_line
			(start -0.67945 0.3048)
			(end -0.67945 -0.305054)
			(stroke
				(width 0.1)
				(type default)
			)
			(layer "F.Fab")
		)
		(fp_line
			(start -0.12065 0.3048)
			(end -0.67945 0.3048)
			(stroke
				(width 0.1)
				(type default)
			)
			(layer "F.Fab")
		)
		(fp_line
			(start 0.120396 0.3048)
			(end 0.120396 0.2794)
			(stroke
				(width 0.1)
				(type default)
			)
			(layer "F.Fab")
		)
		(fp_line
			(start 0.67945 0.3048)
			(end 0.120396 0.3048)
			(stroke
				(width 0.1)
				(type default)
			)
			(layer "F.Fab")
		)
		(fp_line
			(start -0.12065 0.2794)
			(end -0.12065 0.3048)
			(stroke
				(width 0.1)
				(type default)
			)
			(layer "F.Fab")
		)
		(fp_line
			(start 0.120396 0.2794)
			(end -0.12065 0.2794)
			(stroke
				(width 0.1)
				(type default)
			)
			(layer "F.Fab")
		)
		(fp_line
			(start -0.12065 -0.2794)
			(end 0.12065 -0.2794)
			(stroke
				(width 0.1)
				(type default)
			)
			(layer "F.Fab")
		)
		(fp_line
			(start 0.12065 -0.2794)
			(end 0.12065 -0.3048)
			(stroke
				(width 0.1)
				(type default)
			)
			(layer "F.Fab")
		)
		(fp_line
			(start 0.12065 -0.3048)
			(end 0.67945 -0.3048)
			(stroke
				(width 0.1)
				(type default)
			)
			(layer "F.Fab")
		)
		(fp_line
			(start 0.67945 -0.3048)
			(end 0.67945 0.3048)
			(stroke
				(width 0.1)
				(type default)
			)
			(layer "F.Fab")
		)
		(fp_line
			(start -0.67945 -0.305054)
			(end -0.12065 -0.305054)
			(stroke
				(width 0.1)
				(type default)
			)
			(layer "F.Fab")
		)
		(fp_line
			(start -0.12065 -0.305054)
			(end -0.12065 -0.2794)
			(stroke
				(width 0.1)
				(type default)
			)
			(layer "F.Fab")
		)
		(pad "1" smd circle
			(at -0.40005 0 270)
			(size 0 0)
			(layers "F.Cu" "F.Mask" "F.Paste")
			(net "SMB_P52V_PDB_SDA_R")
		)
		(pad "2" smd circle
			(at 0.40005 0 270)
			(size 0 0)
			(layers "F.Cu" "F.Mask" "F.Paste")
			(net "P3V3_AUX")
		)
	)
	(footprint ""
		(layer "F.Cu")
		(at 112.988852 -32.8168 -90)
		(property "Reference" "PR6974"
			(at 0 0 270)
			(layer "F.SilkS")
			(hide yes)
			(effects
				(font
					(size 1.27 1.27)
				)
			)
		)
		(property "Value" ""
			(at 0 0 270)
			(layer "F.Fab")
			(effects
				(font
					(size 1.27 1.27)
				)
			)
		)
		(duplicate_pad_numbers_are_jumpers no)
		(fp_line
			(start -1.2954 0.5842)
			(end -1.2954 -0.5842)
			(stroke
				(width 0.1524)
				(type default)
			)
			(layer "F.SilkS")
		)
		(fp_line
			(start 1.2954 0.5842)
			(end -1.2954 0.5842)
			(stroke
				(width 0.1524)
				(type default)
			)
			(layer "F.SilkS")
		)
		(fp_line
			(start -1.2954 -0.5842)
			(end 1.2954 -0.5842)
			(stroke
				(width 0.1524)
				(type default)
			)
			(layer "F.SilkS")
		)
		(fp_line
			(start 1.2954 -0.5842)
			(end 1.2954 0.5842)
			(stroke
				(width 0.1524)
				(type default)
			)
			(layer "F.SilkS")
		)
		(fp_line
			(start -0.8636 0.4572)
			(end -0.8636 0.4318)
			(stroke
				(width 0.1)
				(type default)
			)
			(layer "F.Fab")
		)
		(fp_line
			(start 0.8636 0.4572)
			(end -0.8636 0.4572)
			(stroke
				(width 0.1)
				(type default)
			)
			(layer "F.Fab")
		)
		(fp_line
			(start -0.8636 0.4318)
			(end -0.8636 0.4064)
			(stroke
				(width 0.1)
				(type default)
			)
			(layer "F.Fab")
		)
		(fp_line
			(start -1.1938 0.4064)
			(end -1.1938 -0.406654)
			(stroke
				(width 0.1)
				(type default)
			)
			(layer "F.Fab")
		)
		(fp_line
			(start -0.8636 0.4064)
			(end -1.1938 0.4064)
			(stroke
				(width 0.1)
				(type default)
			)
			(layer "F.Fab")
		)
		(fp_line
			(start 0.8636 0.4064)
			(end 0.8636 0.4572)
			(stroke
				(width 0.1)
				(type default)
			)
			(layer "F.Fab")
		)
		(fp_line
			(start 1.1938 0.4064)
			(end 0.8636 0.4064)
			(stroke
				(width 0.1)
				(type default)
			)
			(layer "F.Fab")
		)
		(fp_line
			(start -1.1938 -0.406654)
			(end -0.8636 -0.406654)
			(stroke
				(width 0.1)
				(type default)
			)
			(layer "F.Fab")
		)
		(fp_line
			(start -0.8636 -0.406654)
			(end -0.8636 -0.4572)
			(stroke
				(width 0.1)
				(type default)
			)
			(layer "F.Fab")
		)
		(fp_line
			(start 0.8636 -0.406654)
			(end 1.1938 -0.406654)
			(stroke
				(width 0.1)
				(type default)
			)
			(layer "F.Fab")
		)
		(fp_line
			(start 1.1938 -0.406654)
			(end 1.1938 0.4064)
			(stroke
				(width 0.1)
				(type default)
			)
			(layer "F.Fab")
		)
		(fp_line
			(start -0.8636 -0.4572)
			(end 0.8636 -0.4572)
			(stroke
				(width 0.1)
				(type default)
			)
			(layer "F.Fab")
		)
		(fp_line
			(start 0.8636 -0.4572)
			(end 0.8636 -0.406654)
			(stroke
				(width 0.1)
				(type default)
			)
			(layer "F.Fab")
		)
		(pad "1" smd rect
			(at -0.7366 0 180)
			(size 0.7112 0.8128)
			(layers "F.Cu" "F.Mask" "F.Paste")
			(net "P52V_HS2_GATE2_R")
		)
		(pad "2" smd rect
			(at 0.7366 0 180)
			(size 0.7112 0.8128)
			(layers "F.Cu" "F.Mask" "F.Paste")
			(net "P52V_HS2_GATE5")
		)
	)
	(footprint ""
		(layer "F.Cu")
		(at 307.969412 -76.245974)
		(property "Reference" "H26"
			(at -1.1684 -3.52933 0)
			(unlocked yes)
			(layer "F.SilkS")
			(effects
				(font
					(size 0.7874 0.5842)
					(thickness 0.1524)
				)
				(justify left)
			)
		)
		(property "Value" ""
			(at 0 0 0)
			(layer "F.Fab")
			(effects
				(font
					(size 1.27 1.27)
				)
			)
		)
		(duplicate_pad_numbers_are_jumpers no)
		(fp_circle
			(center 0 0)
			(end 2.4003 0)
			(stroke
				(width 0.1524)
				(type default)
			)
			(fill no)
			(layer "F.SilkS")
		)
		(fp_circle
			(center 0 0)
			(end 6.5913 0)
			(stroke
				(width 0.1524)
				(type default)
			)
			(fill no)
			(layer "B.SilkS")
		)
		(fp_circle
			(center 0 0)
			(end 6.5913 0)
			(stroke
				(width 0.1)
				(type default)
			)
			(fill no)
			(layer "B.Fab")
		)
		(fp_circle
			(center 0 0)
			(end 2.4003 0)
			(stroke
				(width 0.1)
				(type default)
			)
			(fill no)
			(layer "F.Fab")
		)
		(pad "" np_thru_hole circle
			(at 0 0)
			(size 3.175 3.175)
			(drill 3.175)
			(layers "*.Cu" "*.Mask")
			(clearance 0.381)
			(thermal_gap 0.381)
		)
		(zone
			(layers "F.Cu" "B.Cu" "In1.Cu" "In2.Cu" "In3.Cu" "In4.Cu" "In5.Cu" "In6.Cu"
				"In7.Cu" "In8.Cu"
			)
			(hatch none 0.5)
			(connect_pads
				(clearance 0)
			)
			(min_thickness 0.25)
			(keepout
				(tracks not_allowed)
				(vias allowed)
				(pads allowed)
				(copperpour not_allowed)
				(footprints allowed)
			)
			(placement
				(enabled no)
				(sheetname "")
			)
			(fill
				(thermal_gap 0.5)
				(thermal_bridge_width 0.5)
				(island_removal_mode 0)
			)
			(polygon
				(pts
					(arc
						(start 310.064912 -76.245974)
						(mid 305.873912 -76.245974)
						(end 310.064912 -76.245974)
					)
				)
			)
		)
	)
	(footprint ""
		(layer "F.Cu")
		(at 449.39712 -81.95818)
		(property "Reference" "PR111"
			(at 0 0 0)
			(layer "F.SilkS")
			(hide yes)
			(effects
				(font
					(size 1.27 1.27)
				)
			)
		)
		(property "Value" ""
			(at 0 0 0)
			(layer "F.Fab")
			(effects
				(font
					(size 1.27 1.27)
				)
			)
		)
		(duplicate_pad_numbers_are_jumpers no)
		(fp_line
			(start -0.7874 -0.4064)
			(end 0.7874 -0.4064)
			(stroke
				(width 0.1524)
				(type default)
			)
			(layer "F.SilkS")
		)
		(fp_line
			(start -0.7874 0.4064)
			(end -0.7874 -0.4064)
			(stroke
				(width 0.1524)
				(type default)
			)
			(layer "F.SilkS")
		)
		(fp_line
			(start 0.7874 -0.4064)
			(end 0.7874 0.4064)
			(stroke
				(width 0.1524)
				(type default)
			)
			(layer "F.SilkS")
		)
		(fp_line
			(start 0.7874 0.4064)
			(end -0.7874 0.4064)
			(stroke
				(width 0.1524)
				(type default)
			)
			(layer "F.SilkS")
		)
		(fp_line
			(start -0.67945 -0.305054)
			(end -0.12065 -0.305054)
			(stroke
				(width 0.1)
				(type default)
			)
			(layer "F.Fab")
		)
		(fp_line
			(start -0.67945 0.3048)
			(end -0.67945 -0.305054)
			(stroke
				(width 0.1)
				(type default)
			)
			(layer "F.Fab")
		)
		(fp_line
			(start -0.12065 -0.305054)
			(end -0.12065 -0.2794)
			(stroke
				(width 0.1)
				(type default)
			)
			(layer "F.Fab")
		)
		(fp_line
			(start -0.12065 -0.2794)
			(end 0.12065 -0.2794)
			(stroke
				(width 0.1)
				(type default)
			)
			(layer "F.Fab")
		)
		(fp_line
			(start -0.12065 0.2794)
			(end -0.12065 0.3048)
			(stroke
				(width 0.1)
				(type default)
			)
			(layer "F.Fab")
		)
		(fp_line
			(start -0.12065 0.3048)
			(end -0.67945 0.3048)
			(stroke
				(width 0.1)
				(type default)
			)
			(layer "F.Fab")
		)
		(fp_line
			(start 0.120396 0.2794)
			(end -0.12065 0.2794)
			(stroke
				(width 0.1)
				(type default)
			)
			(layer "F.Fab")
		)
		(fp_line
			(start 0.120396 0.3048)
			(end 0.120396 0.2794)
			(stroke
				(width 0.1)
				(type default)
			)
			(layer "F.Fab")
		)
		(fp_line
			(start 0.12065 -0.3048)
			(end 0.67945 -0.3048)
			(stroke
				(width 0.1)
				(type default)
			)
			(layer "F.Fab")
		)
		(fp_line
			(start 0.12065 -0.2794)
			(end 0.12065 -0.3048)
			(stroke
				(width 0.1)
				(type default)
			)
			(layer "F.Fab")
		)
		(fp_line
			(start 0.67945 -0.3048)
			(end 0.67945 0.3048)
			(stroke
				(width 0.1)
				(type default)
			)
			(layer "F.Fab")
		)
		(fp_line
			(start 0.67945 0.3048)
			(end 0.120396 0.3048)
			(stroke
				(width 0.1)
				(type default)
			)
			(layer "F.Fab")
		)
		(pad "1" smd circle
			(at -0.40005 0)
			(size 0 0)
			(layers "F.Cu" "F.Mask" "F.Paste")
			(net "SW_P3V3_HPDB_BT")
		)
		(pad "2" smd circle
			(at 0.40005 0)
			(size 0 0)
			(layers "F.Cu" "F.Mask" "F.Paste")
			(net "SW_P3V3_HPDB_BT_R")
		)
	)
	(footprint ""
		(layer "F.Cu")
		(at 449.199 -48.514)
		(property "Reference" "U37"
			(at 1.8415 1.30937 0)
			(unlocked yes)
			(layer "F.SilkS")
			(effects
				(font
					(size 0.7874 0.5842)
					(thickness 0.1524)
				)
				(justify left)
			)
		)
		(property "Value" ""
			(at 0 0 0)
			(layer "F.Fab")
			(effects
				(font
					(size 1.27 1.27)
				)
			)
		)
		(duplicate_pad_numbers_are_jumpers no)
		(fp_line
			(start -1.603248 -1.500124)
			(end 1.603248 -1.500124)
			(stroke
				(width 0.1524)
				(type default)
			)
			(layer "F.SilkS")
		)
		(fp_line
			(start -1.603248 1.500124)
			(end -1.603248 -1.500124)
			(stroke
				(width 0.1524)
				(type default)
			)
			(layer "F.SilkS")
		)
		(fp_line
			(start 1.603248 -1.500124)
			(end 1.603248 1.500124)
			(stroke
				(width 0.1524)
				(type default)
			)
			(layer "F.SilkS")
		)
		(fp_line
			(start 1.603248 1.500124)
			(end -1.603248 1.500124)
			(stroke
				(width 0.1524)
				(type default)
			)
			(layer "F.SilkS")
		)
		(fp_line
			(start -1.249934 -1.169924)
			(end -1.249934 -0.729996)
			(stroke
				(width 0.1)
				(type default)
			)
			(layer "F.Fab")
		)
		(fp_line
			(start -1.249934 -0.729996)
			(end -0.6985 -0.729996)
			(stroke
				(width 0.1)
				(type default)
			)
			(layer "F.Fab")
		)
		(fp_line
			(start -1.249934 0.729996)
			(end -1.249934 1.169924)
			(stroke
				(width 0.1)
				(type default)
			)
			(layer "F.Fab")
		)
		(fp_line
			(start -1.249934 1.169924)
			(end -0.700024 1.169924)
			(stroke
				(width 0.1)
				(type default)
			)
			(layer "F.Fab")
		)
		(fp_line
			(start -0.700024 -1.500124)
			(end -0.700024 -1.169924)
			(stroke
				(width 0.1)
				(type default)
			)
			(layer "F.Fab")
		)
		(fp_line
			(start -0.700024 -1.169924)
			(end -1.249934 -1.169924)
			(stroke
				(width 0.1)
				(type default)
			)
			(layer "F.Fab")
		)
		(fp_line
			(start -0.700024 1.169924)
			(end -0.700024 1.500124)
			(stroke
				(width 0.1)
				(type default)
			)
			(layer "F.Fab")
		)
		(fp_line
			(start -0.700024 1.500124)
			(end 0.700024 1.500124)
			(stroke
				(width 0.1)
				(type default)
			)
			(layer "F.Fab")
		)
		(fp_line
			(start -0.6985 -0.729996)
			(end -0.6985 0.729996)
			(stroke
				(width 0.1)
				(type default)
			)
			(layer "F.Fab")
		)
		(fp_line
			(start -0.6985 0.729996)
			(end -1.249934 0.729996)
			(stroke
				(width 0.1)
				(type default)
			)
			(layer "F.Fab")
		)
		(fp_line
			(start 0.700024 -1.500124)
			(end -0.700024 -1.500124)
			(stroke
				(width 0.1)
				(type default)
			)
			(layer "F.Fab")
		)
		(fp_line
			(start 0.700024 -0.219964)
			(end 0.700024 -1.500124)
			(stroke
				(width 0.1)
				(type default)
			)
			(layer "F.Fab")
		)
		(fp_line
			(start 0.700024 0.219964)
			(end 1.249934 0.219964)
			(stroke
				(width 0.1)
				(type default)
			)
			(layer "F.Fab")
		)
		(fp_line
			(start 0.700024 1.500124)
			(end 0.700024 0.219964)
			(stroke
				(width 0.1)
				(type default)
			)
			(layer "F.Fab")
		)
		(fp_line
			(start 1.249934 -0.219964)
			(end 0.700024 -0.219964)
			(stroke
				(width 0.1)
				(type default)
			)
			(layer "F.Fab")
		)
		(fp_line
			(start 1.249934 0.219964)
			(end 1.249934 -0.219964)
			(stroke
				(width 0.1)
				(type default)
			)
			(layer "F.Fab")
		)
		(fp_rect
			(start -0.700024 1.500124)
			(end 0.700024 -1.500124)
			(stroke
				(width 0)
				(type default)
			)
			(fill no)
			(layer "F.Fab")
		)
		(pad "D" smd rect
			(at 0.999998 0 270)
			(size 0.8128 0.9144)
			(layers "F.Cu" "F.Mask" "F.Paste")
			(net "PWRGD_P3V3_HPDB_R")
		)
		(pad "G" smd rect
			(at -0.999998 -0.94996 270)
			(size 0.8128 0.9144)
			(layers "F.Cu" "F.Mask" "F.Paste")
			(net "PWRGD_P3V3_HPDB_R_N")
		)
		(pad "S" smd rect
			(at -0.999998 0.94996 270)
			(size 0.8128 0.9144)
			(layers "F.Cu" "F.Mask" "F.Paste")
			(net "GND")
		)
	)
	(footprint ""
		(layer "F.Cu")
		(at 230.3526 -91.9988 180)
		(property "Reference" "JP5"
			(at 1.1176 -3.37947 0)
			(unlocked yes)
			(layer "F.SilkS")
			(effects
				(font
					(size 0.7874 0.5842)
					(thickness 0.1524)
				)
				(justify left)
			)
		)
		(property "Value" ""
			(at 0 0 180)
			(layer "F.Fab")
			(effects
				(font
					(size 1.27 1.27)
				)
			)
		)
		(duplicate_pad_numbers_are_jumpers no)
		(fp_line
			(start 1.234948 6.415024)
			(end -1.234948 6.415024)
			(stroke
				(width 0.1524)
				(type default)
			)
			(layer "F.SilkS")
		)
		(fp_line
			(start 1.234948 -1.335024)
			(end 1.234948 6.415024)
			(stroke
				(width 0.1524)
				(type default)
			)
			(layer "F.SilkS")
		)
		(fp_line
			(start -1.234948 6.415024)
			(end -1.234948 -1.335024)
			(stroke
				(width 0.1524)
				(type default)
			)
			(layer "F.SilkS")
		)
		(fp_line
			(start -1.234948 -1.335024)
			(end 1.234948 -1.335024)
			(stroke
				(width 0.1524)
				(type default)
			)
			(layer "F.SilkS")
		)
		(fp_poly
			(pts
				(xy 0.508 -2.530348) (xy -0.508 -2.530348) (xy 0 -1.514348)
			)
			(stroke
				(width 0)
				(type default)
			)
			(fill yes)
			(layer "F.SilkS")
		)
		(fp_line
			(start 1.234948 6.415024)
			(end -1.234948 6.415024)
			(stroke
				(width 0.1)
				(type default)
			)
			(layer "F.Fab")
		)
		(fp_line
			(start 1.234948 -1.335024)
			(end 1.234948 6.415024)
			(stroke
				(width 0.1)
				(type default)
			)
			(layer "F.Fab")
		)
		(fp_line
			(start -1.234948 6.415024)
			(end -1.234948 -1.335024)
			(stroke
				(width 0.1)
				(type default)
			)
			(layer "F.Fab")
		)
		(fp_line
			(start -1.234948 -1.335024)
			(end 1.234948 -1.335024)
			(stroke
				(width 0.1)
				(type default)
			)
			(layer "F.Fab")
		)
		(fp_poly
			(pts
				(xy 0.508 -2.530348) (xy -0.508 -2.530348) (xy 0 -1.514348)
			)
			(stroke
				(width 0)
				(type default)
			)
			(fill yes)
			(layer "F.Fab")
		)
		(fp_text user "3"
			(at -0.009652 6.5659 90)
			(unlocked yes)
			(layer "F.SilkS")
			(effects
				(font
					(size 0.7874 0.5842)
					(thickness 0.1524)
				)
				(justify left)
			)
		)
		(fp_text user "3"
			(at -0.00127 6.640576 90)
			(unlocked yes)
			(layer "B.SilkS")
			(effects
				(font
					(size 0.7874 0.5842)
					(thickness 0.1524)
				)
				(justify left mirror)
			)
		)
		(fp_text user "1"
			(at -0.00127 -0.954024 90)
			(unlocked yes)
			(layer "B.SilkS")
			(effects
				(font
					(size 0.7874 0.5842)
					(thickness 0.1524)
				)
				(justify left mirror)
			)
		)
		(fp_text user "3"
			(at -0.00127 6.640576 90)
			(unlocked yes)
			(layer "B.Fab")
			(effects
				(font
					(size 0.7874 0.5842)
					(thickness 0.1524)
				)
				(justify left mirror)
			)
		)
		(fp_text user "1"
			(at -0.00127 -0.954024 90)
			(unlocked yes)
			(layer "B.Fab")
			(effects
				(font
					(size 0.7874 0.5842)
					(thickness 0.1524)
				)
				(justify left mirror)
			)
		)
		(fp_text user "3"
			(at -0.009652 6.5659 90)
			(unlocked yes)
			(layer "F.Fab")
			(effects
				(font
					(size 0.7874 0.5842)
					(thickness 0.1524)
				)
				(justify left)
			)
		)
		(pad "1" thru_hole rect
			(at 0 0 90)
			(size 1.6764 1.6764)
			(drill 1.1684)
			(layers "*.Cu" "*.Mask")
			(remove_unused_layers no)
			(net "TP_P52V_HS1_EN")
			(clearance 0)
			(padstack
				(mode front_inner_back)
				(layer "Inner"
					(shape circle)
					(size 1.6764 1.6764)
					(clearance 0)
				)
				(layer "B.Cu"
					(shape rect)
					(size 1.6764 1.6764)
					(clearance 0)
				)
			)
		)
		(pad "2" thru_hole circle
			(at 0 2.54 90)
			(size 1.6764 1.6764)
			(drill 1.1684)
			(layers "*.Cu" "*.Mask")
			(remove_unused_layers no)
			(net "GPU_HSC1_BUF_EN_N")
			(clearance 0)
		)
		(pad "3" thru_hole circle
			(at 0 5.08 90)
			(size 1.6764 1.6764)
			(drill 1.1684)
			(layers "*.Cu" "*.Mask")
			(remove_unused_layers no)
			(net "GND")
			(clearance 0)
		)
	)
	(footprint ""
		(layer "F.Cu")
		(at 434.848 -41.148 -90)
		(property "Reference" "R4"
			(at 0 0 270)
			(layer "F.SilkS")
			(hide yes)
			(effects
				(font
					(size 1.27 1.27)
				)
			)
		)
		(property "Value" ""
			(at 0 0 270)
			(layer "F.Fab")
			(effects
				(font
					(size 1.27 1.27)
				)
			)
		)
		(duplicate_pad_numbers_are_jumpers no)
		(fp_line
			(start -0.7874 0.4064)
			(end -0.7874 -0.4064)
			(stroke
				(width 0.1524)
				(type default)
			)
			(layer "F.SilkS")
		)
		(fp_line
			(start 0.7874 0.4064)
			(end -0.7874 0.4064)
			(stroke
				(width 0.1524)
				(type default)
			)
			(layer "F.SilkS")
		)
		(fp_line
			(start -0.7874 -0.4064)
			(end 0.7874 -0.4064)
			(stroke
				(width 0.1524)
				(type default)
			)
			(layer "F.SilkS")
		)
		(fp_line
			(start 0.7874 -0.4064)
			(end 0.7874 0.4064)
			(stroke
				(width 0.1524)
				(type default)
			)
			(layer "F.SilkS")
		)
		(fp_line
			(start -0.67945 0.3048)
			(end -0.67945 -0.305054)
			(stroke
				(width 0.1)
				(type default)
			)
			(layer "F.Fab")
		)
		(fp_line
			(start -0.12065 0.3048)
			(end -0.67945 0.3048)
			(stroke
				(width 0.1)
				(type default)
			)
			(layer "F.Fab")
		)
		(fp_line
			(start 0.120396 0.3048)
			(end 0.120396 0.2794)
			(stroke
				(width 0.1)
				(type default)
			)
			(layer "F.Fab")
		)
		(fp_line
			(start 0.67945 0.3048)
			(end 0.120396 0.3048)
			(stroke
				(width 0.1)
				(type default)
			)
			(layer "F.Fab")
		)
		(fp_line
			(start -0.12065 0.2794)
			(end -0.12065 0.3048)
			(stroke
				(width 0.1)
				(type default)
			)
			(layer "F.Fab")
		)
		(fp_line
			(start 0.120396 0.2794)
			(end -0.12065 0.2794)
			(stroke
				(width 0.1)
				(type default)
			)
			(layer "F.Fab")
		)
		(fp_line
			(start -0.12065 -0.2794)
			(end 0.12065 -0.2794)
			(stroke
				(width 0.1)
				(type default)
			)
			(layer "F.Fab")
		)
		(fp_line
			(start 0.12065 -0.2794)
			(end 0.12065 -0.3048)
			(stroke
				(width 0.1)
				(type default)
			)
			(layer "F.Fab")
		)
		(fp_line
			(start 0.12065 -0.3048)
			(end 0.67945 -0.3048)
			(stroke
				(width 0.1)
				(type default)
			)
			(layer "F.Fab")
		)
		(fp_line
			(start 0.67945 -0.3048)
			(end 0.67945 0.3048)
			(stroke
				(width 0.1)
				(type default)
			)
			(layer "F.Fab")
		)
		(fp_line
			(start -0.67945 -0.305054)
			(end -0.12065 -0.305054)
			(stroke
				(width 0.1)
				(type default)
			)
			(layer "F.Fab")
		)
		(fp_line
			(start -0.12065 -0.305054)
			(end -0.12065 -0.2794)
			(stroke
				(width 0.1)
				(type default)
			)
			(layer "F.Fab")
		)
		(pad "1" smd circle
			(at -0.40005 0 270)
			(size 0 0)
			(layers "F.Cu" "F.Mask" "F.Paste")
			(net "SMB_PDB_MISC_SCL_R")
		)
		(pad "2" smd circle
			(at 0.40005 0 270)
			(size 0 0)
			(layers "F.Cu" "F.Mask" "F.Paste")
			(net "SMB_PDB_MISC_SCL_R1")
		)
	)
	(footprint ""
		(layer "F.Cu")
		(at 302.4124 -34.3662 180)
		(property "Reference" "PR6961"
			(at 0 0 180)
			(layer "F.SilkS")
			(hide yes)
			(effects
				(font
					(size 1.27 1.27)
				)
			)
		)
		(property "Value" ""
			(at 0 0 180)
			(layer "F.Fab")
			(effects
				(font
					(size 1.27 1.27)
				)
			)
		)
		(duplicate_pad_numbers_are_jumpers no)
		(fp_line
			(start 1.2954 0.5842)
			(end -1.2954 0.5842)
			(stroke
				(width 0.1524)
				(type default)
			)
			(layer "F.SilkS")
		)
		(fp_line
			(start 1.2954 -0.5842)
			(end 1.2954 0.5842)
			(stroke
				(width 0.1524)
				(type default)
			)
			(layer "F.SilkS")
		)
		(fp_line
			(start -1.2954 0.5842)
			(end -1.2954 -0.5842)
			(stroke
				(width 0.1524)
				(type default)
			)
			(layer "F.SilkS")
		)
		(fp_line
			(start -1.2954 -0.5842)
			(end 1.2954 -0.5842)
			(stroke
				(width 0.1524)
				(type default)
			)
			(layer "F.SilkS")
		)
		(fp_line
			(start 1.1938 0.4064)
			(end 0.8636 0.4064)
			(stroke
				(width 0.1)
				(type default)
			)
			(layer "F.Fab")
		)
		(fp_line
			(start 1.1938 -0.406654)
			(end 1.1938 0.4064)
			(stroke
				(width 0.1)
				(type default)
			)
			(layer "F.Fab")
		)
		(fp_line
			(start 0.8636 0.4572)
			(end -0.8636 0.4572)
			(stroke
				(width 0.1)
				(type default)
			)
			(layer "F.Fab")
		)
		(fp_line
			(start 0.8636 0.4064)
			(end 0.8636 0.4572)
			(stroke
				(width 0.1)
				(type default)
			)
			(layer "F.Fab")
		)
		(fp_line
			(start 0.8636 -0.406654)
			(end 1.1938 -0.406654)
			(stroke
				(width 0.1)
				(type default)
			)
			(layer "F.Fab")
		)
		(fp_line
			(start 0.8636 -0.4572)
			(end 0.8636 -0.406654)
			(stroke
				(width 0.1)
				(type default)
			)
			(layer "F.Fab")
		)
		(fp_line
			(start -0.8636 0.4572)
			(end -0.8636 0.4318)
			(stroke
				(width 0.1)
				(type default)
			)
			(layer "F.Fab")
		)
		(fp_line
			(start -0.8636 0.4318)
			(end -0.8636 0.4064)
			(stroke
				(width 0.1)
				(type default)
			)
			(layer "F.Fab")
		)
		(fp_line
			(start -0.8636 0.4064)
			(end -1.1938 0.4064)
			(stroke
				(width 0.1)
				(type default)
			)
			(layer "F.Fab")
		)
		(fp_line
			(start -0.8636 -0.406654)
			(end -0.8636 -0.4572)
			(stroke
				(width 0.1)
				(type default)
			)
			(layer "F.Fab")
		)
		(fp_line
			(start -0.8636 -0.4572)
			(end 0.8636 -0.4572)
			(stroke
				(width 0.1)
				(type default)
			)
			(layer "F.Fab")
		)
		(fp_line
			(start -1.1938 0.4064)
			(end -1.1938 -0.406654)
			(stroke
				(width 0.1)
				(type default)
			)
			(layer "F.Fab")
		)
		(fp_line
			(start -1.1938 -0.406654)
			(end -0.8636 -0.406654)
			(stroke
				(width 0.1)
				(type default)
			)
			(layer "F.Fab")
		)
		(pad "1" smd rect
			(at -0.7366 0 90)
			(size 0.7112 0.8128)
			(layers "F.Cu" "F.Mask" "F.Paste")
			(net "P52V_HS_1272_S_P")
		)
		(pad "2" smd rect
			(at 0.7366 0 90)
			(size 0.7112 0.8128)
			(layers "F.Cu" "F.Mask" "F.Paste")
			(net "P52V_HS1_SENSE_P_R2")
		)
	)
	(footprint ""
		(layer "F.Cu")
		(at 302.4124 -37.9222 180)
		(property "Reference" "PR6955"
			(at 0 0 180)
			(layer "F.SilkS")
			(hide yes)
			(effects
				(font
					(size 1.27 1.27)
				)
			)
		)
		(property "Value" ""
			(at 0 0 180)
			(layer "F.Fab")
			(effects
				(font
					(size 1.27 1.27)
				)
			)
		)
		(duplicate_pad_numbers_are_jumpers no)
		(fp_line
			(start 1.2954 0.5842)
			(end -1.2954 0.5842)
			(stroke
				(width 0.1524)
				(type default)
			)
			(layer "F.SilkS")
		)
		(fp_line
			(start 1.2954 -0.5842)
			(end 1.2954 0.5842)
			(stroke
				(width 0.1524)
				(type default)
			)
			(layer "F.SilkS")
		)
		(fp_line
			(start -1.2954 0.5842)
			(end -1.2954 -0.5842)
			(stroke
				(width 0.1524)
				(type default)
			)
			(layer "F.SilkS")
		)
		(fp_line
			(start -1.2954 -0.5842)
			(end 1.2954 -0.5842)
			(stroke
				(width 0.1524)
				(type default)
			)
			(layer "F.SilkS")
		)
		(fp_line
			(start 1.1938 0.4064)
			(end 0.8636 0.4064)
			(stroke
				(width 0.1)
				(type default)
			)
			(layer "F.Fab")
		)
		(fp_line
			(start 1.1938 -0.406654)
			(end 1.1938 0.4064)
			(stroke
				(width 0.1)
				(type default)
			)
			(layer "F.Fab")
		)
		(fp_line
			(start 0.8636 0.4572)
			(end -0.8636 0.4572)
			(stroke
				(width 0.1)
				(type default)
			)
			(layer "F.Fab")
		)
		(fp_line
			(start 0.8636 0.4064)
			(end 0.8636 0.4572)
			(stroke
				(width 0.1)
				(type default)
			)
			(layer "F.Fab")
		)
		(fp_line
			(start 0.8636 -0.406654)
			(end 1.1938 -0.406654)
			(stroke
				(width 0.1)
				(type default)
			)
			(layer "F.Fab")
		)
		(fp_line
			(start 0.8636 -0.4572)
			(end 0.8636 -0.406654)
			(stroke
				(width 0.1)
				(type default)
			)
			(layer "F.Fab")
		)
		(fp_line
			(start -0.8636 0.4572)
			(end -0.8636 0.4318)
			(stroke
				(width 0.1)
				(type default)
			)
			(layer "F.Fab")
		)
		(fp_line
			(start -0.8636 0.4318)
			(end -0.8636 0.4064)
			(stroke
				(width 0.1)
				(type default)
			)
			(layer "F.Fab")
		)
		(fp_line
			(start -0.8636 0.4064)
			(end -1.1938 0.4064)
			(stroke
				(width 0.1)
				(type default)
			)
			(layer "F.Fab")
		)
		(fp_line
			(start -0.8636 -0.406654)
			(end -0.8636 -0.4572)
			(stroke
				(width 0.1)
				(type default)
			)
			(layer "F.Fab")
		)
		(fp_line
			(start -0.8636 -0.4572)
			(end 0.8636 -0.4572)
			(stroke
				(width 0.1)
				(type default)
			)
			(layer "F.Fab")
		)
		(fp_line
			(start -1.1938 0.4064)
			(end -1.1938 -0.406654)
			(stroke
				(width 0.1)
				(type default)
			)
			(layer "F.Fab")
		)
		(fp_line
			(start -1.1938 -0.406654)
			(end -0.8636 -0.406654)
			(stroke
				(width 0.1)
				(type default)
			)
			(layer "F.Fab")
		)
		(pad "1" smd rect
			(at -0.7366 0 90)
			(size 0.7112 0.8128)
			(layers "F.Cu" "F.Mask" "F.Paste")
			(net "P52V_HS_4287_S2P")
		)
		(pad "2" smd rect
			(at 0.7366 0 90)
			(size 0.7112 0.8128)
			(layers "F.Cu" "F.Mask" "F.Paste")
			(net "P52V_HS1_SENSE_P_R2")
		)
	)
	(footprint ""
		(layer "F.Cu")
		(at 413.75584 -27.852878 90)
		(property "Reference" "R5925"
			(at 0 0 90)
			(layer "F.SilkS")
			(hide yes)
			(effects
				(font
					(size 1.27 1.27)
				)
			)
		)
		(property "Value" ""
			(at 0 0 90)
			(layer "F.Fab")
			(effects
				(font
					(size 1.27 1.27)
				)
			)
		)
		(duplicate_pad_numbers_are_jumpers no)
		(fp_line
			(start 0.7874 -0.4064)
			(end 0.7874 0.4064)
			(stroke
				(width 0.1524)
				(type default)
			)
			(layer "F.SilkS")
		)
		(fp_line
			(start -0.7874 -0.4064)
			(end 0.7874 -0.4064)
			(stroke
				(width 0.1524)
				(type default)
			)
			(layer "F.SilkS")
		)
		(fp_line
			(start 0.7874 0.4064)
			(end -0.7874 0.4064)
			(stroke
				(width 0.1524)
				(type default)
			)
			(layer "F.SilkS")
		)
		(fp_line
			(start -0.7874 0.4064)
			(end -0.7874 -0.4064)
			(stroke
				(width 0.1524)
				(type default)
			)
			(layer "F.SilkS")
		)
		(fp_line
			(start -0.12065 -0.305054)
			(end -0.12065 -0.2794)
			(stroke
				(width 0.1)
				(type default)
			)
			(layer "F.Fab")
		)
		(fp_line
			(start -0.67945 -0.305054)
			(end -0.12065 -0.305054)
			(stroke
				(width 0.1)
				(type default)
			)
			(layer "F.Fab")
		)
		(fp_line
			(start 0.67945 -0.3048)
			(end 0.67945 0.3048)
			(stroke
				(width 0.1)
				(type default)
			)
			(layer "F.Fab")
		)
		(fp_line
			(start 0.12065 -0.3048)
			(end 0.67945 -0.3048)
			(stroke
				(width 0.1)
				(type default)
			)
			(layer "F.Fab")
		)
		(fp_line
			(start 0.12065 -0.2794)
			(end 0.12065 -0.3048)
			(stroke
				(width 0.1)
				(type default)
			)
			(layer "F.Fab")
		)
		(fp_line
			(start -0.12065 -0.2794)
			(end 0.12065 -0.2794)
			(stroke
				(width 0.1)
				(type default)
			)
			(layer "F.Fab")
		)
		(fp_line
			(start 0.120396 0.2794)
			(end -0.12065 0.2794)
			(stroke
				(width 0.1)
				(type default)
			)
			(layer "F.Fab")
		)
		(fp_line
			(start -0.12065 0.2794)
			(end -0.12065 0.3048)
			(stroke
				(width 0.1)
				(type default)
			)
			(layer "F.Fab")
		)
		(fp_line
			(start 0.67945 0.3048)
			(end 0.120396 0.3048)
			(stroke
				(width 0.1)
				(type default)
			)
			(layer "F.Fab")
		)
		(fp_line
			(start 0.120396 0.3048)
			(end 0.120396 0.2794)
			(stroke
				(width 0.1)
				(type default)
			)
			(layer "F.Fab")
		)
		(fp_line
			(start -0.12065 0.3048)
			(end -0.67945 0.3048)
			(stroke
				(width 0.1)
				(type default)
			)
			(layer "F.Fab")
		)
		(fp_line
			(start -0.67945 0.3048)
			(end -0.67945 -0.305054)
			(stroke
				(width 0.1)
				(type default)
			)
			(layer "F.Fab")
		)
		(pad "1" smd circle
			(at -0.40005 0 90)
			(size 0 0)
			(layers "F.Cu" "F.Mask" "F.Paste")
			(net "GND")
		)
		(pad "2" smd circle
			(at 0.40005 0 90)
			(size 0 0)
			(layers "F.Cu" "F.Mask" "F.Paste")
			(net "P12V_LED_FB")
		)
	)
	(footprint ""
		(layer "F.Cu")
		(at 445.643 -48.514)
		(property "Reference" "U36"
			(at -2.24663 0.3175 90)
			(unlocked yes)
			(layer "F.SilkS")
			(effects
				(font
					(size 0.7874 0.5842)
					(thickness 0.1524)
				)
				(justify left)
			)
		)
		(property "Value" ""
			(at 0 0 0)
			(layer "F.Fab")
			(effects
				(font
					(size 1.27 1.27)
				)
			)
		)
		(duplicate_pad_numbers_are_jumpers no)
		(fp_line
			(start -1.603248 -1.500124)
			(end 1.603248 -1.500124)
			(stroke
				(width 0.1524)
				(type default)
			)
			(layer "F.SilkS")
		)
		(fp_line
			(start -1.603248 1.500124)
			(end -1.603248 -1.500124)
			(stroke
				(width 0.1524)
				(type default)
			)
			(layer "F.SilkS")
		)
		(fp_line
			(start 1.603248 -1.500124)
			(end 1.603248 1.500124)
			(stroke
				(width 0.1524)
				(type default)
			)
			(layer "F.SilkS")
		)
		(fp_line
			(start 1.603248 1.500124)
			(end -1.603248 1.500124)
			(stroke
				(width 0.1524)
				(type default)
			)
			(layer "F.SilkS")
		)
		(fp_line
			(start -1.249934 -1.169924)
			(end -1.249934 -0.729996)
			(stroke
				(width 0.1)
				(type default)
			)
			(layer "F.Fab")
		)
		(fp_line
			(start -1.249934 -0.729996)
			(end -0.6985 -0.729996)
			(stroke
				(width 0.1)
				(type default)
			)
			(layer "F.Fab")
		)
		(fp_line
			(start -1.249934 0.729996)
			(end -1.249934 1.169924)
			(stroke
				(width 0.1)
				(type default)
			)
			(layer "F.Fab")
		)
		(fp_line
			(start -1.249934 1.169924)
			(end -0.700024 1.169924)
			(stroke
				(width 0.1)
				(type default)
			)
			(layer "F.Fab")
		)
		(fp_line
			(start -0.700024 -1.500124)
			(end -0.700024 -1.169924)
			(stroke
				(width 0.1)
				(type default)
			)
			(layer "F.Fab")
		)
		(fp_line
			(start -0.700024 -1.169924)
			(end -1.249934 -1.169924)
			(stroke
				(width 0.1)
				(type default)
			)
			(layer "F.Fab")
		)
		(fp_line
			(start -0.700024 1.169924)
			(end -0.700024 1.500124)
			(stroke
				(width 0.1)
				(type default)
			)
			(layer "F.Fab")
		)
		(fp_line
			(start -0.700024 1.500124)
			(end 0.700024 1.500124)
			(stroke
				(width 0.1)
				(type default)
			)
			(layer "F.Fab")
		)
		(fp_line
			(start -0.6985 -0.729996)
			(end -0.6985 0.729996)
			(stroke
				(width 0.1)
				(type default)
			)
			(layer "F.Fab")
		)
		(fp_line
			(start -0.6985 0.729996)
			(end -1.249934 0.729996)
			(stroke
				(width 0.1)
				(type default)
			)
			(layer "F.Fab")
		)
		(fp_line
			(start 0.700024 -1.500124)
			(end -0.700024 -1.500124)
			(stroke
				(width 0.1)
				(type default)
			)
			(layer "F.Fab")
		)
		(fp_line
			(start 0.700024 -0.219964)
			(end 0.700024 -1.500124)
			(stroke
				(width 0.1)
				(type default)
			)
			(layer "F.Fab")
		)
		(fp_line
			(start 0.700024 0.219964)
			(end 1.249934 0.219964)
			(stroke
				(width 0.1)
				(type default)
			)
			(layer "F.Fab")
		)
		(fp_line
			(start 0.700024 1.500124)
			(end 0.700024 0.219964)
			(stroke
				(width 0.1)
				(type default)
			)
			(layer "F.Fab")
		)
		(fp_line
			(start 1.249934 -0.219964)
			(end 0.700024 -0.219964)
			(stroke
				(width 0.1)
				(type default)
			)
			(layer "F.Fab")
		)
		(fp_line
			(start 1.249934 0.219964)
			(end 1.249934 -0.219964)
			(stroke
				(width 0.1)
				(type default)
			)
			(layer "F.Fab")
		)
		(fp_rect
			(start -0.700024 1.500124)
			(end 0.700024 -1.500124)
			(stroke
				(width 0)
				(type default)
			)
			(fill no)
			(layer "F.Fab")
		)
		(pad "D" smd rect
			(at 0.999998 0 270)
			(size 0.8128 0.9144)
			(layers "F.Cu" "F.Mask" "F.Paste")
			(net "PWRGD_P3V3_HPDB_R_N")
		)
		(pad "G" smd rect
			(at -0.999998 -0.94996 270)
			(size 0.8128 0.9144)
			(layers "F.Cu" "F.Mask" "F.Paste")
			(net "P3V3_HPDB_PG")
		)
		(pad "S" smd rect
			(at -0.999998 0.94996 270)
			(size 0.8128 0.9144)
			(layers "F.Cu" "F.Mask" "F.Paste")
			(net "GND")
		)
	)
	(footprint ""
		(layer "F.Cu")
		(at 435.5338 -22.352 180)
		(property "Reference" "R59"
			(at 0 0 180)
			(layer "F.SilkS")
			(hide yes)
			(effects
				(font
					(size 1.27 1.27)
				)
			)
		)
		(property "Value" ""
			(at 0 0 180)
			(layer "F.Fab")
			(effects
				(font
					(size 1.27 1.27)
				)
			)
		)
		(duplicate_pad_numbers_are_jumpers no)
		(fp_line
			(start 0.7874 0.4064)
			(end -0.7874 0.4064)
			(stroke
				(width 0.1524)
				(type default)
			)
			(layer "F.SilkS")
		)
		(fp_line
			(start 0.7874 -0.4064)
			(end 0.7874 0.4064)
			(stroke
				(width 0.1524)
				(type default)
			)
			(layer "F.SilkS")
		)
		(fp_line
			(start -0.7874 0.4064)
			(end -0.7874 -0.4064)
			(stroke
				(width 0.1524)
				(type default)
			)
			(layer "F.SilkS")
		)
		(fp_line
			(start -0.7874 -0.4064)
			(end 0.7874 -0.4064)
			(stroke
				(width 0.1524)
				(type default)
			)
			(layer "F.SilkS")
		)
		(fp_line
			(start 0.67945 0.3048)
			(end 0.120396 0.3048)
			(stroke
				(width 0.1)
				(type default)
			)
			(layer "F.Fab")
		)
		(fp_line
			(start 0.67945 -0.3048)
			(end 0.67945 0.3048)
			(stroke
				(width 0.1)
				(type default)
			)
			(layer "F.Fab")
		)
		(fp_line
			(start 0.12065 -0.2794)
			(end 0.12065 -0.3048)
			(stroke
				(width 0.1)
				(type default)
			)
			(layer "F.Fab")
		)
		(fp_line
			(start 0.12065 -0.3048)
			(end 0.67945 -0.3048)
			(stroke
				(width 0.1)
				(type default)
			)
			(layer "F.Fab")
		)
		(fp_line
			(start 0.120396 0.3048)
			(end 0.120396 0.2794)
			(stroke
				(width 0.1)
				(type default)
			)
			(layer "F.Fab")
		)
		(fp_line
			(start 0.120396 0.2794)
			(end -0.12065 0.2794)
			(stroke
				(width 0.1)
				(type default)
			)
			(layer "F.Fab")
		)
		(fp_line
			(start -0.12065 0.3048)
			(end -0.67945 0.3048)
			(stroke
				(width 0.1)
				(type default)
			)
			(layer "F.Fab")
		)
		(fp_line
			(start -0.12065 0.2794)
			(end -0.12065 0.3048)
			(stroke
				(width 0.1)
				(type default)
			)
			(layer "F.Fab")
		)
		(fp_line
			(start -0.12065 -0.2794)
			(end 0.12065 -0.2794)
			(stroke
				(width 0.1)
				(type default)
			)
			(layer "F.Fab")
		)
		(fp_line
			(start -0.12065 -0.305054)
			(end -0.12065 -0.2794)
			(stroke
				(width 0.1)
				(type default)
			)
			(layer "F.Fab")
		)
		(fp_line
			(start -0.67945 0.3048)
			(end -0.67945 -0.305054)
			(stroke
				(width 0.1)
				(type default)
			)
			(layer "F.Fab")
		)
		(fp_line
			(start -0.67945 -0.305054)
			(end -0.12065 -0.305054)
			(stroke
				(width 0.1)
				(type default)
			)
			(layer "F.Fab")
		)
		(pad "1" smd circle
			(at -0.40005 0 180)
			(size 0 0)
			(layers "F.Cu" "F.Mask" "F.Paste")
			(net "P3V3_AUX")
		)
		(pad "2" smd circle
			(at 0.40005 0 180)
			(size 0 0)
			(layers "F.Cu" "F.Mask" "F.Paste")
			(net "FRU_ADDR2")
		)
	)
	(footprint ""
		(layer "F.Cu")
		(at 140.79982 -36.1442 180)
		(property "Reference" "PR6990"
			(at 0 0 180)
			(layer "F.SilkS")
			(hide yes)
			(effects
				(font
					(size 1.27 1.27)
				)
			)
		)
		(property "Value" ""
			(at 0 0 180)
			(layer "F.Fab")
			(effects
				(font
					(size 1.27 1.27)
				)
			)
		)
		(duplicate_pad_numbers_are_jumpers no)
		(fp_line
			(start 1.2954 0.5842)
			(end -1.2954 0.5842)
			(stroke
				(width 0.1524)
				(type default)
			)
			(layer "F.SilkS")
		)
		(fp_line
			(start 1.2954 -0.5842)
			(end 1.2954 0.5842)
			(stroke
				(width 0.1524)
				(type default)
			)
			(layer "F.SilkS")
		)
		(fp_line
			(start -1.2954 0.5842)
			(end -1.2954 -0.5842)
			(stroke
				(width 0.1524)
				(type default)
			)
			(layer "F.SilkS")
		)
		(fp_line
			(start -1.2954 -0.5842)
			(end 1.2954 -0.5842)
			(stroke
				(width 0.1524)
				(type default)
			)
			(layer "F.SilkS")
		)
		(fp_line
			(start 1.1938 0.4064)
			(end 0.8636 0.4064)
			(stroke
				(width 0.1)
				(type default)
			)
			(layer "F.Fab")
		)
		(fp_line
			(start 1.1938 -0.406654)
			(end 1.1938 0.4064)
			(stroke
				(width 0.1)
				(type default)
			)
			(layer "F.Fab")
		)
		(fp_line
			(start 0.8636 0.4572)
			(end -0.8636 0.4572)
			(stroke
				(width 0.1)
				(type default)
			)
			(layer "F.Fab")
		)
		(fp_line
			(start 0.8636 0.4064)
			(end 0.8636 0.4572)
			(stroke
				(width 0.1)
				(type default)
			)
			(layer "F.Fab")
		)
		(fp_line
			(start 0.8636 -0.406654)
			(end 1.1938 -0.406654)
			(stroke
				(width 0.1)
				(type default)
			)
			(layer "F.Fab")
		)
		(fp_line
			(start 0.8636 -0.4572)
			(end 0.8636 -0.406654)
			(stroke
				(width 0.1)
				(type default)
			)
			(layer "F.Fab")
		)
		(fp_line
			(start -0.8636 0.4572)
			(end -0.8636 0.4318)
			(stroke
				(width 0.1)
				(type default)
			)
			(layer "F.Fab")
		)
		(fp_line
			(start -0.8636 0.4318)
			(end -0.8636 0.4064)
			(stroke
				(width 0.1)
				(type default)
			)
			(layer "F.Fab")
		)
		(fp_line
			(start -0.8636 0.4064)
			(end -1.1938 0.4064)
			(stroke
				(width 0.1)
				(type default)
			)
			(layer "F.Fab")
		)
		(fp_line
			(start -0.8636 -0.406654)
			(end -0.8636 -0.4572)
			(stroke
				(width 0.1)
				(type default)
			)
			(layer "F.Fab")
		)
		(fp_line
			(start -0.8636 -0.4572)
			(end 0.8636 -0.4572)
			(stroke
				(width 0.1)
				(type default)
			)
			(layer "F.Fab")
		)
		(fp_line
			(start -1.1938 0.4064)
			(end -1.1938 -0.406654)
			(stroke
				(width 0.1)
				(type default)
			)
			(layer "F.Fab")
		)
		(fp_line
			(start -1.1938 -0.406654)
			(end -0.8636 -0.406654)
			(stroke
				(width 0.1)
				(type default)
			)
			(layer "F.Fab")
		)
		(pad "1" smd rect
			(at -0.7366 0 90)
			(size 0.7112 0.8128)
			(layers "F.Cu" "F.Mask" "F.Paste")
			(net "P52V_HS2_1272_S_N")
		)
		(pad "2" smd rect
			(at 0.7366 0 90)
			(size 0.7112 0.8128)
			(layers "F.Cu" "F.Mask" "F.Paste")
			(net "P52V_HS2_SENSE_N_R2")
		)
	)
	(footprint ""
		(layer "F.Cu")
		(at 391.199878 -156.830014 180)
		(property "Reference" "J1"
			(at 3.976878 -7.758684 0)
			(unlocked yes)
			(layer "F.SilkS")
			(effects
				(font
					(size 0.7874 0.5842)
					(thickness 0.1524)
				)
				(justify left)
			)
		)
		(property "Value" ""
			(at 0 0 180)
			(layer "F.Fab")
			(effects
				(font
					(size 1.27 1.27)
				)
			)
		)
		(duplicate_pad_numbers_are_jumpers no)
		(fp_line
			(start 12.925044 28.450032)
			(end -4.92506 28.450032)
			(stroke
				(width 0.1524)
				(type default)
			)
			(layer "F.SilkS")
		)
		(fp_line
			(start 12.925044 -6.849872)
			(end 12.925044 28.450032)
			(stroke
				(width 0.1524)
				(type default)
			)
			(layer "F.SilkS")
		)
		(fp_line
			(start 9.92505 25.450038)
			(end -1.925066 25.450038)
			(stroke
				(width 0.1524)
				(type default)
			)
			(layer "F.SilkS")
		)
		(fp_line
			(start 9.92505 -3.850132)
			(end 9.92505 25.450038)
			(stroke
				(width 0.1524)
				(type default)
			)
			(layer "F.SilkS")
		)
		(fp_line
			(start -1.925066 25.450038)
			(end -1.925066 -3.850132)
			(stroke
				(width 0.1524)
				(type default)
			)
			(layer "F.SilkS")
		)
		(fp_line
			(start -1.925066 14.99997)
			(end 9.92505 14.99997)
			(stroke
				(width 0.1524)
				(type default)
			)
			(layer "F.SilkS")
		)
		(fp_line
			(start -1.925066 -3.850132)
			(end 9.92505 -3.850132)
			(stroke
				(width 0.1524)
				(type default)
			)
			(layer "F.SilkS")
		)
		(fp_line
			(start -4.92506 28.450032)
			(end -4.92506 -6.849872)
			(stroke
				(width 0.1524)
				(type default)
			)
			(layer "F.SilkS")
		)
		(fp_line
			(start -4.92506 -6.849872)
			(end 12.925044 -6.849872)
			(stroke
				(width 0.1524)
				(type default)
			)
			(layer "F.SilkS")
		)
		(fp_poly
			(pts
				(xy 0.054864 -0.8636) (xy 0.816864 -2.7686) (xy -0.707136 -2.7686)
			)
			(stroke
				(width 0)
				(type default)
			)
			(fill yes)
			(layer "F.SilkS")
		)
		(fp_line
			(start 12.925044 28.450032)
			(end -4.92506 28.450032)
			(stroke
				(width 0.1524)
				(type default)
			)
			(layer "B.SilkS")
		)
		(fp_line
			(start 12.925044 -6.849872)
			(end 12.925044 28.450032)
			(stroke
				(width 0.1524)
				(type default)
			)
			(layer "B.SilkS")
		)
		(fp_line
			(start -4.92506 28.450032)
			(end -4.92506 -6.849872)
			(stroke
				(width 0.1524)
				(type default)
			)
			(layer "B.SilkS")
		)
		(fp_line
			(start -4.92506 -6.849872)
			(end 12.925044 -6.849872)
			(stroke
				(width 0.1524)
				(type default)
			)
			(layer "B.SilkS")
		)
		(fp_line
			(start 12.925044 28.450032)
			(end -4.92506 28.450032)
			(stroke
				(width 0.1)
				(type default)
			)
			(layer "B.Fab")
		)
		(fp_line
			(start 12.925044 -6.849872)
			(end 12.925044 28.450032)
			(stroke
				(width 0.1)
				(type default)
			)
			(layer "B.Fab")
		)
		(fp_line
			(start -4.92506 28.450032)
			(end -4.92506 -6.849872)
			(stroke
				(width 0.1)
				(type default)
			)
			(layer "B.Fab")
		)
		(fp_line
			(start -4.92506 -6.849872)
			(end 12.925044 -6.849872)
			(stroke
				(width 0.1)
				(type default)
			)
			(layer "B.Fab")
		)
		(fp_line
			(start 9.92505 25.450038)
			(end -1.925066 25.450038)
			(stroke
				(width 0.1)
				(type default)
			)
			(layer "F.Fab")
		)
		(fp_line
			(start 9.92505 -3.850132)
			(end 9.92505 25.450038)
			(stroke
				(width 0.1)
				(type default)
			)
			(layer "F.Fab")
		)
		(fp_line
			(start -1.925066 25.450038)
			(end -1.925066 -3.850132)
			(stroke
				(width 0.1)
				(type default)
			)
			(layer "F.Fab")
		)
		(fp_line
			(start -1.925066 -3.850132)
			(end 9.92505 -3.850132)
			(stroke
				(width 0.1)
				(type default)
			)
			(layer "F.Fab")
		)
		(fp_poly
			(pts
				(xy -2.108708 0) (xy -4.013708 -0.762) (xy -4.013708 0.762)
			)
			(stroke
				(width 0)
				(type default)
			)
			(fill yes)
			(layer "F.Fab")
		)
		(fp_text user "PRESS-FIT"
			(at 9.564878 -5.636514 0)
			(unlocked yes)
			(layer "F.SilkS")
			(effects
				(font
					(size 1.27 0.9652)
					(thickness 0.1524)
				)
				(justify left)
			)
		)
		(fp_text user "PRESS-FIT"
			(at -3.382772 -4.811014 270)
			(unlocked yes)
			(layer "B.SilkS")
			(effects
				(font
					(size 1.905 1.4224)
					(thickness 0.1524)
				)
				(justify left mirror)
			)
		)
		(fp_text user "PRESS-FIT"
			(at 11.346942 12.866116 90)
			(unlocked yes)
			(layer "B.Fab")
			(effects
				(font
					(size 1.905 1.4224)
					(thickness 0.1524)
				)
				(justify left mirror)
			)
		)
		(fp_text user "PRESS-FIT"
			(at 11.346942 -3.872484 90)
			(unlocked yes)
			(layer "F.Fab")
			(effects
				(font
					(size 1.905 1.4224)
					(thickness 0.1524)
				)
				(justify left)
			)
		)
		(pad "" np_thru_hole circle
			(at 3.999992 5.500116 180)
			(size 2.1082 2.1082)
			(drill 2.1082)
			(layers "*.Cu" "*.Mask")
			(clearance 0.381)
			(thermal_gap 0.381)
		)
		(pad "A1" thru_hole rect
			(at 0 0 180)
			(size 1.156208 1.156208)
			(drill 0.749808)
			(layers "*.Cu" "*.Mask")
			(remove_unused_layers no)
			(net "P52V_HS1")
			(clearance 0.0508)
			(thermal_gap 0.0508)
			(padstack
				(mode front_inner_back)
				(layer "Inner"
					(shape circle)
					(size 1.156208 1.156208)
					(clearance 0.0508)
				)
				(layer "B.Cu"
					(shape rect)
					(size 1.156208 1.156208)
					(clearance 0.0508)
				)
			)
		)
		(pad "A2" thru_hole circle
			(at 0 1.999996 180)
			(size 1.156208 1.156208)
			(drill 0.749808)
			(layers "*.Cu" "*.Mask")
			(remove_unused_layers no)
			(net "P52V_HS1")
			(clearance 0.0508)
			(thermal_gap 0.0508)
		)
		(pad "A3" thru_hole circle
			(at 0 3.999992 180)
			(size 1.156208 1.156208)
			(drill 0.749808)
			(layers "*.Cu" "*.Mask")
			(remove_unused_layers no)
			(net "P52V_HS1")
			(clearance 0.0508)
			(thermal_gap 0.0508)
		)
		(pad "A4" thru_hole circle
			(at 1.999996 0 180)
			(size 1.156208 1.156208)
			(drill 0.749808)
			(layers "*.Cu" "*.Mask")
			(remove_unused_layers no)
			(net "P52V_HS1")
			(clearance 0.0508)
			(thermal_gap 0.0508)
		)
		(pad "A5" thru_hole circle
			(at 1.999996 1.999996 180)
			(size 1.156208 1.156208)
			(drill 0.749808)
			(layers "*.Cu" "*.Mask")
			(remove_unused_layers no)
			(net "P52V_HS1")
			(clearance 0.0508)
			(thermal_gap 0.0508)
		)
		(pad "A6" thru_hole circle
			(at 1.999996 3.999992 180)
			(size 1.156208 1.156208)
			(drill 0.749808)
			(layers "*.Cu" "*.Mask")
			(remove_unused_layers no)
			(net "P52V_HS1")
			(clearance 0.0508)
			(thermal_gap 0.0508)
		)
		(pad "B1" thru_hole circle
			(at 7.999984 0 180)
			(size 1.156208 1.156208)
			(drill 0.749808)
			(layers "*.Cu" "*.Mask")
			(remove_unused_layers no)
			(net "P52V_HS1")
			(clearance 0.0508)
			(thermal_gap 0.0508)
		)
		(pad "B2" thru_hole circle
			(at 7.999984 1.999996 180)
			(size 1.156208 1.156208)
			(drill 0.749808)
			(layers "*.Cu" "*.Mask")
			(remove_unused_layers no)
			(net "P52V_HS1")
			(clearance 0.0508)
			(thermal_gap 0.0508)
		)
		(pad "B3" thru_hole circle
			(at 7.999984 3.999992 180)
			(size 1.156208 1.156208)
			(drill 0.749808)
			(layers "*.Cu" "*.Mask")
			(remove_unused_layers no)
			(net "P52V_HS1")
			(clearance 0.0508)
			(thermal_gap 0.0508)
		)
		(pad "B4" thru_hole circle
			(at 5.999988 0 180)
			(size 1.156208 1.156208)
			(drill 0.749808)
			(layers "*.Cu" "*.Mask")
			(remove_unused_layers no)
			(net "P52V_HS1")
			(clearance 0.0508)
			(thermal_gap 0.0508)
		)
		(pad "B5" thru_hole circle
			(at 5.999988 1.999996 180)
			(size 1.156208 1.156208)
			(drill 0.749808)
			(layers "*.Cu" "*.Mask")
			(remove_unused_layers no)
			(net "P52V_HS1")
			(clearance 0.0508)
			(thermal_gap 0.0508)
		)
		(pad "B6" thru_hole circle
			(at 5.999988 3.999992 180)
			(size 1.156208 1.156208)
			(drill 0.749808)
			(layers "*.Cu" "*.Mask")
			(remove_unused_layers no)
			(net "P52V_HS1")
			(clearance 0.0508)
			(thermal_gap 0.0508)
		)
		(pad "C1" thru_hole circle
			(at 7.999984 7.999984 180)
			(size 1.156208 1.156208)
			(drill 0.749808)
			(layers "*.Cu" "*.Mask")
			(remove_unused_layers no)
			(net "GND")
			(clearance 0.0508)
			(thermal_gap 0.0508)
		)
		(pad "C2" thru_hole circle
			(at 7.999984 9.99998 180)
			(size 1.156208 1.156208)
			(drill 0.749808)
			(layers "*.Cu" "*.Mask")
			(remove_unused_layers no)
			(net "GND")
			(clearance 0.0508)
			(thermal_gap 0.0508)
		)
		(pad "C3" thru_hole circle
			(at 7.999984 11.999976 180)
			(size 1.156208 1.156208)
			(drill 0.749808)
			(layers "*.Cu" "*.Mask")
			(remove_unused_layers no)
			(net "GND")
			(clearance 0.0508)
			(thermal_gap 0.0508)
		)
		(pad "C4" thru_hole circle
			(at 5.999988 7.999984 180)
			(size 1.156208 1.156208)
			(drill 0.749808)
			(layers "*.Cu" "*.Mask")
			(remove_unused_layers no)
			(net "GND")
			(clearance 0.0508)
			(thermal_gap 0.0508)
		)
		(pad "C5" thru_hole circle
			(at 5.999988 9.99998 180)
			(size 1.156208 1.156208)
			(drill 0.749808)
			(layers "*.Cu" "*.Mask")
			(remove_unused_layers no)
			(net "GND")
			(clearance 0.0508)
			(thermal_gap 0.0508)
		)
		(pad "C6" thru_hole circle
			(at 5.999988 11.999976 180)
			(size 1.156208 1.156208)
			(drill 0.749808)
			(layers "*.Cu" "*.Mask")
			(remove_unused_layers no)
			(net "GND")
			(clearance 0.0508)
			(thermal_gap 0.0508)
		)
		(pad "D1" thru_hole circle
			(at 0 7.999984 180)
			(size 1.156208 1.156208)
			(drill 0.749808)
			(layers "*.Cu" "*.Mask")
			(remove_unused_layers no)
			(net "GND")
			(clearance 0.0508)
			(thermal_gap 0.0508)
		)
		(pad "D2" thru_hole circle
			(at 0 9.99998 180)
			(size 1.156208 1.156208)
			(drill 0.749808)
			(layers "*.Cu" "*.Mask")
			(remove_unused_layers no)
			(net "GND")
			(clearance 0.0508)
			(thermal_gap 0.0508)
		)
		(pad "D3" thru_hole circle
			(at 0 11.999976 180)
			(size 1.156208 1.156208)
			(drill 0.749808)
			(layers "*.Cu" "*.Mask")
			(remove_unused_layers no)
			(net "GND")
			(clearance 0.0508)
			(thermal_gap 0.0508)
		)
		(pad "D4" thru_hole circle
			(at 1.999996 7.999984 180)
			(size 1.156208 1.156208)
			(drill 0.749808)
			(layers "*.Cu" "*.Mask")
			(remove_unused_layers no)
			(net "GND")
			(clearance 0.0508)
			(thermal_gap 0.0508)
		)
		(pad "D5" thru_hole circle
			(at 1.999996 9.99998 180)
			(size 1.156208 1.156208)
			(drill 0.749808)
			(layers "*.Cu" "*.Mask")
			(remove_unused_layers no)
			(net "GND")
			(clearance 0.0508)
			(thermal_gap 0.0508)
		)
		(pad "D6" thru_hole circle
			(at 1.999996 11.999976 180)
			(size 1.156208 1.156208)
			(drill 0.749808)
			(layers "*.Cu" "*.Mask")
			(remove_unused_layers no)
			(net "GND")
			(clearance 0.0508)
			(thermal_gap 0.0508)
		)
		(zone
			(layers "F.Cu" "B.Cu" "In1.Cu" "In2.Cu" "In3.Cu" "In4.Cu" "In5.Cu" "In6.Cu"
				"In7.Cu" "In8.Cu"
			)
			(hatch none 0.5)
			(connect_pads
				(clearance 0)
			)
			(min_thickness 0.25)
			(keepout
				(tracks not_allowed)
				(vias allowed)
				(pads allowed)
				(copperpour not_allowed)
				(footprints allowed)
			)
			(placement
				(enabled no)
				(sheetname "")
			)
			(fill
				(thermal_gap 0.5)
				(thermal_bridge_width 0.5)
				(island_removal_mode 0)
			)
			(polygon
				(pts
					(arc
						(start 388.660386 -162.329876)
						(mid 385.739386 -162.330384)
						(end 388.660386 -162.329876)
					)
				)
			)
		)
		(zone
			(layer "B.Cu")
			(hatch none 0.5)
			(connect_pads
				(clearance 0)
			)
			(min_thickness 0.25)
			(keepout
				(tracks allowed)
				(vias not_allowed)
				(pads allowed)
				(copperpour not_allowed)
				(footprints allowed)
			)
			(placement
				(enabled no)
				(sheetname "")
			)
			(fill
				(thermal_gap 0.5)
				(thermal_bridge_width 0.5)
				(island_removal_mode 0)
			)
			(polygon
				(pts
					(xy 385.840986 -169.46753) (xy 382.564386 -169.46753) (xy 382.564386 -164.18433) (xy 385.840986 -164.18433)
				)
			)
		)
		(zone
			(layer "B.Cu")
			(hatch none 0.5)
			(connect_pads
				(clearance 0)
			)
			(min_thickness 0.25)
			(keepout
				(tracks allowed)
				(vias not_allowed)
				(pads allowed)
				(copperpour not_allowed)
				(footprints allowed)
			)
			(placement
				(enabled no)
				(sheetname "")
			)
			(fill
				(thermal_gap 0.5)
				(thermal_bridge_width 0.5)
				(island_removal_mode 0)
			)
			(polygon
				(pts
					(xy 385.840986 -161.46653) (xy 382.564386 -161.46653) (xy 382.564386 -156.18333) (xy 385.840986 -156.18333)
				)
			)
		)
		(zone
			(layer "B.Cu")
			(hatch none 0.5)
			(connect_pads
				(clearance 0)
			)
			(min_thickness 0.25)
			(keepout
				(tracks allowed)
				(vias not_allowed)
				(pads allowed)
				(copperpour not_allowed)
				(footprints allowed)
			)
			(placement
				(enabled no)
				(sheetname "")
			)
			(fill
				(thermal_gap 0.5)
				(thermal_bridge_width 0.5)
				(island_removal_mode 0)
			)
			(polygon
				(pts
					(xy 391.835386 -169.46753) (xy 388.558786 -169.46753) (xy 388.558786 -164.18433) (xy 391.835386 -164.18433)
				)
			)
		)
		(zone
			(layer "B.Cu")
			(hatch none 0.5)
			(connect_pads
				(clearance 0)
			)
			(min_thickness 0.25)
			(keepout
				(tracks allowed)
				(vias not_allowed)
				(pads allowed)
				(copperpour not_allowed)
				(footprints allowed)
			)
			(placement
				(enabled no)
				(sheetname "")
			)
			(fill
				(thermal_gap 0.5)
				(thermal_bridge_width 0.5)
				(island_removal_mode 0)
			)
			(polygon
				(pts
					(xy 391.835386 -161.46653) (xy 388.558786 -161.46653) (xy 388.558786 -156.18333) (xy 391.835386 -156.18333)
				)
			)
		)
	)
	(footprint ""
		(layer "F.Cu")
		(at 427.228 -38.989)
		(property "Reference" "R137"
			(at 0 0 0)
			(layer "F.SilkS")
			(hide yes)
			(effects
				(font
					(size 1.27 1.27)
				)
			)
		)
		(property "Value" ""
			(at 0 0 0)
			(layer "F.Fab")
			(effects
				(font
					(size 1.27 1.27)
				)
			)
		)
		(duplicate_pad_numbers_are_jumpers no)
		(fp_line
			(start -0.7874 -0.4064)
			(end 0.7874 -0.4064)
			(stroke
				(width 0.1524)
				(type default)
			)
			(layer "F.SilkS")
		)
		(fp_line
			(start -0.7874 0.4064)
			(end -0.7874 -0.4064)
			(stroke
				(width 0.1524)
				(type default)
			)
			(layer "F.SilkS")
		)
		(fp_line
			(start 0.7874 -0.4064)
			(end 0.7874 0.4064)
			(stroke
				(width 0.1524)
				(type default)
			)
			(layer "F.SilkS")
		)
		(fp_line
			(start 0.7874 0.4064)
			(end -0.7874 0.4064)
			(stroke
				(width 0.1524)
				(type default)
			)
			(layer "F.SilkS")
		)
		(fp_line
			(start -0.67945 -0.305054)
			(end -0.12065 -0.305054)
			(stroke
				(width 0.1)
				(type default)
			)
			(layer "F.Fab")
		)
		(fp_line
			(start -0.67945 0.3048)
			(end -0.67945 -0.305054)
			(stroke
				(width 0.1)
				(type default)
			)
			(layer "F.Fab")
		)
		(fp_line
			(start -0.12065 -0.305054)
			(end -0.12065 -0.2794)
			(stroke
				(width 0.1)
				(type default)
			)
			(layer "F.Fab")
		)
		(fp_line
			(start -0.12065 -0.2794)
			(end 0.12065 -0.2794)
			(stroke
				(width 0.1)
				(type default)
			)
			(layer "F.Fab")
		)
		(fp_line
			(start -0.12065 0.2794)
			(end -0.12065 0.3048)
			(stroke
				(width 0.1)
				(type default)
			)
			(layer "F.Fab")
		)
		(fp_line
			(start -0.12065 0.3048)
			(end -0.67945 0.3048)
			(stroke
				(width 0.1)
				(type default)
			)
			(layer "F.Fab")
		)
		(fp_line
			(start 0.120396 0.2794)
			(end -0.12065 0.2794)
			(stroke
				(width 0.1)
				(type default)
			)
			(layer "F.Fab")
		)
		(fp_line
			(start 0.120396 0.3048)
			(end 0.120396 0.2794)
			(stroke
				(width 0.1)
				(type default)
			)
			(layer "F.Fab")
		)
		(fp_line
			(start 0.12065 -0.3048)
			(end 0.67945 -0.3048)
			(stroke
				(width 0.1)
				(type default)
			)
			(layer "F.Fab")
		)
		(fp_line
			(start 0.12065 -0.2794)
			(end 0.12065 -0.3048)
			(stroke
				(width 0.1)
				(type default)
			)
			(layer "F.Fab")
		)
		(fp_line
			(start 0.67945 -0.3048)
			(end 0.67945 0.3048)
			(stroke
				(width 0.1)
				(type default)
			)
			(layer "F.Fab")
		)
		(fp_line
			(start 0.67945 0.3048)
			(end 0.120396 0.3048)
			(stroke
				(width 0.1)
				(type default)
			)
			(layer "F.Fab")
		)
		(pad "1" smd circle
			(at -0.40005 0)
			(size 0 0)
			(layers "F.Cu" "F.Mask" "F.Paste")
			(net "BOARD_ID_1")
		)
		(pad "2" smd circle
			(at 0.40005 0)
			(size 0 0)
			(layers "F.Cu" "F.Mask" "F.Paste")
			(net "GND")
		)
	)
	(footprint ""
		(layer "F.Cu")
		(at 304.546 -39.4462)
		(property "Reference" "PR5864"
			(at 0 0 0)
			(layer "F.SilkS")
			(hide yes)
			(effects
				(font
					(size 1.27 1.27)
				)
			)
		)
		(property "Value" ""
			(at 0 0 0)
			(layer "F.Fab")
			(effects
				(font
					(size 1.27 1.27)
				)
			)
		)
		(duplicate_pad_numbers_are_jumpers no)
		(fp_line
			(start -0.7874 -0.4064)
			(end 0.7874 -0.4064)
			(stroke
				(width 0.1524)
				(type default)
			)
			(layer "F.SilkS")
		)
		(fp_line
			(start -0.7874 0.4064)
			(end -0.7874 -0.4064)
			(stroke
				(width 0.1524)
				(type default)
			)
			(layer "F.SilkS")
		)
		(fp_line
			(start 0.7874 -0.4064)
			(end 0.7874 0.4064)
			(stroke
				(width 0.1524)
				(type default)
			)
			(layer "F.SilkS")
		)
		(fp_line
			(start 0.7874 0.4064)
			(end -0.7874 0.4064)
			(stroke
				(width 0.1524)
				(type default)
			)
			(layer "F.SilkS")
		)
		(fp_line
			(start -0.67945 -0.305054)
			(end -0.12065 -0.305054)
			(stroke
				(width 0.1)
				(type default)
			)
			(layer "F.Fab")
		)
		(fp_line
			(start -0.67945 0.3048)
			(end -0.67945 -0.305054)
			(stroke
				(width 0.1)
				(type default)
			)
			(layer "F.Fab")
		)
		(fp_line
			(start -0.12065 -0.305054)
			(end -0.12065 -0.2794)
			(stroke
				(width 0.1)
				(type default)
			)
			(layer "F.Fab")
		)
		(fp_line
			(start -0.12065 -0.2794)
			(end 0.12065 -0.2794)
			(stroke
				(width 0.1)
				(type default)
			)
			(layer "F.Fab")
		)
		(fp_line
			(start -0.12065 0.2794)
			(end -0.12065 0.3048)
			(stroke
				(width 0.1)
				(type default)
			)
			(layer "F.Fab")
		)
		(fp_line
			(start -0.12065 0.3048)
			(end -0.67945 0.3048)
			(stroke
				(width 0.1)
				(type default)
			)
			(layer "F.Fab")
		)
		(fp_line
			(start 0.120396 0.2794)
			(end -0.12065 0.2794)
			(stroke
				(width 0.1)
				(type default)
			)
			(layer "F.Fab")
		)
		(fp_line
			(start 0.120396 0.3048)
			(end 0.120396 0.2794)
			(stroke
				(width 0.1)
				(type default)
			)
			(layer "F.Fab")
		)
		(fp_line
			(start 0.12065 -0.3048)
			(end 0.67945 -0.3048)
			(stroke
				(width 0.1)
				(type default)
			)
			(layer "F.Fab")
		)
		(fp_line
			(start 0.12065 -0.2794)
			(end 0.12065 -0.3048)
			(stroke
				(width 0.1)
				(type default)
			)
			(layer "F.Fab")
		)
		(fp_line
			(start 0.67945 -0.3048)
			(end 0.67945 0.3048)
			(stroke
				(width 0.1)
				(type default)
			)
			(layer "F.Fab")
		)
		(fp_line
			(start 0.67945 0.3048)
			(end 0.120396 0.3048)
			(stroke
				(width 0.1)
				(type default)
			)
			(layer "F.Fab")
		)
		(pad "1" smd circle
			(at -0.40005 0)
			(size 0 0)
			(layers "F.Cu" "F.Mask" "F.Paste")
			(net "P52V_HS_4287_S2P")
		)
		(pad "2" smd circle
			(at 0.40005 0)
			(size 0 0)
			(layers "F.Cu" "F.Mask" "F.Paste")
			(net "P52V_HS_4287_S2N")
		)
	)
	(footprint ""
		(layer "F.Cu")
		(at 450.42074 -84.409788)
		(property "Reference" "PC53"
			(at 0 0 0)
			(layer "F.SilkS")
			(hide yes)
			(effects
				(font
					(size 1.27 1.27)
				)
			)
		)
		(property "Value" ""
			(at 0 0 0)
			(layer "F.Fab")
			(effects
				(font
					(size 1.27 1.27)
				)
			)
		)
		(duplicate_pad_numbers_are_jumpers no)
		(fp_line
			(start -0.7874 -0.4064)
			(end 0.7874 -0.4064)
			(stroke
				(width 0.1524)
				(type default)
			)
			(layer "F.SilkS")
		)
		(fp_line
			(start -0.7874 0.4064)
			(end -0.7874 -0.4064)
			(stroke
				(width 0.1524)
				(type default)
			)
			(layer "F.SilkS")
		)
		(fp_line
			(start 0.7874 -0.4064)
			(end 0.7874 0.4064)
			(stroke
				(width 0.1524)
				(type default)
			)
			(layer "F.SilkS")
		)
		(fp_line
			(start 0.7874 0.4064)
			(end -0.7874 0.4064)
			(stroke
				(width 0.1524)
				(type default)
			)
			(layer "F.SilkS")
		)
		(fp_line
			(start -0.67945 -0.305054)
			(end -0.12065 -0.305054)
			(stroke
				(width 0.1)
				(type default)
			)
			(layer "F.Fab")
		)
		(fp_line
			(start -0.67945 0.3048)
			(end -0.67945 -0.305054)
			(stroke
				(width 0.1)
				(type default)
			)
			(layer "F.Fab")
		)
		(fp_line
			(start -0.12065 -0.305054)
			(end -0.12065 -0.2794)
			(stroke
				(width 0.1)
				(type default)
			)
			(layer "F.Fab")
		)
		(fp_line
			(start -0.12065 -0.2794)
			(end 0.12065 -0.2794)
			(stroke
				(width 0.1)
				(type default)
			)
			(layer "F.Fab")
		)
		(fp_line
			(start -0.12065 0.2794)
			(end -0.12065 0.3048)
			(stroke
				(width 0.1)
				(type default)
			)
			(layer "F.Fab")
		)
		(fp_line
			(start -0.12065 0.3048)
			(end -0.67945 0.3048)
			(stroke
				(width 0.1)
				(type default)
			)
			(layer "F.Fab")
		)
		(fp_line
			(start 0.120396 0.2794)
			(end -0.12065 0.2794)
			(stroke
				(width 0.1)
				(type default)
			)
			(layer "F.Fab")
		)
		(fp_line
			(start 0.120396 0.3048)
			(end 0.120396 0.2794)
			(stroke
				(width 0.1)
				(type default)
			)
			(layer "F.Fab")
		)
		(fp_line
			(start 0.12065 -0.3048)
			(end 0.67945 -0.3048)
			(stroke
				(width 0.1)
				(type default)
			)
			(layer "F.Fab")
		)
		(fp_line
			(start 0.12065 -0.2794)
			(end 0.12065 -0.3048)
			(stroke
				(width 0.1)
				(type default)
			)
			(layer "F.Fab")
		)
		(fp_line
			(start 0.67945 -0.3048)
			(end 0.67945 0.3048)
			(stroke
				(width 0.1)
				(type default)
			)
			(layer "F.Fab")
		)
		(fp_line
			(start 0.67945 0.3048)
			(end 0.120396 0.3048)
			(stroke
				(width 0.1)
				(type default)
			)
			(layer "F.Fab")
		)
		(pad "1" smd circle
			(at -0.40005 0)
			(size 0 0)
			(layers "F.Cu" "F.Mask" "F.Paste")
			(net "P3V3_HPDB_REF")
		)
		(pad "2" smd circle
			(at 0.40005 0)
			(size 0 0)
			(layers "F.Cu" "F.Mask" "F.Paste")
			(net "GND")
		)
	)
	(footprint ""
		(layer "F.Cu")
		(at 281.0764 -76.327)
		(property "Reference" "PR36"
			(at 0 0 0)
			(layer "F.SilkS")
			(hide yes)
			(effects
				(font
					(size 1.27 1.27)
				)
			)
		)
		(property "Value" ""
			(at 0 0 0)
			(layer "F.Fab")
			(effects
				(font
					(size 1.27 1.27)
				)
			)
		)
		(duplicate_pad_numbers_are_jumpers no)
		(fp_line
			(start -0.7874 -0.4064)
			(end 0.7874 -0.4064)
			(stroke
				(width 0.1524)
				(type default)
			)
			(layer "F.SilkS")
		)
		(fp_line
			(start -0.7874 0.4064)
			(end -0.7874 -0.4064)
			(stroke
				(width 0.1524)
				(type default)
			)
			(layer "F.SilkS")
		)
		(fp_line
			(start 0.7874 -0.4064)
			(end 0.7874 0.4064)
			(stroke
				(width 0.1524)
				(type default)
			)
			(layer "F.SilkS")
		)
		(fp_line
			(start 0.7874 0.4064)
			(end -0.7874 0.4064)
			(stroke
				(width 0.1524)
				(type default)
			)
			(layer "F.SilkS")
		)
		(fp_line
			(start -0.67945 -0.305054)
			(end -0.12065 -0.305054)
			(stroke
				(width 0.1)
				(type default)
			)
			(layer "F.Fab")
		)
		(fp_line
			(start -0.67945 0.3048)
			(end -0.67945 -0.305054)
			(stroke
				(width 0.1)
				(type default)
			)
			(layer "F.Fab")
		)
		(fp_line
			(start -0.12065 -0.305054)
			(end -0.12065 -0.2794)
			(stroke
				(width 0.1)
				(type default)
			)
			(layer "F.Fab")
		)
		(fp_line
			(start -0.12065 -0.2794)
			(end 0.12065 -0.2794)
			(stroke
				(width 0.1)
				(type default)
			)
			(layer "F.Fab")
		)
		(fp_line
			(start -0.12065 0.2794)
			(end -0.12065 0.3048)
			(stroke
				(width 0.1)
				(type default)
			)
			(layer "F.Fab")
		)
		(fp_line
			(start -0.12065 0.3048)
			(end -0.67945 0.3048)
			(stroke
				(width 0.1)
				(type default)
			)
			(layer "F.Fab")
		)
		(fp_line
			(start 0.120396 0.2794)
			(end -0.12065 0.2794)
			(stroke
				(width 0.1)
				(type default)
			)
			(layer "F.Fab")
		)
		(fp_line
			(start 0.120396 0.3048)
			(end 0.120396 0.2794)
			(stroke
				(width 0.1)
				(type default)
			)
			(layer "F.Fab")
		)
		(fp_line
			(start 0.12065 -0.3048)
			(end 0.67945 -0.3048)
			(stroke
				(width 0.1)
				(type default)
			)
			(layer "F.Fab")
		)
		(fp_line
			(start 0.12065 -0.2794)
			(end 0.12065 -0.3048)
			(stroke
				(width 0.1)
				(type default)
			)
			(layer "F.Fab")
		)
		(fp_line
			(start 0.67945 -0.3048)
			(end 0.67945 0.3048)
			(stroke
				(width 0.1)
				(type default)
			)
			(layer "F.Fab")
		)
		(fp_line
			(start 0.67945 0.3048)
			(end 0.120396 0.3048)
			(stroke
				(width 0.1)
				(type default)
			)
			(layer "F.Fab")
		)
		(pad "1" smd circle
			(at -0.40005 0)
			(size 0 0)
			(layers "F.Cu" "F.Mask" "F.Paste")
			(net "P52V_HS1_ESTART")
		)
		(pad "2" smd circle
			(at 0.40005 0)
			(size 0 0)
			(layers "F.Cu" "F.Mask" "F.Paste")
			(net "GND_FIELD_SIGNAL")
		)
	)
	(footprint ""
		(layer "F.Cu")
		(at 438.3278 -25.146 180)
		(property "Reference" "R66"
			(at 0 0 180)
			(layer "F.SilkS")
			(hide yes)
			(effects
				(font
					(size 1.27 1.27)
				)
			)
		)
		(property "Value" ""
			(at 0 0 180)
			(layer "F.Fab")
			(effects
				(font
					(size 1.27 1.27)
				)
			)
		)
		(duplicate_pad_numbers_are_jumpers no)
		(fp_line
			(start 0.7874 0.4064)
			(end -0.7874 0.4064)
			(stroke
				(width 0.1524)
				(type default)
			)
			(layer "F.SilkS")
		)
		(fp_line
			(start 0.7874 -0.4064)
			(end 0.7874 0.4064)
			(stroke
				(width 0.1524)
				(type default)
			)
			(layer "F.SilkS")
		)
		(fp_line
			(start -0.7874 0.4064)
			(end -0.7874 -0.4064)
			(stroke
				(width 0.1524)
				(type default)
			)
			(layer "F.SilkS")
		)
		(fp_line
			(start -0.7874 -0.4064)
			(end 0.7874 -0.4064)
			(stroke
				(width 0.1524)
				(type default)
			)
			(layer "F.SilkS")
		)
		(fp_line
			(start 0.67945 0.3048)
			(end 0.120396 0.3048)
			(stroke
				(width 0.1)
				(type default)
			)
			(layer "F.Fab")
		)
		(fp_line
			(start 0.67945 -0.3048)
			(end 0.67945 0.3048)
			(stroke
				(width 0.1)
				(type default)
			)
			(layer "F.Fab")
		)
		(fp_line
			(start 0.12065 -0.2794)
			(end 0.12065 -0.3048)
			(stroke
				(width 0.1)
				(type default)
			)
			(layer "F.Fab")
		)
		(fp_line
			(start 0.12065 -0.3048)
			(end 0.67945 -0.3048)
			(stroke
				(width 0.1)
				(type default)
			)
			(layer "F.Fab")
		)
		(fp_line
			(start 0.120396 0.3048)
			(end 0.120396 0.2794)
			(stroke
				(width 0.1)
				(type default)
			)
			(layer "F.Fab")
		)
		(fp_line
			(start 0.120396 0.2794)
			(end -0.12065 0.2794)
			(stroke
				(width 0.1)
				(type default)
			)
			(layer "F.Fab")
		)
		(fp_line
			(start -0.12065 0.3048)
			(end -0.67945 0.3048)
			(stroke
				(width 0.1)
				(type default)
			)
			(layer "F.Fab")
		)
		(fp_line
			(start -0.12065 0.2794)
			(end -0.12065 0.3048)
			(stroke
				(width 0.1)
				(type default)
			)
			(layer "F.Fab")
		)
		(fp_line
			(start -0.12065 -0.2794)
			(end 0.12065 -0.2794)
			(stroke
				(width 0.1)
				(type default)
			)
			(layer "F.Fab")
		)
		(fp_line
			(start -0.12065 -0.305054)
			(end -0.12065 -0.2794)
			(stroke
				(width 0.1)
				(type default)
			)
			(layer "F.Fab")
		)
		(fp_line
			(start -0.67945 0.3048)
			(end -0.67945 -0.305054)
			(stroke
				(width 0.1)
				(type default)
			)
			(layer "F.Fab")
		)
		(fp_line
			(start -0.67945 -0.305054)
			(end -0.12065 -0.305054)
			(stroke
				(width 0.1)
				(type default)
			)
			(layer "F.Fab")
		)
		(pad "1" smd circle
			(at -0.40005 0 180)
			(size 0 0)
			(layers "F.Cu" "F.Mask" "F.Paste")
			(net "GND")
		)
		(pad "2" smd circle
			(at 0.40005 0 180)
			(size 0 0)
			(layers "F.Cu" "F.Mask" "F.Paste")
			(net "FRU_ADDR0")
		)
	)
	(footprint ""
		(layer "F.Cu")
		(at 433.705 -50.038 -90)
		(property "Reference" "R5898"
			(at 0 0 270)
			(layer "F.SilkS")
			(hide yes)
			(effects
				(font
					(size 1.27 1.27)
				)
			)
		)
		(property "Value" ""
			(at 0 0 270)
			(layer "F.Fab")
			(effects
				(font
					(size 1.27 1.27)
				)
			)
		)
		(duplicate_pad_numbers_are_jumpers no)
		(fp_line
			(start -0.7874 0.4064)
			(end -0.7874 -0.4064)
			(stroke
				(width 0.1524)
				(type default)
			)
			(layer "F.SilkS")
		)
		(fp_line
			(start 0.7874 0.4064)
			(end -0.7874 0.4064)
			(stroke
				(width 0.1524)
				(type default)
			)
			(layer "F.SilkS")
		)
		(fp_line
			(start -0.7874 -0.4064)
			(end 0.7874 -0.4064)
			(stroke
				(width 0.1524)
				(type default)
			)
			(layer "F.SilkS")
		)
		(fp_line
			(start 0.7874 -0.4064)
			(end 0.7874 0.4064)
			(stroke
				(width 0.1524)
				(type default)
			)
			(layer "F.SilkS")
		)
		(fp_line
			(start -0.67945 0.3048)
			(end -0.67945 -0.305054)
			(stroke
				(width 0.1)
				(type default)
			)
			(layer "F.Fab")
		)
		(fp_line
			(start -0.12065 0.3048)
			(end -0.67945 0.3048)
			(stroke
				(width 0.1)
				(type default)
			)
			(layer "F.Fab")
		)
		(fp_line
			(start 0.120396 0.3048)
			(end 0.120396 0.2794)
			(stroke
				(width 0.1)
				(type default)
			)
			(layer "F.Fab")
		)
		(fp_line
			(start 0.67945 0.3048)
			(end 0.120396 0.3048)
			(stroke
				(width 0.1)
				(type default)
			)
			(layer "F.Fab")
		)
		(fp_line
			(start -0.12065 0.2794)
			(end -0.12065 0.3048)
			(stroke
				(width 0.1)
				(type default)
			)
			(layer "F.Fab")
		)
		(fp_line
			(start 0.120396 0.2794)
			(end -0.12065 0.2794)
			(stroke
				(width 0.1)
				(type default)
			)
			(layer "F.Fab")
		)
		(fp_line
			(start -0.12065 -0.2794)
			(end 0.12065 -0.2794)
			(stroke
				(width 0.1)
				(type default)
			)
			(layer "F.Fab")
		)
		(fp_line
			(start 0.12065 -0.2794)
			(end 0.12065 -0.3048)
			(stroke
				(width 0.1)
				(type default)
			)
			(layer "F.Fab")
		)
		(fp_line
			(start 0.12065 -0.3048)
			(end 0.67945 -0.3048)
			(stroke
				(width 0.1)
				(type default)
			)
			(layer "F.Fab")
		)
		(fp_line
			(start 0.67945 -0.3048)
			(end 0.67945 0.3048)
			(stroke
				(width 0.1)
				(type default)
			)
			(layer "F.Fab")
		)
		(fp_line
			(start -0.67945 -0.305054)
			(end -0.12065 -0.305054)
			(stroke
				(width 0.1)
				(type default)
			)
			(layer "F.Fab")
		)
		(fp_line
			(start -0.12065 -0.305054)
			(end -0.12065 -0.2794)
			(stroke
				(width 0.1)
				(type default)
			)
			(layer "F.Fab")
		)
		(pad "1" smd circle
			(at -0.40005 0 270)
			(size 0 0)
			(layers "F.Cu" "F.Mask" "F.Paste")
			(net "PWRGD_P52V_HS_PG_R2")
		)
		(pad "2" smd circle
			(at 0.40005 0 270)
			(size 0 0)
			(layers "F.Cu" "F.Mask" "F.Paste")
			(net "PWRGD_P52V_HS_PG")
		)
	)
	(footprint ""
		(layer "F.Cu")
		(at 446.333372 -85.257132 180)
		(property "Reference" "PU5"
			(at 2.315972 -3.241802 0)
			(unlocked yes)
			(layer "F.SilkS")
			(effects
				(font
					(size 0.7874 0.5842)
					(thickness 0.1524)
				)
				(justify left)
			)
		)
		(property "Value" ""
			(at 0 0 180)
			(layer "F.Fab")
			(effects
				(font
					(size 1.27 1.27)
				)
			)
		)
		(duplicate_pad_numbers_are_jumpers no)
		(fp_line
			(start 1.549908 2.050034)
			(end 1.549908 1.9304)
			(stroke
				(width 0.1524)
				(type default)
			)
			(layer "F.SilkS")
		)
		(fp_line
			(start 1.549908 -1.9812)
			(end 1.549908 -2.050034)
			(stroke
				(width 0.1524)
				(type default)
			)
			(layer "F.SilkS")
		)
		(fp_line
			(start 1.549908 -2.050034)
			(end 0.5842 -2.050034)
			(stroke
				(width 0.1524)
				(type default)
			)
			(layer "F.SilkS")
		)
		(fp_line
			(start 0 2.050034)
			(end 1.549908 2.050034)
			(stroke
				(width 0.1524)
				(type default)
			)
			(layer "F.SilkS")
		)
		(fp_line
			(start -0.5842 -2.050034)
			(end -1.549908 -2.050034)
			(stroke
				(width 0.1524)
				(type default)
			)
			(layer "F.SilkS")
		)
		(fp_line
			(start -1.549908 2.050034)
			(end -0.5842 2.050034)
			(stroke
				(width 0.1524)
				(type default)
			)
			(layer "F.SilkS")
		)
		(fp_line
			(start -1.549908 1.9812)
			(end -1.549908 2.050034)
			(stroke
				(width 0.1524)
				(type default)
			)
			(layer "F.SilkS")
		)
		(fp_line
			(start -1.549908 -2.050034)
			(end -1.549908 -1.9812)
			(stroke
				(width 0.1524)
				(type default)
			)
			(layer "F.SilkS")
		)
		(fp_poly
			(pts
				(xy -2.9464 -2.208022) (xy -2.9464 -1.192022) (xy -1.9304 -1.700022)
			)
			(stroke
				(width 0)
				(type default)
			)
			(fill yes)
			(layer "F.SilkS")
		)
		(fp_line
			(start 1.549908 2.050034)
			(end 1.549908 -2.050034)
			(stroke
				(width 0.1)
				(type default)
			)
			(layer "F.Fab")
		)
		(fp_line
			(start 1.549908 -2.050034)
			(end -1.549908 -2.050034)
			(stroke
				(width 0.1)
				(type default)
			)
			(layer "F.Fab")
		)
		(fp_line
			(start -1.549908 2.050034)
			(end 1.549908 2.050034)
			(stroke
				(width 0.1)
				(type default)
			)
			(layer "F.Fab")
		)
		(fp_line
			(start -1.549908 -2.050034)
			(end -1.549908 2.050034)
			(stroke
				(width 0.1)
				(type default)
			)
			(layer "F.Fab")
		)
		(fp_poly
			(pts
				(xy -2.9464 -2.208022) (xy -2.9464 -1.192022) (xy -1.9304 -1.700022)
			)
			(stroke
				(width 0)
				(type default)
			)
			(fill yes)
			(layer "F.Fab")
		)
		(pad "1" smd circle
			(at -1.35001 -1.700022 180)
			(size 0 0)
			(layers "F.Cu" "F.Mask" "F.Paste")
			(net "SW_P3V3_HPDB_BT")
		)
		(pad "2" smd rect
			(at -1.400048 -1.199896 270)
			(size 0.1778 0.8128)
			(layers "F.Cu" "F.Mask" "F.Paste")
			(net "GND")
		)
		(pad "3" smd rect
			(at -1.400048 -0.8001 270)
			(size 0.1778 0.8128)
			(layers "F.Cu" "F.Mask" "F.Paste")
			(net "P3V3_HPDB_CS")
		)
		(pad "4" smd rect
			(at -1.400048 -0.40005 270)
			(size 0.1778 0.8128)
			(layers "F.Cu" "F.Mask" "F.Paste")
			(net "GND")
		)
		(pad "5" smd rect
			(at -1.400048 0 270)
			(size 0.1778 0.8128)
			(layers "F.Cu" "F.Mask" "F.Paste")
			(net "P3V3_HPDB_REF")
		)
		(pad "6" smd rect
			(at -1.400048 0.40005 270)
			(size 0.1778 0.8128)
			(layers "F.Cu" "F.Mask" "F.Paste")
			(net "GND")
		)
		(pad "7" smd rect
			(at -1.400048 0.8001 270)
			(size 0.1778 0.8128)
			(layers "F.Cu" "F.Mask" "F.Paste")
			(net "P3V3_HPDB_FB")
		)
		(pad "8" smd rect
			(at -1.400048 1.199896 270)
			(size 0.1778 0.8128)
			(layers "F.Cu" "F.Mask" "F.Paste")
			(net "P3V3_HPDB_EN")
		)
		(pad "9" smd rect
			(at -1.400048 1.700022 270)
			(size 0.3048 0.8128)
			(layers "F.Cu" "F.Mask" "F.Paste")
			(net "P3V3_HPDB_PG_R")
		)
		(pad "10" smd rect
			(at -0.299974 1.299972 180)
			(size 0.3048 2.0066)
			(layers "F.Cu" "F.Mask" "F.Paste")
			(net "SW_P3V3_HPDB_FLT")
		)
		(pad "11_18" smd circle
			(at 1.175004 0.275082 180)
			(size 0 0)
			(layers "F.Cu" "F.Mask" "F.Paste")
			(net "GND")
		)
		(pad "19" smd rect
			(at 1.400048 -1.700022 90)
			(size 0.3048 0.8128)
			(layers "F.Cu" "F.Mask" "F.Paste")
			(net "P3V3_HPDB_VCC")
		)
		(pad "20" smd rect
			(at 0.299974 -1.299972 180)
			(size 0.3048 2.0066)
			(layers "F.Cu" "F.Mask" "F.Paste")
			(net "SW_P3V3_HPDB_PH")
		)
		(pad "21" smd rect
			(at -0.299974 -1.299972 180)
			(size 0.3048 2.0066)
			(layers "F.Cu" "F.Mask" "F.Paste")
			(net "SW_P3V3_HPDB_FLT")
		)
	)
	(footprint ""
		(layer "F.Cu")
		(at 413.9184 -49.276 90)
		(property "Reference" "R420"
			(at 0 0 90)
			(layer "F.SilkS")
			(hide yes)
			(effects
				(font
					(size 1.27 1.27)
				)
			)
		)
		(property "Value" ""
			(at 0 0 90)
			(layer "F.Fab")
			(effects
				(font
					(size 1.27 1.27)
				)
			)
		)
		(duplicate_pad_numbers_are_jumpers no)
		(fp_line
			(start 0.7874 -0.4064)
			(end 0.7874 0.4064)
			(stroke
				(width 0.1524)
				(type default)
			)
			(layer "F.SilkS")
		)
		(fp_line
			(start -0.7874 -0.4064)
			(end 0.7874 -0.4064)
			(stroke
				(width 0.1524)
				(type default)
			)
			(layer "F.SilkS")
		)
		(fp_line
			(start 0.7874 0.4064)
			(end -0.7874 0.4064)
			(stroke
				(width 0.1524)
				(type default)
			)
			(layer "F.SilkS")
		)
		(fp_line
			(start -0.7874 0.4064)
			(end -0.7874 -0.4064)
			(stroke
				(width 0.1524)
				(type default)
			)
			(layer "F.SilkS")
		)
		(fp_line
			(start -0.12065 -0.305054)
			(end -0.12065 -0.2794)
			(stroke
				(width 0.1)
				(type default)
			)
			(layer "F.Fab")
		)
		(fp_line
			(start -0.67945 -0.305054)
			(end -0.12065 -0.305054)
			(stroke
				(width 0.1)
				(type default)
			)
			(layer "F.Fab")
		)
		(fp_line
			(start 0.67945 -0.3048)
			(end 0.67945 0.3048)
			(stroke
				(width 0.1)
				(type default)
			)
			(layer "F.Fab")
		)
		(fp_line
			(start 0.12065 -0.3048)
			(end 0.67945 -0.3048)
			(stroke
				(width 0.1)
				(type default)
			)
			(layer "F.Fab")
		)
		(fp_line
			(start 0.12065 -0.2794)
			(end 0.12065 -0.3048)
			(stroke
				(width 0.1)
				(type default)
			)
			(layer "F.Fab")
		)
		(fp_line
			(start -0.12065 -0.2794)
			(end 0.12065 -0.2794)
			(stroke
				(width 0.1)
				(type default)
			)
			(layer "F.Fab")
		)
		(fp_line
			(start 0.120396 0.2794)
			(end -0.12065 0.2794)
			(stroke
				(width 0.1)
				(type default)
			)
			(layer "F.Fab")
		)
		(fp_line
			(start -0.12065 0.2794)
			(end -0.12065 0.3048)
			(stroke
				(width 0.1)
				(type default)
			)
			(layer "F.Fab")
		)
		(fp_line
			(start 0.67945 0.3048)
			(end 0.120396 0.3048)
			(stroke
				(width 0.1)
				(type default)
			)
			(layer "F.Fab")
		)
		(fp_line
			(start 0.120396 0.3048)
			(end 0.120396 0.2794)
			(stroke
				(width 0.1)
				(type default)
			)
			(layer "F.Fab")
		)
		(fp_line
			(start -0.12065 0.3048)
			(end -0.67945 0.3048)
			(stroke
				(width 0.1)
				(type default)
			)
			(layer "F.Fab")
		)
		(fp_line
			(start -0.67945 0.3048)
			(end -0.67945 -0.305054)
			(stroke
				(width 0.1)
				(type default)
			)
			(layer "F.Fab")
		)
		(pad "1" smd circle
			(at -0.40005 0 90)
			(size 0 0)
			(layers "F.Cu" "F.Mask" "F.Paste")
			(net "PWRGD_P52V_HS1_4287_PG_N")
		)
		(pad "2" smd circle
			(at 0.40005 0 90)
			(size 0 0)
			(layers "F.Cu" "F.Mask" "F.Paste")
			(net "PWRGD_P52V_HS1_4287_PG_R_N")
		)
	)
	(footprint ""
		(layer "F.Cu")
		(at 47.513494 -18.542)
		(property "Reference" "PR107"
			(at -8.118094 -0.60833 0)
			(unlocked yes)
			(layer "F.SilkS")
			(effects
				(font
					(size 0.7874 0.5842)
					(thickness 0.1524)
				)
				(justify left)
			)
		)
		(property "Value" ""
			(at 0 0 0)
			(layer "F.Fab")
			(effects
				(font
					(size 1.27 1.27)
				)
			)
		)
		(duplicate_pad_numbers_are_jumpers no)
		(fp_line
			(start -3.62712 -1.8796)
			(end -3.62712 1.8796)
			(stroke
				(width 0.1524)
				(type default)
			)
			(layer "F.SilkS")
		)
		(fp_line
			(start -3.62712 1.8796)
			(end 3.62712 1.8796)
			(stroke
				(width 0.1524)
				(type default)
			)
			(layer "F.SilkS")
		)
		(fp_line
			(start 3.62712 -1.8796)
			(end -3.62712 -1.8796)
			(stroke
				(width 0.1524)
				(type default)
			)
			(layer "F.SilkS")
		)
		(fp_line
			(start 3.62712 1.8796)
			(end 3.62712 -1.8796)
			(stroke
				(width 0.1524)
				(type default)
			)
			(layer "F.SilkS")
		)
		(fp_line
			(start -3.299968 -1.700022)
			(end -3.299968 1.700022)
			(stroke
				(width 0.1)
				(type default)
			)
			(layer "F.Fab")
		)
		(fp_line
			(start -3.299968 1.700022)
			(end 3.299968 1.700022)
			(stroke
				(width 0.1)
				(type default)
			)
			(layer "F.Fab")
		)
		(fp_line
			(start 3.299968 -1.700022)
			(end -3.299968 -1.700022)
			(stroke
				(width 0.1)
				(type default)
			)
			(layer "F.Fab")
		)
		(fp_line
			(start 3.299968 1.700022)
			(end 3.299968 -1.700022)
			(stroke
				(width 0.1)
				(type default)
			)
			(layer "F.Fab")
		)
		(pad "1" smd rect
			(at -2.70002 0)
			(size 1.6002 3.5052)
			(layers "F.Cu" "F.Mask" "F.Paste")
			(net "P52V_HS2_EN_DISCHARGE_VBE_R")
		)
		(pad "2" smd rect
			(at 2.70002 0)
			(size 1.6002 3.5052)
			(layers "F.Cu" "F.Mask" "F.Paste")
			(net "GND")
		)
	)
	(footprint ""
		(layer "F.Cu")
		(at 446.151 -50.927)
		(property "Reference" "R5913"
			(at 0 0 0)
			(layer "F.SilkS")
			(hide yes)
			(effects
				(font
					(size 1.27 1.27)
				)
			)
		)
		(property "Value" ""
			(at 0 0 0)
			(layer "F.Fab")
			(effects
				(font
					(size 1.27 1.27)
				)
			)
		)
		(duplicate_pad_numbers_are_jumpers no)
		(fp_line
			(start -0.7874 -0.4064)
			(end 0.7874 -0.4064)
			(stroke
				(width 0.1524)
				(type default)
			)
			(layer "F.SilkS")
		)
		(fp_line
			(start -0.7874 0.4064)
			(end -0.7874 -0.4064)
			(stroke
				(width 0.1524)
				(type default)
			)
			(layer "F.SilkS")
		)
		(fp_line
			(start 0.7874 -0.4064)
			(end 0.7874 0.4064)
			(stroke
				(width 0.1524)
				(type default)
			)
			(layer "F.SilkS")
		)
		(fp_line
			(start 0.7874 0.4064)
			(end -0.7874 0.4064)
			(stroke
				(width 0.1524)
				(type default)
			)
			(layer "F.SilkS")
		)
		(fp_line
			(start -0.67945 -0.305054)
			(end -0.12065 -0.305054)
			(stroke
				(width 0.1)
				(type default)
			)
			(layer "F.Fab")
		)
		(fp_line
			(start -0.67945 0.3048)
			(end -0.67945 -0.305054)
			(stroke
				(width 0.1)
				(type default)
			)
			(layer "F.Fab")
		)
		(fp_line
			(start -0.12065 -0.305054)
			(end -0.12065 -0.2794)
			(stroke
				(width 0.1)
				(type default)
			)
			(layer "F.Fab")
		)
		(fp_line
			(start -0.12065 -0.2794)
			(end 0.12065 -0.2794)
			(stroke
				(width 0.1)
				(type default)
			)
			(layer "F.Fab")
		)
		(fp_line
			(start -0.12065 0.2794)
			(end -0.12065 0.3048)
			(stroke
				(width 0.1)
				(type default)
			)
			(layer "F.Fab")
		)
		(fp_line
			(start -0.12065 0.3048)
			(end -0.67945 0.3048)
			(stroke
				(width 0.1)
				(type default)
			)
			(layer "F.Fab")
		)
		(fp_line
			(start 0.120396 0.2794)
			(end -0.12065 0.2794)
			(stroke
				(width 0.1)
				(type default)
			)
			(layer "F.Fab")
		)
		(fp_line
			(start 0.120396 0.3048)
			(end 0.120396 0.2794)
			(stroke
				(width 0.1)
				(type default)
			)
			(layer "F.Fab")
		)
		(fp_line
			(start 0.12065 -0.3048)
			(end 0.67945 -0.3048)
			(stroke
				(width 0.1)
				(type default)
			)
			(layer "F.Fab")
		)
		(fp_line
			(start 0.12065 -0.2794)
			(end 0.12065 -0.3048)
			(stroke
				(width 0.1)
				(type default)
			)
			(layer "F.Fab")
		)
		(fp_line
			(start 0.67945 -0.3048)
			(end 0.67945 0.3048)
			(stroke
				(width 0.1)
				(type default)
			)
			(layer "F.Fab")
		)
		(fp_line
			(start 0.67945 0.3048)
			(end 0.120396 0.3048)
			(stroke
				(width 0.1)
				(type default)
			)
			(layer "F.Fab")
		)
		(pad "1" smd circle
			(at -0.40005 0)
			(size 0 0)
			(layers "F.Cu" "F.Mask" "F.Paste")
			(net "P3V3_AUX")
		)
		(pad "2" smd circle
			(at 0.40005 0)
			(size 0 0)
			(layers "F.Cu" "F.Mask" "F.Paste")
			(net "PWRGD_P3V3_HPDB_R_N")
		)
	)
	(footprint ""
		(layer "F.Cu")
		(at 124.483876 -18.2626)
		(property "Reference" "PQ43"
			(at 8.913114 -3.609848 0)
			(unlocked yes)
			(layer "F.SilkS")
			(effects
				(font
					(size 0.7874 0.5842)
					(thickness 0.1524)
				)
				(justify left)
			)
		)
		(property "Value" ""
			(at 0 0 0)
			(layer "F.Fab")
			(effects
				(font
					(size 1.27 1.27)
				)
			)
		)
		(duplicate_pad_numbers_are_jumpers no)
		(fp_line
			(start -7.649972 -4.99999)
			(end -7.649972 -3.3274)
			(stroke
				(width 0.1524)
				(type default)
			)
			(layer "F.SilkS")
		)
		(fp_line
			(start -7.649972 -1.7526)
			(end -7.649972 1.7526)
			(stroke
				(width 0.1524)
				(type default)
			)
			(layer "F.SilkS")
		)
		(fp_line
			(start -7.649972 3.3274)
			(end -7.649972 4.99999)
			(stroke
				(width 0.1524)
				(type default)
			)
			(layer "F.SilkS")
		)
		(fp_line
			(start -7.649972 4.99999)
			(end 5.115814 4.99999)
			(stroke
				(width 0.1524)
				(type default)
			)
			(layer "F.SilkS")
		)
		(fp_line
			(start 5.115814 -4.99999)
			(end -7.649972 -4.99999)
			(stroke
				(width 0.1524)
				(type default)
			)
			(layer "F.SilkS")
		)
		(fp_line
			(start 7.630414 4.99999)
			(end 7.649972 4.99999)
			(stroke
				(width 0.1524)
				(type default)
			)
			(layer "F.SilkS")
		)
		(fp_line
			(start 7.649972 -4.99999)
			(end 7.630414 -4.99999)
			(stroke
				(width 0.1524)
				(type default)
			)
			(layer "F.SilkS")
		)
		(fp_line
			(start 7.649972 4.99999)
			(end 7.649972 -4.99999)
			(stroke
				(width 0.1524)
				(type default)
			)
			(layer "F.SilkS")
		)
		(fp_line
			(start -7.649972 -4.99999)
			(end -7.649972 4.99999)
			(stroke
				(width 0.1)
				(type default)
			)
			(layer "F.Fab")
		)
		(fp_line
			(start -7.649972 4.99999)
			(end 7.649972 4.99999)
			(stroke
				(width 0.1)
				(type default)
			)
			(layer "F.Fab")
		)
		(fp_line
			(start 7.649972 -4.99999)
			(end -7.649972 -4.99999)
			(stroke
				(width 0.1)
				(type default)
			)
			(layer "F.Fab")
		)
		(fp_line
			(start 7.649972 4.99999)
			(end 7.649972 -4.99999)
			(stroke
				(width 0.1)
				(type default)
			)
			(layer "F.Fab")
		)
		(pad "D" smd circle
			(at 2.15011 0)
			(size 0 0)
			(layers "F.Cu" "F.Mask" "F.Paste")
			(net "P52V_HS2_DRAIN_2")
		)
		(pad "G" smd rect
			(at -7.050024 -2.54 270)
			(size 1.3208 3.0988)
			(layers "F.Cu" "F.Mask" "F.Paste")
			(net "P52V_HS2_GATE6")
		)
		(pad "S" smd rect
			(at -7.050024 2.54 270)
			(size 1.3208 3.0988)
			(layers "F.Cu" "F.Mask" "F.Paste")
			(net "P52V_HS2")
		)
		(zone
			(layer "F.Cu")
			(hatch none 0.5)
			(connect_pads
				(clearance 0)
			)
			(min_thickness 0.25)
			(keepout
				(tracks not_allowed)
				(vias allowed)
				(pads allowed)
				(copperpour not_allowed)
				(footprints allowed)
			)
			(placement
				(enabled no)
				(sheetname "")
			)
			(fill
				(thermal_gap 0.5)
				(thermal_bridge_width 0.5)
				(island_removal_mode 0)
			)
			(polygon
				(pts
					(xy 129.665476 -23.241) (xy 116.838476 -23.241) (xy 116.838476 -21.5138) (xy 119.048276 -21.5138)
					(xy 119.048276 -20.0914) (xy 116.838476 -20.0914) (xy 116.838476 -16.4338) (xy 119.048276 -16.4338)
					(xy 119.048276 -15.0114) (xy 116.838476 -15.0114) (xy 116.838476 -13.2842) (xy 129.665476 -13.2842)
					(xy 129.665476 -14.4526) (xy 123.467876 -14.4526) (xy 123.467876 -22.0726) (xy 129.665476 -22.0726)
				)
			)
		)
	)
	(footprint ""
		(layer "F.Cu")
		(at 61.92139 -119.38)
		(property "Reference" "PC37"
			(at -8.17499 -4.92633 0)
			(unlocked yes)
			(layer "F.SilkS")
			(effects
				(font
					(size 0.7874 0.5842)
					(thickness 0.1524)
				)
				(justify left)
			)
		)
		(property "Value" ""
			(at 0 0 0)
			(layer "F.Fab")
			(effects
				(font
					(size 1.27 1.27)
				)
			)
		)
		(duplicate_pad_numbers_are_jumpers no)
		(fp_line
			(start -9.253728 3.750056)
			(end 9.249918 3.750056)
			(stroke
				(width 0.1524)
				(type default)
			)
			(layer "F.SilkS")
		)
		(fp_line
			(start 0 3.750056)
			(end -9.253728 3.750056)
			(stroke
				(width 0.1524)
				(type default)
			)
			(layer "F.SilkS")
		)
		(fp_circle
			(center 0 3.750056)
			(end 9.249918 3.750056)
			(stroke
				(width 0.1524)
				(type default)
			)
			(fill no)
			(layer "F.SilkS")
		)
		(fp_poly
			(pts
				(arc
					(start 9.249918 3.750056)
					(mid 0 12.999974)
					(end -9.249918 3.750056)
				)
			)
			(stroke
				(width 0)
				(type default)
			)
			(fill yes)
			(layer "F.SilkS")
		)
		(fp_circle
			(center 0 3.750056)
			(end 9.249918 3.750056)
			(stroke
				(width 0.1)
				(type default)
			)
			(fill no)
			(layer "F.Fab")
		)
		(pad "1" thru_hole rect
			(at 0 0)
			(size 1.778 1.778)
			(drill 1.27)
			(layers "*.Cu" "*.Mask")
			(remove_unused_layers no)
			(net "P52V_HS2")
			(clearance 0)
			(padstack
				(mode front_inner_back)
				(layer "Inner"
					(shape circle)
					(size 1.778 1.778)
					(clearance 0)
				)
				(layer "B.Cu"
					(shape rect)
					(size 1.778 1.778)
					(clearance 0)
				)
			)
		)
		(pad "2" thru_hole circle
			(at 0 7.500112)
			(size 1.778 1.778)
			(drill 1.27)
			(layers "*.Cu" "*.Mask")
			(remove_unused_layers no)
			(net "GND")
			(clearance 0)
		)
	)
	(footprint ""
		(layer "F.Cu")
		(at 381.946912 -17.907254 90)
		(property "Reference" "R72"
			(at 0 0 90)
			(layer "F.SilkS")
			(hide yes)
			(effects
				(font
					(size 1.27 1.27)
				)
			)
		)
		(property "Value" ""
			(at 0 0 90)
			(layer "F.Fab")
			(effects
				(font
					(size 1.27 1.27)
				)
			)
		)
		(duplicate_pad_numbers_are_jumpers no)
		(fp_line
			(start 0.7874 -0.4064)
			(end 0.7874 0.4064)
			(stroke
				(width 0.1524)
				(type default)
			)
			(layer "F.SilkS")
		)
		(fp_line
			(start -0.7874 -0.4064)
			(end 0.7874 -0.4064)
			(stroke
				(width 0.1524)
				(type default)
			)
			(layer "F.SilkS")
		)
		(fp_line
			(start 0.7874 0.4064)
			(end -0.7874 0.4064)
			(stroke
				(width 0.1524)
				(type default)
			)
			(layer "F.SilkS")
		)
		(fp_line
			(start -0.7874 0.4064)
			(end -0.7874 -0.4064)
			(stroke
				(width 0.1524)
				(type default)
			)
			(layer "F.SilkS")
		)
		(fp_line
			(start -0.12065 -0.305054)
			(end -0.12065 -0.2794)
			(stroke
				(width 0.1)
				(type default)
			)
			(layer "F.Fab")
		)
		(fp_line
			(start -0.67945 -0.305054)
			(end -0.12065 -0.305054)
			(stroke
				(width 0.1)
				(type default)
			)
			(layer "F.Fab")
		)
		(fp_line
			(start 0.67945 -0.3048)
			(end 0.67945 0.3048)
			(stroke
				(width 0.1)
				(type default)
			)
			(layer "F.Fab")
		)
		(fp_line
			(start 0.12065 -0.3048)
			(end 0.67945 -0.3048)
			(stroke
				(width 0.1)
				(type default)
			)
			(layer "F.Fab")
		)
		(fp_line
			(start 0.12065 -0.2794)
			(end 0.12065 -0.3048)
			(stroke
				(width 0.1)
				(type default)
			)
			(layer "F.Fab")
		)
		(fp_line
			(start -0.12065 -0.2794)
			(end 0.12065 -0.2794)
			(stroke
				(width 0.1)
				(type default)
			)
			(layer "F.Fab")
		)
		(fp_line
			(start 0.120396 0.2794)
			(end -0.12065 0.2794)
			(stroke
				(width 0.1)
				(type default)
			)
			(layer "F.Fab")
		)
		(fp_line
			(start -0.12065 0.2794)
			(end -0.12065 0.3048)
			(stroke
				(width 0.1)
				(type default)
			)
			(layer "F.Fab")
		)
		(fp_line
			(start 0.67945 0.3048)
			(end 0.120396 0.3048)
			(stroke
				(width 0.1)
				(type default)
			)
			(layer "F.Fab")
		)
		(fp_line
			(start 0.120396 0.3048)
			(end 0.120396 0.2794)
			(stroke
				(width 0.1)
				(type default)
			)
			(layer "F.Fab")
		)
		(fp_line
			(start -0.12065 0.3048)
			(end -0.67945 0.3048)
			(stroke
				(width 0.1)
				(type default)
			)
			(layer "F.Fab")
		)
		(fp_line
			(start -0.67945 0.3048)
			(end -0.67945 -0.305054)
			(stroke
				(width 0.1)
				(type default)
			)
			(layer "F.Fab")
		)
		(pad "1" smd circle
			(at -0.40005 0 90)
			(size 0 0)
			(layers "F.Cu" "F.Mask" "F.Paste")
			(net "FAN_PWR_EN_0_R")
		)
		(pad "2" smd circle
			(at 0.40005 0 90)
			(size 0 0)
			(layers "F.Cu" "F.Mask" "F.Paste")
			(net "FAN_PWR_EN_BUF")
		)
	)
	(footprint ""
		(layer "F.Cu")
		(at 222.6564 -91.948 180)
		(property "Reference" "PR473"
			(at 0 0 180)
			(layer "F.SilkS")
			(hide yes)
			(effects
				(font
					(size 1.27 1.27)
				)
			)
		)
		(property "Value" ""
			(at 0 0 180)
			(layer "F.Fab")
			(effects
				(font
					(size 1.27 1.27)
				)
			)
		)
		(duplicate_pad_numbers_are_jumpers no)
		(fp_line
			(start 0.7874 0.4064)
			(end -0.7874 0.4064)
			(stroke
				(width 0.1524)
				(type default)
			)
			(layer "F.SilkS")
		)
		(fp_line
			(start 0.7874 -0.4064)
			(end 0.7874 0.4064)
			(stroke
				(width 0.1524)
				(type default)
			)
			(layer "F.SilkS")
		)
		(fp_line
			(start -0.7874 0.4064)
			(end -0.7874 -0.4064)
			(stroke
				(width 0.1524)
				(type default)
			)
			(layer "F.SilkS")
		)
		(fp_line
			(start -0.7874 -0.4064)
			(end 0.7874 -0.4064)
			(stroke
				(width 0.1524)
				(type default)
			)
			(layer "F.SilkS")
		)
		(fp_line
			(start 0.67945 0.3048)
			(end 0.120396 0.3048)
			(stroke
				(width 0.1)
				(type default)
			)
			(layer "F.Fab")
		)
		(fp_line
			(start 0.67945 -0.3048)
			(end 0.67945 0.3048)
			(stroke
				(width 0.1)
				(type default)
			)
			(layer "F.Fab")
		)
		(fp_line
			(start 0.12065 -0.2794)
			(end 0.12065 -0.3048)
			(stroke
				(width 0.1)
				(type default)
			)
			(layer "F.Fab")
		)
		(fp_line
			(start 0.12065 -0.3048)
			(end 0.67945 -0.3048)
			(stroke
				(width 0.1)
				(type default)
			)
			(layer "F.Fab")
		)
		(fp_line
			(start 0.120396 0.3048)
			(end 0.120396 0.2794)
			(stroke
				(width 0.1)
				(type default)
			)
			(layer "F.Fab")
		)
		(fp_line
			(start 0.120396 0.2794)
			(end -0.12065 0.2794)
			(stroke
				(width 0.1)
				(type default)
			)
			(layer "F.Fab")
		)
		(fp_line
			(start -0.12065 0.3048)
			(end -0.67945 0.3048)
			(stroke
				(width 0.1)
				(type default)
			)
			(layer "F.Fab")
		)
		(fp_line
			(start -0.12065 0.2794)
			(end -0.12065 0.3048)
			(stroke
				(width 0.1)
				(type default)
			)
			(layer "F.Fab")
		)
		(fp_line
			(start -0.12065 -0.2794)
			(end 0.12065 -0.2794)
			(stroke
				(width 0.1)
				(type default)
			)
			(layer "F.Fab")
		)
		(fp_line
			(start -0.12065 -0.305054)
			(end -0.12065 -0.2794)
			(stroke
				(width 0.1)
				(type default)
			)
			(layer "F.Fab")
		)
		(fp_line
			(start -0.67945 0.3048)
			(end -0.67945 -0.305054)
			(stroke
				(width 0.1)
				(type default)
			)
			(layer "F.Fab")
		)
		(fp_line
			(start -0.67945 -0.305054)
			(end -0.12065 -0.305054)
			(stroke
				(width 0.1)
				(type default)
			)
			(layer "F.Fab")
		)
		(pad "1" smd circle
			(at -0.40005 0 180)
			(size 0 0)
			(layers "F.Cu" "F.Mask" "F.Paste")
			(net "SMB_P52V_PDB_SCL")
		)
		(pad "2" smd circle
			(at 0.40005 0 180)
			(size 0 0)
			(layers "F.Cu" "F.Mask" "F.Paste")
			(net "SMB_P52V_PDB_DEBUG_SCL")
		)
	)
	(footprint ""
		(layer "F.Cu")
		(at 306.7304 -36.1442 180)
		(property "Reference" "PR6965"
			(at 0 0 180)
			(layer "F.SilkS")
			(hide yes)
			(effects
				(font
					(size 1.27 1.27)
				)
			)
		)
		(property "Value" ""
			(at 0 0 180)
			(layer "F.Fab")
			(effects
				(font
					(size 1.27 1.27)
				)
			)
		)
		(duplicate_pad_numbers_are_jumpers no)
		(fp_line
			(start 1.2954 0.5842)
			(end -1.2954 0.5842)
			(stroke
				(width 0.1524)
				(type default)
			)
			(layer "F.SilkS")
		)
		(fp_line
			(start 1.2954 -0.5842)
			(end 1.2954 0.5842)
			(stroke
				(width 0.1524)
				(type default)
			)
			(layer "F.SilkS")
		)
		(fp_line
			(start -1.2954 0.5842)
			(end -1.2954 -0.5842)
			(stroke
				(width 0.1524)
				(type default)
			)
			(layer "F.SilkS")
		)
		(fp_line
			(start -1.2954 -0.5842)
			(end 1.2954 -0.5842)
			(stroke
				(width 0.1524)
				(type default)
			)
			(layer "F.SilkS")
		)
		(fp_line
			(start 1.1938 0.4064)
			(end 0.8636 0.4064)
			(stroke
				(width 0.1)
				(type default)
			)
			(layer "F.Fab")
		)
		(fp_line
			(start 1.1938 -0.406654)
			(end 1.1938 0.4064)
			(stroke
				(width 0.1)
				(type default)
			)
			(layer "F.Fab")
		)
		(fp_line
			(start 0.8636 0.4572)
			(end -0.8636 0.4572)
			(stroke
				(width 0.1)
				(type default)
			)
			(layer "F.Fab")
		)
		(fp_line
			(start 0.8636 0.4064)
			(end 0.8636 0.4572)
			(stroke
				(width 0.1)
				(type default)
			)
			(layer "F.Fab")
		)
		(fp_line
			(start 0.8636 -0.406654)
			(end 1.1938 -0.406654)
			(stroke
				(width 0.1)
				(type default)
			)
			(layer "F.Fab")
		)
		(fp_line
			(start 0.8636 -0.4572)
			(end 0.8636 -0.406654)
			(stroke
				(width 0.1)
				(type default)
			)
			(layer "F.Fab")
		)
		(fp_line
			(start -0.8636 0.4572)
			(end -0.8636 0.4318)
			(stroke
				(width 0.1)
				(type default)
			)
			(layer "F.Fab")
		)
		(fp_line
			(start -0.8636 0.4318)
			(end -0.8636 0.4064)
			(stroke
				(width 0.1)
				(type default)
			)
			(layer "F.Fab")
		)
		(fp_line
			(start -0.8636 0.4064)
			(end -1.1938 0.4064)
			(stroke
				(width 0.1)
				(type default)
			)
			(layer "F.Fab")
		)
		(fp_line
			(start -0.8636 -0.406654)
			(end -0.8636 -0.4572)
			(stroke
				(width 0.1)
				(type default)
			)
			(layer "F.Fab")
		)
		(fp_line
			(start -0.8636 -0.4572)
			(end 0.8636 -0.4572)
			(stroke
				(width 0.1)
				(type default)
			)
			(layer "F.Fab")
		)
		(fp_line
			(start -1.1938 0.4064)
			(end -1.1938 -0.406654)
			(stroke
				(width 0.1)
				(type default)
			)
			(layer "F.Fab")
		)
		(fp_line
			(start -1.1938 -0.406654)
			(end -0.8636 -0.406654)
			(stroke
				(width 0.1)
				(type default)
			)
			(layer "F.Fab")
		)
		(pad "1" smd rect
			(at -0.7366 0 90)
			(size 0.7112 0.8128)
			(layers "F.Cu" "F.Mask" "F.Paste")
			(net "P52V_HS1_SENSE_N_R2")
		)
		(pad "2" smd rect
			(at 0.7366 0 90)
			(size 0.7112 0.8128)
			(layers "F.Cu" "F.Mask" "F.Paste")
			(net "P52V_HS_4287_ADC_N")
		)
	)
	(footprint ""
		(layer "F.Cu")
		(at 438.023 -46.609 180)
		(property "Reference" "R387"
			(at 0 0 180)
			(layer "F.SilkS")
			(hide yes)
			(effects
				(font
					(size 1.27 1.27)
				)
			)
		)
		(property "Value" ""
			(at 0 0 180)
			(layer "F.Fab")
			(effects
				(font
					(size 1.27 1.27)
				)
			)
		)
		(duplicate_pad_numbers_are_jumpers no)
		(fp_line
			(start 0.7874 0.4064)
			(end -0.7874 0.4064)
			(stroke
				(width 0.1524)
				(type default)
			)
			(layer "F.SilkS")
		)
		(fp_line
			(start 0.7874 -0.4064)
			(end 0.7874 0.4064)
			(stroke
				(width 0.1524)
				(type default)
			)
			(layer "F.SilkS")
		)
		(fp_line
			(start -0.7874 0.4064)
			(end -0.7874 -0.4064)
			(stroke
				(width 0.1524)
				(type default)
			)
			(layer "F.SilkS")
		)
		(fp_line
			(start -0.7874 -0.4064)
			(end 0.7874 -0.4064)
			(stroke
				(width 0.1524)
				(type default)
			)
			(layer "F.SilkS")
		)
		(fp_line
			(start 0.67945 0.3048)
			(end 0.120396 0.3048)
			(stroke
				(width 0.1)
				(type default)
			)
			(layer "F.Fab")
		)
		(fp_line
			(start 0.67945 -0.3048)
			(end 0.67945 0.3048)
			(stroke
				(width 0.1)
				(type default)
			)
			(layer "F.Fab")
		)
		(fp_line
			(start 0.12065 -0.2794)
			(end 0.12065 -0.3048)
			(stroke
				(width 0.1)
				(type default)
			)
			(layer "F.Fab")
		)
		(fp_line
			(start 0.12065 -0.3048)
			(end 0.67945 -0.3048)
			(stroke
				(width 0.1)
				(type default)
			)
			(layer "F.Fab")
		)
		(fp_line
			(start 0.120396 0.3048)
			(end 0.120396 0.2794)
			(stroke
				(width 0.1)
				(type default)
			)
			(layer "F.Fab")
		)
		(fp_line
			(start 0.120396 0.2794)
			(end -0.12065 0.2794)
			(stroke
				(width 0.1)
				(type default)
			)
			(layer "F.Fab")
		)
		(fp_line
			(start -0.12065 0.3048)
			(end -0.67945 0.3048)
			(stroke
				(width 0.1)
				(type default)
			)
			(layer "F.Fab")
		)
		(fp_line
			(start -0.12065 0.2794)
			(end -0.12065 0.3048)
			(stroke
				(width 0.1)
				(type default)
			)
			(layer "F.Fab")
		)
		(fp_line
			(start -0.12065 -0.2794)
			(end 0.12065 -0.2794)
			(stroke
				(width 0.1)
				(type default)
			)
			(layer "F.Fab")
		)
		(fp_line
			(start -0.12065 -0.305054)
			(end -0.12065 -0.2794)
			(stroke
				(width 0.1)
				(type default)
			)
			(layer "F.Fab")
		)
		(fp_line
			(start -0.67945 0.3048)
			(end -0.67945 -0.305054)
			(stroke
				(width 0.1)
				(type default)
			)
			(layer "F.Fab")
		)
		(fp_line
			(start -0.67945 -0.305054)
			(end -0.12065 -0.305054)
			(stroke
				(width 0.1)
				(type default)
			)
			(layer "F.Fab")
		)
		(pad "1" smd circle
			(at -0.40005 0 180)
			(size 0 0)
			(layers "F.Cu" "F.Mask" "F.Paste")
			(net "GND")
		)
		(pad "2" smd circle
			(at 0.40005 0 180)
			(size 0 0)
			(layers "F.Cu" "F.Mask" "F.Paste")
			(net "PWRGD_P3V3_AUX_MB_BUF")
		)
	)
	(footprint ""
		(layer "F.Cu")
		(at 424.999912 -60.099956)
		(property "Reference" "H24"
			(at -1.048512 -8.961374 0)
			(unlocked yes)
			(layer "F.SilkS")
			(effects
				(font
					(size 0.7874 0.5842)
					(thickness 0.1524)
				)
				(justify left)
			)
		)
		(property "Value" ""
			(at 0 0 0)
			(layer "F.Fab")
			(effects
				(font
					(size 1.27 1.27)
				)
			)
		)
		(duplicate_pad_numbers_are_jumpers no)
		(fp_arc
			(start -7.611618 2.462276)
			(mid -1.24637 -7.902332)
			(end 7.999984 0)
			(stroke
				(width 0.1524)
				(type default)
			)
			(layer "F.SilkS")
		)
		(fp_arc
			(start 7.999984 0)
			(mid 2.498026 7.599939)
			(end -6.439916 4.746244)
			(stroke
				(width 0.1524)
				(type default)
			)
			(layer "F.SilkS")
		)
		(fp_circle
			(center 0 0)
			(end 7.999984 0)
			(stroke
				(width 0.1524)
				(type default)
			)
			(fill no)
			(layer "B.SilkS")
		)
		(fp_circle
			(center 0 0)
			(end 7.999984 0)
			(stroke
				(width 0.1)
				(type default)
			)
			(fill no)
			(layer "B.Fab")
		)
		(fp_circle
			(center 0 0)
			(end 7.999984 0)
			(stroke
				(width 0.1)
				(type default)
			)
			(fill no)
			(layer "F.Fab")
		)
		(pad "" np_thru_hole circle
			(at 0 0)
			(size 4.0132 4.0132)
			(drill 4.0132)
			(layers "*.Cu" "*.Mask")
			(clearance 0.381)
			(thermal_gap 0.381)
		)
		(pad "2" thru_hole circle
			(at 0 -3.50012)
			(size 0.762 0.762)
			(drill 0.5588)
			(layers "*.Cu" "*.Mask")
			(remove_unused_layers no)
			(net "GND")
			(clearance 0.1524)
			(thermal_gap 0.1524)
		)
		(pad "3" thru_hole circle
			(at -2.500122 -2.500122)
			(size 0.762 0.762)
			(drill 0.5588)
			(layers "*.Cu" "*.Mask")
			(remove_unused_layers no)
			(net "GND")
			(clearance 0.1524)
			(thermal_gap 0.1524)
		)
		(pad "4" thru_hole circle
			(at -3.50012 0)
			(size 0.762 0.762)
			(drill 0.5588)
			(layers "*.Cu" "*.Mask")
			(remove_unused_layers no)
			(net "GND")
			(clearance 0.1524)
			(thermal_gap 0.1524)
		)
		(pad "5" thru_hole circle
			(at -2.500122 2.500122)
			(size 0.762 0.762)
			(drill 0.5588)
			(layers "*.Cu" "*.Mask")
			(remove_unused_layers no)
			(net "GND")
			(clearance 0.1524)
			(thermal_gap 0.1524)
		)
		(pad "6" thru_hole circle
			(at 0 3.50012)
			(size 0.762 0.762)
			(drill 0.5588)
			(layers "*.Cu" "*.Mask")
			(remove_unused_layers no)
			(net "GND")
			(clearance 0.1524)
			(thermal_gap 0.1524)
		)
		(pad "7" thru_hole circle
			(at 2.500122 2.500122)
			(size 0.762 0.762)
			(drill 0.5588)
			(layers "*.Cu" "*.Mask")
			(remove_unused_layers no)
			(net "GND")
			(clearance 0.1524)
			(thermal_gap 0.1524)
		)
		(pad "8" thru_hole circle
			(at 3.50012 0)
			(size 0.762 0.762)
			(drill 0.5588)
			(layers "*.Cu" "*.Mask")
			(remove_unused_layers no)
			(net "GND")
			(clearance 0.1524)
			(thermal_gap 0.1524)
		)
		(pad "9" thru_hole circle
			(at 2.500122 -2.500122)
			(size 0.762 0.762)
			(drill 0.5588)
			(layers "*.Cu" "*.Mask")
			(remove_unused_layers no)
			(net "GND")
			(clearance 0.1524)
			(thermal_gap 0.1524)
		)
		(zone
			(layers "F.Cu" "B.Cu" "In1.Cu" "In2.Cu" "In3.Cu" "In4.Cu" "In5.Cu" "In6.Cu"
				"In7.Cu" "In8.Cu"
			)
			(hatch none 0.5)
			(connect_pads
				(clearance 0)
			)
			(min_thickness 0.25)
			(keepout
				(tracks not_allowed)
				(vias allowed)
				(pads allowed)
				(copperpour not_allowed)
				(footprints allowed)
			)
			(placement
				(enabled no)
				(sheetname "")
			)
			(fill
				(thermal_gap 0.5)
				(thermal_bridge_width 0.5)
				(island_removal_mode 0)
			)
			(polygon
				(pts
					(arc
						(start 427.514512 -60.099956)
						(mid 422.485312 -60.099956)
						(end 427.514512 -60.099956)
					)
				)
			)
		)
	)
	(footprint ""
		(layer "F.Cu")
		(at 419.87216 -26.00452)
		(property "Reference" "C96"
			(at 0 0 0)
			(layer "F.SilkS")
			(hide yes)
			(effects
				(font
					(size 1.27 1.27)
				)
			)
		)
		(property "Value" ""
			(at 0 0 0)
			(layer "F.Fab")
			(effects
				(font
					(size 1.27 1.27)
				)
			)
		)
		(duplicate_pad_numbers_are_jumpers no)
		(fp_line
			(start -0.7874 -0.4064)
			(end 0.7874 -0.4064)
			(stroke
				(width 0.1524)
				(type default)
			)
			(layer "F.SilkS")
		)
		(fp_line
			(start -0.7874 0.4064)
			(end -0.7874 -0.4064)
			(stroke
				(width 0.1524)
				(type default)
			)
			(layer "F.SilkS")
		)
		(fp_line
			(start 0.7874 -0.4064)
			(end 0.7874 0.4064)
			(stroke
				(width 0.1524)
				(type default)
			)
			(layer "F.SilkS")
		)
		(fp_line
			(start 0.7874 0.4064)
			(end -0.7874 0.4064)
			(stroke
				(width 0.1524)
				(type default)
			)
			(layer "F.SilkS")
		)
		(fp_line
			(start -0.6858 -0.3048)
			(end -0.1016 -0.3048)
			(stroke
				(width 0.1)
				(type default)
			)
			(layer "F.Fab")
		)
		(fp_line
			(start -0.6858 0.3048)
			(end -0.6858 -0.3048)
			(stroke
				(width 0.1)
				(type default)
			)
			(layer "F.Fab")
		)
		(fp_line
			(start -0.1016 -0.3048)
			(end -0.1016 -0.2794)
			(stroke
				(width 0.1)
				(type default)
			)
			(layer "F.Fab")
		)
		(fp_line
			(start -0.1016 -0.2794)
			(end 0.1016 -0.2794)
			(stroke
				(width 0.1)
				(type default)
			)
			(layer "F.Fab")
		)
		(fp_line
			(start -0.1016 0.2794)
			(end -0.1016 0.3048)
			(stroke
				(width 0.1)
				(type default)
			)
			(layer "F.Fab")
		)
		(fp_line
			(start -0.1016 0.3048)
			(end -0.6858 0.3048)
			(stroke
				(width 0.1)
				(type default)
			)
			(layer "F.Fab")
		)
		(fp_line
			(start 0.1016 -0.3048)
			(end 0.6858 -0.3048)
			(stroke
				(width 0.1)
				(type default)
			)
			(layer "F.Fab")
		)
		(fp_line
			(start 0.1016 -0.2794)
			(end 0.1016 -0.3048)
			(stroke
				(width 0.1)
				(type default)
			)
			(layer "F.Fab")
		)
		(fp_line
			(start 0.1016 0.2794)
			(end -0.1016 0.2794)
			(stroke
				(width 0.1)
				(type default)
			)
			(layer "F.Fab")
		)
		(fp_line
			(start 0.1016 0.3048)
			(end 0.1016 0.2794)
			(stroke
				(width 0.1)
				(type default)
			)
			(layer "F.Fab")
		)
		(fp_line
			(start 0.6858 -0.3048)
			(end 0.6858 0.3048)
			(stroke
				(width 0.1)
				(type default)
			)
			(layer "F.Fab")
		)
		(fp_line
			(start 0.6858 0.3048)
			(end 0.1016 0.3048)
			(stroke
				(width 0.1)
				(type default)
			)
			(layer "F.Fab")
		)
		(pad "1" smd rect
			(at -0.40005 0 180)
			(size 0.4572 0.508)
			(layers "F.Cu" "F.Mask" "F.Paste")
			(net "P12V_FAN_LED")
		)
		(pad "2" smd rect
			(at 0.40005 0 180)
			(size 0.4572 0.508)
			(layers "F.Cu" "F.Mask" "F.Paste")
			(net "GND")
		)
	)
	(footprint ""
		(layer "F.Cu")
		(at 145.11782 -36.1442)
		(property "Reference" "PR6991"
			(at 0 0 0)
			(layer "F.SilkS")
			(hide yes)
			(effects
				(font
					(size 1.27 1.27)
				)
			)
		)
		(property "Value" ""
			(at 0 0 0)
			(layer "F.Fab")
			(effects
				(font
					(size 1.27 1.27)
				)
			)
		)
		(duplicate_pad_numbers_are_jumpers no)
		(fp_line
			(start -1.2954 -0.5842)
			(end 1.2954 -0.5842)
			(stroke
				(width 0.1524)
				(type default)
			)
			(layer "F.SilkS")
		)
		(fp_line
			(start -1.2954 0.5842)
			(end -1.2954 -0.5842)
			(stroke
				(width 0.1524)
				(type default)
			)
			(layer "F.SilkS")
		)
		(fp_line
			(start 1.2954 -0.5842)
			(end 1.2954 0.5842)
			(stroke
				(width 0.1524)
				(type default)
			)
			(layer "F.SilkS")
		)
		(fp_line
			(start 1.2954 0.5842)
			(end -1.2954 0.5842)
			(stroke
				(width 0.1524)
				(type default)
			)
			(layer "F.SilkS")
		)
		(fp_line
			(start -1.1938 -0.406654)
			(end -0.8636 -0.406654)
			(stroke
				(width 0.1)
				(type default)
			)
			(layer "F.Fab")
		)
		(fp_line
			(start -1.1938 0.4064)
			(end -1.1938 -0.406654)
			(stroke
				(width 0.1)
				(type default)
			)
			(layer "F.Fab")
		)
		(fp_line
			(start -0.8636 -0.4572)
			(end 0.8636 -0.4572)
			(stroke
				(width 0.1)
				(type default)
			)
			(layer "F.Fab")
		)
		(fp_line
			(start -0.8636 -0.406654)
			(end -0.8636 -0.4572)
			(stroke
				(width 0.1)
				(type default)
			)
			(layer "F.Fab")
		)
		(fp_line
			(start -0.8636 0.4064)
			(end -1.1938 0.4064)
			(stroke
				(width 0.1)
				(type default)
			)
			(layer "F.Fab")
		)
		(fp_line
			(start -0.8636 0.4318)
			(end -0.8636 0.4064)
			(stroke
				(width 0.1)
				(type default)
			)
			(layer "F.Fab")
		)
		(fp_line
			(start -0.8636 0.4572)
			(end -0.8636 0.4318)
			(stroke
				(width 0.1)
				(type default)
			)
			(layer "F.Fab")
		)
		(fp_line
			(start 0.8636 -0.4572)
			(end 0.8636 -0.406654)
			(stroke
				(width 0.1)
				(type default)
			)
			(layer "F.Fab")
		)
		(fp_line
			(start 0.8636 -0.406654)
			(end 1.1938 -0.406654)
			(stroke
				(width 0.1)
				(type default)
			)
			(layer "F.Fab")
		)
		(fp_line
			(start 0.8636 0.4064)
			(end 0.8636 0.4572)
			(stroke
				(width 0.1)
				(type default)
			)
			(layer "F.Fab")
		)
		(fp_line
			(start 0.8636 0.4572)
			(end -0.8636 0.4572)
			(stroke
				(width 0.1)
				(type default)
			)
			(layer "F.Fab")
		)
		(fp_line
			(start 1.1938 -0.406654)
			(end 1.1938 0.4064)
			(stroke
				(width 0.1)
				(type default)
			)
			(layer "F.Fab")
		)
		(fp_line
			(start 1.1938 0.4064)
			(end 0.8636 0.4064)
			(stroke
				(width 0.1)
				(type default)
			)
			(layer "F.Fab")
		)
		(pad "1" smd rect
			(at -0.7366 0 270)
			(size 0.7112 0.8128)
			(layers "F.Cu" "F.Mask" "F.Paste")
			(net "P52V_HS2_1272_S_P")
		)
		(pad "2" smd rect
			(at 0.7366 0 270)
			(size 0.7112 0.8128)
			(layers "F.Cu" "F.Mask" "F.Paste")
			(net "P52V_HS2_SENSE_P_R2")
		)
	)
	(footprint ""
		(layer "F.Cu")
		(at 398.375124 -168.82999)
		(property "Reference" "JP1"
			(at 3.960876 21.91766 0)
			(unlocked yes)
			(layer "F.SilkS")
			(effects
				(font
					(size 0.7874 0.5842)
					(thickness 0.1524)
				)
			)
		)
		(property "Value" ""
			(at 0 0 0)
			(layer "F.Fab")
			(effects
				(font
					(size 1.27 1.27)
				)
			)
		)
		(duplicate_pad_numbers_are_jumpers no)
		(fp_line
			(start -6.374892 -18.699988)
			(end 13.124942 -18.699988)
			(stroke
				(width 0.1524)
				(type default)
			)
			(layer "F.SilkS")
		)
		(fp_line
			(start -6.374892 20.999958)
			(end -6.374892 -18.699988)
			(stroke
				(width 0.1524)
				(type default)
			)
			(layer "F.SilkS")
		)
		(fp_line
			(start -3.374898 -15.699994)
			(end 10.124948 -15.699994)
			(stroke
				(width 0.1524)
				(type default)
			)
			(layer "F.SilkS")
		)
		(fp_line
			(start -3.374898 -6.500114)
			(end 10.124948 -6.500114)
			(stroke
				(width 0.1524)
				(type default)
			)
			(layer "F.SilkS")
		)
		(fp_line
			(start -3.374898 17.999964)
			(end -3.374898 -15.699994)
			(stroke
				(width 0.1524)
				(type default)
			)
			(layer "F.SilkS")
		)
		(fp_line
			(start 10.124948 -15.699994)
			(end 10.124948 17.999964)
			(stroke
				(width 0.1524)
				(type default)
			)
			(layer "F.SilkS")
		)
		(fp_line
			(start 10.124948 17.999964)
			(end -3.374898 17.999964)
			(stroke
				(width 0.1524)
				(type default)
			)
			(layer "F.SilkS")
		)
		(fp_line
			(start 13.124942 -18.699988)
			(end 13.124942 20.999958)
			(stroke
				(width 0.1524)
				(type default)
			)
			(layer "F.SilkS")
		)
		(fp_line
			(start 13.124942 20.999958)
			(end -6.374892 20.999958)
			(stroke
				(width 0.1524)
				(type default)
			)
			(layer "F.SilkS")
		)
		(fp_poly
			(pts
				(xy 0.451866 -2.025142) (xy -0.564134 -2.025142) (xy -0.056134 -1.009142)
			)
			(stroke
				(width 0)
				(type default)
			)
			(fill yes)
			(layer "F.SilkS")
		)
		(fp_line
			(start -6.374892 -18.699988)
			(end 13.124942 -18.699988)
			(stroke
				(width 0.1524)
				(type default)
			)
			(layer "B.SilkS")
		)
		(fp_line
			(start -6.374892 20.999958)
			(end -6.374892 -18.699988)
			(stroke
				(width 0.1524)
				(type default)
			)
			(layer "B.SilkS")
		)
		(fp_line
			(start 13.124942 -18.699988)
			(end 13.124942 20.999958)
			(stroke
				(width 0.1524)
				(type default)
			)
			(layer "B.SilkS")
		)
		(fp_line
			(start 13.124942 20.999958)
			(end -6.374892 20.999958)
			(stroke
				(width 0.1524)
				(type default)
			)
			(layer "B.SilkS")
		)
		(fp_line
			(start -6.374892 -18.699988)
			(end 13.124942 -18.699988)
			(stroke
				(width 0.1)
				(type default)
			)
			(layer "B.Fab")
		)
		(fp_line
			(start -6.374892 20.999958)
			(end -6.374892 -18.699988)
			(stroke
				(width 0.1)
				(type default)
			)
			(layer "B.Fab")
		)
		(fp_line
			(start 13.124942 -18.699988)
			(end 13.124942 20.999958)
			(stroke
				(width 0.1)
				(type default)
			)
			(layer "B.Fab")
		)
		(fp_line
			(start 13.124942 20.999958)
			(end -6.374892 20.999958)
			(stroke
				(width 0.1)
				(type default)
			)
			(layer "B.Fab")
		)
		(fp_line
			(start -3.374898 -15.699994)
			(end 10.124948 -15.699994)
			(stroke
				(width 0.1)
				(type default)
			)
			(layer "F.Fab")
		)
		(fp_line
			(start -3.374898 17.999964)
			(end -3.374898 -15.699994)
			(stroke
				(width 0.1)
				(type default)
			)
			(layer "F.Fab")
		)
		(fp_line
			(start 10.124948 -15.699994)
			(end 10.124948 17.999964)
			(stroke
				(width 0.1)
				(type default)
			)
			(layer "F.Fab")
		)
		(fp_line
			(start 10.124948 17.999964)
			(end -3.374898 17.999964)
			(stroke
				(width 0.1)
				(type default)
			)
			(layer "F.Fab")
		)
		(fp_poly
			(pts
				(xy -4.842256 -0.508) (xy -4.842256 0.508) (xy -3.826256 0)
			)
			(stroke
				(width 0)
				(type default)
			)
			(fill yes)
			(layer "F.Fab")
		)
		(fp_text user "PRESS-FIT"
			(at -0.865124 19.66849 0)
			(unlocked yes)
			(layer "F.SilkS")
			(effects
				(font
					(size 1.27 0.9652)
					(thickness 0.1524)
				)
				(justify left)
			)
		)
		(fp_text user "PRESS-FIT"
			(at 8.653526 16.68399 270)
			(unlocked yes)
			(layer "B.SilkS")
			(effects
				(font
					(size 1.905 1.4224)
					(thickness 0.1524)
				)
				(justify left mirror)
			)
		)
		(fp_text user "PRESS-FIT"
			(at 11.811 19.94535 0)
			(unlocked yes)
			(layer "B.Fab")
			(effects
				(font
					(size 1.905 1.4224)
					(thickness 0.1524)
				)
				(justify left mirror)
			)
		)
		(fp_text user "PRESS-FIT"
			(at -4.8768 19.94535 0)
			(unlocked yes)
			(layer "F.Fab")
			(effects
				(font
					(size 1.905 1.4224)
					(thickness 0.1524)
				)
				(justify left)
			)
		)
		(pad "P1_1" thru_hole rect
			(at 0 0)
			(size 1.156208 1.156208)
			(drill 0.749808)
			(layers "*.Cu" "*.Mask")
			(remove_unused_layers no)
			(net "P52V_HS1")
			(clearance 0.0508)
			(thermal_gap 0.0508)
			(padstack
				(mode front_inner_back)
				(layer "Inner"
					(shape circle)
					(size 1.156208 1.156208)
					(clearance 0.0508)
				)
				(layer "B.Cu"
					(shape rect)
					(size 1.156208 1.156208)
					(clearance 0.0508)
				)
			)
		)
		(pad "P1_2" thru_hole circle
			(at 0 1.999996)
			(size 1.156208 1.156208)
			(drill 0.749808)
			(layers "*.Cu" "*.Mask")
			(remove_unused_layers no)
			(net "P52V_HS1")
			(clearance 0.0508)
			(thermal_gap 0.0508)
		)
		(pad "P1_3" thru_hole circle
			(at 0 3.999992)
			(size 1.156208 1.156208)
			(drill 0.749808)
			(layers "*.Cu" "*.Mask")
			(remove_unused_layers no)
			(net "P52V_HS1")
			(clearance 0.0508)
			(thermal_gap 0.0508)
		)
		(pad "P1_4" thru_hole circle
			(at 0 5.999988)
			(size 1.156208 1.156208)
			(drill 0.749808)
			(layers "*.Cu" "*.Mask")
			(remove_unused_layers no)
			(net "P52V_HS1")
			(clearance 0.0508)
			(thermal_gap 0.0508)
		)
		(pad "P1_5" thru_hole circle
			(at 0 7.999984)
			(size 1.156208 1.156208)
			(drill 0.749808)
			(layers "*.Cu" "*.Mask")
			(remove_unused_layers no)
			(net "P52V_HS1")
			(clearance 0.0508)
			(thermal_gap 0.0508)
		)
		(pad "P1_6" thru_hole circle
			(at 0 9.99998)
			(size 1.156208 1.156208)
			(drill 0.749808)
			(layers "*.Cu" "*.Mask")
			(remove_unused_layers no)
			(net "P52V_HS1")
			(clearance 0.0508)
			(thermal_gap 0.0508)
		)
		(pad "P1_7" thru_hole circle
			(at 0 11.999976)
			(size 1.156208 1.156208)
			(drill 0.749808)
			(layers "*.Cu" "*.Mask")
			(remove_unused_layers no)
			(net "P52V_HS1")
			(clearance 0.0508)
			(thermal_gap 0.0508)
		)
		(pad "P1_8" thru_hole circle
			(at 0 13.999972)
			(size 1.156208 1.156208)
			(drill 0.749808)
			(layers "*.Cu" "*.Mask")
			(remove_unused_layers no)
			(net "P52V_HS1")
			(clearance 0.0508)
			(thermal_gap 0.0508)
		)
		(pad "P1_9" thru_hole circle
			(at 0 15.999968)
			(size 1.156208 1.156208)
			(drill 0.749808)
			(layers "*.Cu" "*.Mask")
			(remove_unused_layers no)
			(net "P52V_HS1")
			(clearance 0.0508)
			(thermal_gap 0.0508)
		)
		(pad "P1_10" thru_hole circle
			(at 1.999996 0)
			(size 1.156208 1.156208)
			(drill 0.749808)
			(layers "*.Cu" "*.Mask")
			(remove_unused_layers no)
			(net "P52V_HS1")
			(clearance 0.0508)
			(thermal_gap 0.0508)
		)
		(pad "P1_11" thru_hole circle
			(at 1.999996 1.999996)
			(size 1.156208 1.156208)
			(drill 0.749808)
			(layers "*.Cu" "*.Mask")
			(remove_unused_layers no)
			(net "P52V_HS1")
			(clearance 0.0508)
			(thermal_gap 0.0508)
		)
		(pad "P1_12" thru_hole circle
			(at 1.999996 3.999992)
			(size 1.156208 1.156208)
			(drill 0.749808)
			(layers "*.Cu" "*.Mask")
			(remove_unused_layers no)
			(net "P52V_HS1")
			(clearance 0.0508)
			(thermal_gap 0.0508)
		)
		(pad "P1_13" thru_hole circle
			(at 1.999996 5.999988)
			(size 1.156208 1.156208)
			(drill 0.749808)
			(layers "*.Cu" "*.Mask")
			(remove_unused_layers no)
			(net "P52V_HS1")
			(clearance 0.0508)
			(thermal_gap 0.0508)
		)
		(pad "P1_14" thru_hole circle
			(at 1.999996 7.999984)
			(size 1.156208 1.156208)
			(drill 0.749808)
			(layers "*.Cu" "*.Mask")
			(remove_unused_layers no)
			(net "P52V_HS1")
			(clearance 0.0508)
			(thermal_gap 0.0508)
		)
		(pad "P1_15" thru_hole circle
			(at 1.999996 9.99998)
			(size 1.156208 1.156208)
			(drill 0.749808)
			(layers "*.Cu" "*.Mask")
			(remove_unused_layers no)
			(net "P52V_HS1")
			(clearance 0.0508)
			(thermal_gap 0.0508)
		)
		(pad "P1_16" thru_hole circle
			(at 1.999996 11.999976)
			(size 1.156208 1.156208)
			(drill 0.749808)
			(layers "*.Cu" "*.Mask")
			(remove_unused_layers no)
			(net "P52V_HS1")
			(clearance 0.0508)
			(thermal_gap 0.0508)
		)
		(pad "P1_17" thru_hole circle
			(at 1.999996 13.999972)
			(size 1.156208 1.156208)
			(drill 0.749808)
			(layers "*.Cu" "*.Mask")
			(remove_unused_layers no)
			(net "P52V_HS1")
			(clearance 0.0508)
			(thermal_gap 0.0508)
		)
		(pad "P1_18" thru_hole circle
			(at 1.999996 15.999968)
			(size 1.156208 1.156208)
			(drill 0.749808)
			(layers "*.Cu" "*.Mask")
			(remove_unused_layers no)
			(net "P52V_HS1")
			(clearance 0.0508)
			(thermal_gap 0.0508)
		)
		(pad "P2_1" thru_hole circle
			(at 4.750054 0)
			(size 1.156208 1.156208)
			(drill 0.749808)
			(layers "*.Cu" "*.Mask")
			(remove_unused_layers no)
			(net "GND")
			(clearance 0.0508)
			(thermal_gap 0.0508)
		)
		(pad "P2_2" thru_hole circle
			(at 4.750054 1.999996)
			(size 1.156208 1.156208)
			(drill 0.749808)
			(layers "*.Cu" "*.Mask")
			(remove_unused_layers no)
			(net "GND")
			(clearance 0.0508)
			(thermal_gap 0.0508)
		)
		(pad "P2_3" thru_hole circle
			(at 4.750054 3.999992)
			(size 1.156208 1.156208)
			(drill 0.749808)
			(layers "*.Cu" "*.Mask")
			(remove_unused_layers no)
			(net "GND")
			(clearance 0.0508)
			(thermal_gap 0.0508)
		)
		(pad "P2_4" thru_hole circle
			(at 4.750054 5.999988)
			(size 1.156208 1.156208)
			(drill 0.749808)
			(layers "*.Cu" "*.Mask")
			(remove_unused_layers no)
			(net "GND")
			(clearance 0.0508)
			(thermal_gap 0.0508)
		)
		(pad "P2_5" thru_hole circle
			(at 4.750054 7.999984)
			(size 1.156208 1.156208)
			(drill 0.749808)
			(layers "*.Cu" "*.Mask")
			(remove_unused_layers no)
			(net "GND")
			(clearance 0.0508)
			(thermal_gap 0.0508)
		)
		(pad "P2_6" thru_hole circle
			(at 4.750054 9.99998)
			(size 1.156208 1.156208)
			(drill 0.749808)
			(layers "*.Cu" "*.Mask")
			(remove_unused_layers no)
			(net "GND")
			(clearance 0.0508)
			(thermal_gap 0.0508)
		)
		(pad "P2_7" thru_hole circle
			(at 4.750054 11.999976)
			(size 1.156208 1.156208)
			(drill 0.749808)
			(layers "*.Cu" "*.Mask")
			(remove_unused_layers no)
			(net "GND")
			(clearance 0.0508)
			(thermal_gap 0.0508)
		)
		(pad "P2_8" thru_hole circle
			(at 4.750054 13.999972)
			(size 1.156208 1.156208)
			(drill 0.749808)
			(layers "*.Cu" "*.Mask")
			(remove_unused_layers no)
			(net "GND")
			(clearance 0.0508)
			(thermal_gap 0.0508)
		)
		(pad "P2_9" thru_hole circle
			(at 4.750054 15.999968)
			(size 1.156208 1.156208)
			(drill 0.749808)
			(layers "*.Cu" "*.Mask")
			(remove_unused_layers no)
			(net "GND")
			(clearance 0.0508)
			(thermal_gap 0.0508)
		)
		(pad "P2_10" thru_hole circle
			(at 6.75005 0)
			(size 1.156208 1.156208)
			(drill 0.749808)
			(layers "*.Cu" "*.Mask")
			(remove_unused_layers no)
			(net "GND")
			(clearance 0.0508)
			(thermal_gap 0.0508)
		)
		(pad "P2_11" thru_hole circle
			(at 6.75005 1.999996)
			(size 1.156208 1.156208)
			(drill 0.749808)
			(layers "*.Cu" "*.Mask")
			(remove_unused_layers no)
			(net "GND")
			(clearance 0.0508)
			(thermal_gap 0.0508)
		)
		(pad "P2_12" thru_hole circle
			(at 6.75005 3.999992)
			(size 1.156208 1.156208)
			(drill 0.749808)
			(layers "*.Cu" "*.Mask")
			(remove_unused_layers no)
			(net "GND")
			(clearance 0.0508)
			(thermal_gap 0.0508)
		)
		(pad "P2_13" thru_hole circle
			(at 6.75005 5.999988)
			(size 1.156208 1.156208)
			(drill 0.749808)
			(layers "*.Cu" "*.Mask")
			(remove_unused_layers no)
			(net "GND")
			(clearance 0.0508)
			(thermal_gap 0.0508)
		)
		(pad "P2_14" thru_hole circle
			(at 6.75005 7.999984)
			(size 1.156208 1.156208)
			(drill 0.749808)
			(layers "*.Cu" "*.Mask")
			(remove_unused_layers no)
			(net "GND")
			(clearance 0.0508)
			(thermal_gap 0.0508)
		)
		(pad "P2_15" thru_hole circle
			(at 6.75005 9.99998)
			(size 1.156208 1.156208)
			(drill 0.749808)
			(layers "*.Cu" "*.Mask")
			(remove_unused_layers no)
			(net "GND")
			(clearance 0.0508)
			(thermal_gap 0.0508)
		)
		(pad "P2_16" thru_hole circle
			(at 6.75005 11.999976)
			(size 1.156208 1.156208)
			(drill 0.749808)
			(layers "*.Cu" "*.Mask")
			(remove_unused_layers no)
			(net "GND")
			(clearance 0.0508)
			(thermal_gap 0.0508)
		)
		(pad "P2_17" thru_hole circle
			(at 6.75005 13.999972)
			(size 1.156208 1.156208)
			(drill 0.749808)
			(layers "*.Cu" "*.Mask")
			(remove_unused_layers no)
			(net "GND")
			(clearance 0.0508)
			(thermal_gap 0.0508)
		)
		(pad "P2_18" thru_hole circle
			(at 6.75005 15.999968)
			(size 1.156208 1.156208)
			(drill 0.749808)
			(layers "*.Cu" "*.Mask")
			(remove_unused_layers no)
			(net "GND")
			(clearance 0.0508)
			(thermal_gap 0.0508)
		)
		(zone
			(layer "B.Cu")
			(hatch none 0.5)
			(connect_pads
				(clearance 0)
			)
			(min_thickness 0.25)
			(keepout
				(tracks allowed)
				(vias not_allowed)
				(pads allowed)
				(copperpour not_allowed)
				(footprints allowed)
			)
			(placement
				(enabled no)
				(sheetname "")
			)
			(fill
				(thermal_gap 0.5)
				(thermal_bridge_width 0.5)
				(island_removal_mode 0)
			)
			(polygon
				(pts
					(xy 397.73352 -169.471594) (xy 397.73352 -152.188418) (xy 405.766778 -152.188418) (xy 405.766778 -169.471594)
				)
			)
		)
	)
	(footprint ""
		(layer "F.Cu")
		(at 470.449656 -107.502452 90)
		(property "Reference" "R87"
			(at 0 0 90)
			(layer "F.SilkS")
			(hide yes)
			(effects
				(font
					(size 1.27 1.27)
				)
			)
		)
		(property "Value" ""
			(at 0 0 90)
			(layer "F.Fab")
			(effects
				(font
					(size 1.27 1.27)
				)
			)
		)
		(duplicate_pad_numbers_are_jumpers no)
		(fp_line
			(start 0.7874 -0.4064)
			(end 0.7874 0.4064)
			(stroke
				(width 0.1524)
				(type default)
			)
			(layer "F.SilkS")
		)
		(fp_line
			(start -0.7874 -0.4064)
			(end 0.7874 -0.4064)
			(stroke
				(width 0.1524)
				(type default)
			)
			(layer "F.SilkS")
		)
		(fp_line
			(start 0.7874 0.4064)
			(end -0.7874 0.4064)
			(stroke
				(width 0.1524)
				(type default)
			)
			(layer "F.SilkS")
		)
		(fp_line
			(start -0.7874 0.4064)
			(end -0.7874 -0.4064)
			(stroke
				(width 0.1524)
				(type default)
			)
			(layer "F.SilkS")
		)
		(fp_line
			(start -0.12065 -0.305054)
			(end -0.12065 -0.2794)
			(stroke
				(width 0.1)
				(type default)
			)
			(layer "F.Fab")
		)
		(fp_line
			(start -0.67945 -0.305054)
			(end -0.12065 -0.305054)
			(stroke
				(width 0.1)
				(type default)
			)
			(layer "F.Fab")
		)
		(fp_line
			(start 0.67945 -0.3048)
			(end 0.67945 0.3048)
			(stroke
				(width 0.1)
				(type default)
			)
			(layer "F.Fab")
		)
		(fp_line
			(start 0.12065 -0.3048)
			(end 0.67945 -0.3048)
			(stroke
				(width 0.1)
				(type default)
			)
			(layer "F.Fab")
		)
		(fp_line
			(start 0.12065 -0.2794)
			(end 0.12065 -0.3048)
			(stroke
				(width 0.1)
				(type default)
			)
			(layer "F.Fab")
		)
		(fp_line
			(start -0.12065 -0.2794)
			(end 0.12065 -0.2794)
			(stroke
				(width 0.1)
				(type default)
			)
			(layer "F.Fab")
		)
		(fp_line
			(start 0.120396 0.2794)
			(end -0.12065 0.2794)
			(stroke
				(width 0.1)
				(type default)
			)
			(layer "F.Fab")
		)
		(fp_line
			(start -0.12065 0.2794)
			(end -0.12065 0.3048)
			(stroke
				(width 0.1)
				(type default)
			)
			(layer "F.Fab")
		)
		(fp_line
			(start 0.67945 0.3048)
			(end 0.120396 0.3048)
			(stroke
				(width 0.1)
				(type default)
			)
			(layer "F.Fab")
		)
		(fp_line
			(start 0.120396 0.3048)
			(end 0.120396 0.2794)
			(stroke
				(width 0.1)
				(type default)
			)
			(layer "F.Fab")
		)
		(fp_line
			(start -0.12065 0.3048)
			(end -0.67945 0.3048)
			(stroke
				(width 0.1)
				(type default)
			)
			(layer "F.Fab")
		)
		(fp_line
			(start -0.67945 0.3048)
			(end -0.67945 -0.305054)
			(stroke
				(width 0.1)
				(type default)
			)
			(layer "F.Fab")
		)
		(pad "1" smd circle
			(at -0.40005 0 90)
			(size 0 0)
			(layers "F.Cu" "F.Mask" "F.Paste")
			(net "SMB_P52V_SDA")
		)
		(pad "2" smd circle
			(at 0.40005 0 90)
			(size 0 0)
			(layers "F.Cu" "F.Mask" "F.Paste")
			(net "SMB_P52V_R_SDA")
		)
	)
	(footprint ""
		(layer "F.Cu")
		(at 429.2854 -31.3436 -90)
		(property "Reference" "R57"
			(at 0 0 270)
			(layer "F.SilkS")
			(hide yes)
			(effects
				(font
					(size 1.27 1.27)
				)
			)
		)
		(property "Value" ""
			(at 0 0 270)
			(layer "F.Fab")
			(effects
				(font
					(size 1.27 1.27)
				)
			)
		)
		(duplicate_pad_numbers_are_jumpers no)
		(fp_line
			(start -0.7874 0.4064)
			(end -0.7874 -0.4064)
			(stroke
				(width 0.1524)
				(type default)
			)
			(layer "F.SilkS")
		)
		(fp_line
			(start 0.7874 0.4064)
			(end -0.7874 0.4064)
			(stroke
				(width 0.1524)
				(type default)
			)
			(layer "F.SilkS")
		)
		(fp_line
			(start -0.7874 -0.4064)
			(end 0.7874 -0.4064)
			(stroke
				(width 0.1524)
				(type default)
			)
			(layer "F.SilkS")
		)
		(fp_line
			(start 0.7874 -0.4064)
			(end 0.7874 0.4064)
			(stroke
				(width 0.1524)
				(type default)
			)
			(layer "F.SilkS")
		)
		(fp_line
			(start -0.67945 0.3048)
			(end -0.67945 -0.305054)
			(stroke
				(width 0.1)
				(type default)
			)
			(layer "F.Fab")
		)
		(fp_line
			(start -0.12065 0.3048)
			(end -0.67945 0.3048)
			(stroke
				(width 0.1)
				(type default)
			)
			(layer "F.Fab")
		)
		(fp_line
			(start 0.120396 0.3048)
			(end 0.120396 0.2794)
			(stroke
				(width 0.1)
				(type default)
			)
			(layer "F.Fab")
		)
		(fp_line
			(start 0.67945 0.3048)
			(end 0.120396 0.3048)
			(stroke
				(width 0.1)
				(type default)
			)
			(layer "F.Fab")
		)
		(fp_line
			(start -0.12065 0.2794)
			(end -0.12065 0.3048)
			(stroke
				(width 0.1)
				(type default)
			)
			(layer "F.Fab")
		)
		(fp_line
			(start 0.120396 0.2794)
			(end -0.12065 0.2794)
			(stroke
				(width 0.1)
				(type default)
			)
			(layer "F.Fab")
		)
		(fp_line
			(start -0.12065 -0.2794)
			(end 0.12065 -0.2794)
			(stroke
				(width 0.1)
				(type default)
			)
			(layer "F.Fab")
		)
		(fp_line
			(start 0.12065 -0.2794)
			(end 0.12065 -0.3048)
			(stroke
				(width 0.1)
				(type default)
			)
			(layer "F.Fab")
		)
		(fp_line
			(start 0.12065 -0.3048)
			(end 0.67945 -0.3048)
			(stroke
				(width 0.1)
				(type default)
			)
			(layer "F.Fab")
		)
		(fp_line
			(start 0.67945 -0.3048)
			(end 0.67945 0.3048)
			(stroke
				(width 0.1)
				(type default)
			)
			(layer "F.Fab")
		)
		(fp_line
			(start -0.67945 -0.305054)
			(end -0.12065 -0.305054)
			(stroke
				(width 0.1)
				(type default)
			)
			(layer "F.Fab")
		)
		(fp_line
			(start -0.12065 -0.305054)
			(end -0.12065 -0.2794)
			(stroke
				(width 0.1)
				(type default)
			)
			(layer "F.Fab")
		)
		(pad "1" smd circle
			(at -0.40005 0 270)
			(size 0 0)
			(layers "F.Cu" "F.Mask" "F.Paste")
			(net "P3V3_AUX")
		)
		(pad "2" smd circle
			(at 0.40005 0 270)
			(size 0 0)
			(layers "F.Cu" "F.Mask" "F.Paste")
			(net "FRU_WP_N")
		)
	)
	(footprint ""
		(layer "F.Cu")
		(at 143.003778 -29.5402 180)
		(property "Reference" "PR6989"
			(at 0.458978 -4.68757 0)
			(unlocked yes)
			(layer "F.SilkS")
			(effects
				(font
					(size 0.7874 0.5842)
					(thickness 0.1524)
				)
				(justify left)
			)
		)
		(property "Value" ""
			(at 0 0 180)
			(layer "F.Fab")
			(effects
				(font
					(size 1.27 1.27)
				)
			)
		)
		(duplicate_pad_numbers_are_jumpers no)
		(fp_line
			(start 3.9878 3.5814)
			(end -3.9878 3.5814)
			(stroke
				(width 0.1524)
				(type default)
			)
			(layer "F.SilkS")
		)
		(fp_line
			(start 3.9878 -3.5814)
			(end 3.9878 3.5814)
			(stroke
				(width 0.1524)
				(type default)
			)
			(layer "F.SilkS")
		)
		(fp_line
			(start -3.9878 3.5814)
			(end -3.9878 -3.5814)
			(stroke
				(width 0.1524)
				(type default)
			)
			(layer "F.SilkS")
		)
		(fp_line
			(start -3.9878 -3.5814)
			(end 3.9878 -3.5814)
			(stroke
				(width 0.1524)
				(type default)
			)
			(layer "F.SilkS")
		)
		(fp_line
			(start 3.5306 3.353054)
			(end -3.5306 3.353054)
			(stroke
				(width 0.1)
				(type default)
			)
			(layer "F.Fab")
		)
		(fp_line
			(start 3.5306 -3.353054)
			(end 3.5306 3.353054)
			(stroke
				(width 0.1)
				(type default)
			)
			(layer "F.Fab")
		)
		(fp_line
			(start -3.5306 3.353054)
			(end -3.5306 -3.353054)
			(stroke
				(width 0.1)
				(type default)
			)
			(layer "F.Fab")
		)
		(fp_line
			(start -3.5306 -3.353054)
			(end 3.5306 -3.353054)
			(stroke
				(width 0.1)
				(type default)
			)
			(layer "F.Fab")
		)
		(pad "1A" smd rect
			(at -2.249932 0)
			(size 3.2004 6.858)
			(layers "F.Cu" "F.Mask" "F.Paste")
			(net "P52V_2")
		)
		(pad "1B" smd rect
			(at -0.776732 0 180)
			(size 0.254 0.508)
			(layers "F.Cu" "F.Mask" "F.Paste")
			(net "P52V_HS2_SENSE_P_R2")
		)
		(pad "2A" smd rect
			(at 2.249932 0)
			(size 3.2004 6.858)
			(layers "F.Cu" "F.Mask" "F.Paste")
			(net "P52V_HS2_DRAIN_2")
		)
		(pad "2B" smd rect
			(at 0.776732 0 180)
			(size 0.254 0.508)
			(layers "F.Cu" "F.Mask" "F.Paste")
			(net "P52V_HS2_SENSE_N_R2")
		)
	)
	(footprint ""
		(layer "F.Cu")
		(at 420.37 -42.418)
		(property "Reference" "U8"
			(at -1.905 -4.79933 0)
			(unlocked yes)
			(layer "F.SilkS")
			(effects
				(font
					(size 0.7874 0.5842)
					(thickness 0.1524)
				)
				(justify left)
			)
		)
		(property "Value" ""
			(at 0 0 0)
			(layer "F.Fab")
			(effects
				(font
					(size 1.27 1.27)
				)
			)
		)
		(duplicate_pad_numbers_are_jumpers no)
		(fp_line
			(start -2.0066 -3.9624)
			(end -0.5842 -3.9624)
			(stroke
				(width 0.1524)
				(type default)
			)
			(layer "F.SilkS")
		)
		(fp_line
			(start -2.0066 3.9624)
			(end -2.0066 -3.9624)
			(stroke
				(width 0.1524)
				(type default)
			)
			(layer "F.SilkS")
		)
		(fp_line
			(start -0.5842 -3.9624)
			(end 0 -3.3782)
			(stroke
				(width 0.1524)
				(type default)
			)
			(layer "F.SilkS")
		)
		(fp_line
			(start 0 -3.3782)
			(end 0.5842 -3.9624)
			(stroke
				(width 0.1524)
				(type default)
			)
			(layer "F.SilkS")
		)
		(fp_line
			(start 0.5842 -3.9624)
			(end 2.0066 -3.9624)
			(stroke
				(width 0.1524)
				(type default)
			)
			(layer "F.SilkS")
		)
		(fp_line
			(start 2.0066 -3.9624)
			(end 2.0066 3.9624)
			(stroke
				(width 0.1524)
				(type default)
			)
			(layer "F.SilkS")
		)
		(fp_line
			(start 2.0066 3.9624)
			(end -2.0066 3.9624)
			(stroke
				(width 0.1524)
				(type default)
			)
			(layer "F.SilkS")
		)
		(fp_poly
			(pts
				(xy -3.007614 -3.9116) (xy -3.388614 -4.6736) (xy -2.626614 -4.6736)
			)
			(stroke
				(width 0)
				(type default)
			)
			(fill yes)
			(layer "F.SilkS")
		)
		(fp_line
			(start -3.724402 -3.80365)
			(end -3.724402 3.80365)
			(stroke
				(width 0.1)
				(type default)
			)
			(layer "F.Fab")
		)
		(fp_line
			(start -3.724402 3.80365)
			(end -2.2479 3.80365)
			(stroke
				(width 0.1)
				(type default)
			)
			(layer "F.Fab")
		)
		(fp_line
			(start -3.7211 -3.34645)
			(end -3.7211 -3.80365)
			(stroke
				(width 0.1)
				(type default)
			)
			(layer "F.Fab")
		)
		(fp_line
			(start -2.2479 -3.974846)
			(end -2.2479 -3.80365)
			(stroke
				(width 0.1)
				(type default)
			)
			(layer "F.Fab")
		)
		(fp_line
			(start -2.2479 -3.80365)
			(end -3.724402 -3.80365)
			(stroke
				(width 0.1)
				(type default)
			)
			(layer "F.Fab")
		)
		(fp_line
			(start -2.2479 3.80365)
			(end -2.2479 3.9624)
			(stroke
				(width 0.1)
				(type default)
			)
			(layer "F.Fab")
		)
		(fp_line
			(start -2.2479 3.9624)
			(end 2.2479 3.9624)
			(stroke
				(width 0.1)
				(type default)
			)
			(layer "F.Fab")
		)
		(fp_line
			(start 2.2479 -3.974846)
			(end -2.2479 -3.974846)
			(stroke
				(width 0.1)
				(type default)
			)
			(layer "F.Fab")
		)
		(fp_line
			(start 2.2479 -3.80365)
			(end 2.2479 -3.974846)
			(stroke
				(width 0.1)
				(type default)
			)
			(layer "F.Fab")
		)
		(fp_line
			(start 2.2479 3.80365)
			(end 3.7211 3.80365)
			(stroke
				(width 0.1)
				(type default)
			)
			(layer "F.Fab")
		)
		(fp_line
			(start 2.2479 3.9624)
			(end 2.2479 3.80365)
			(stroke
				(width 0.1)
				(type default)
			)
			(layer "F.Fab")
		)
		(fp_line
			(start 3.7211 -3.80365)
			(end 2.2479 -3.80365)
			(stroke
				(width 0.1)
				(type default)
			)
			(layer "F.Fab")
		)
		(fp_line
			(start 3.7211 3.80365)
			(end 3.7211 -3.80365)
			(stroke
				(width 0.1)
				(type default)
			)
			(layer "F.Fab")
		)
		(fp_poly
			(pts
				(xy -3.8862 -3.570986) (xy -4.6482 -3.189986) (xy -4.6482 -3.951986)
			)
			(stroke
				(width 0)
				(type default)
			)
			(fill yes)
			(layer "F.Fab")
		)
		(pad "1" smd rect
			(at -2.921 -3.57505 270)
			(size 0.3556 1.4986)
			(layers "F.Cu" "F.Mask" "F.Paste")
			(net "PU_U8_PIN1")
		)
		(pad "2" smd rect
			(at -2.921 -2.925064 270)
			(size 0.3556 1.4986)
			(layers "F.Cu" "F.Mask" "F.Paste")
			(net "PCA9555_A1")
		)
		(pad "3" smd rect
			(at -2.921 -2.275078 270)
			(size 0.3556 1.4986)
			(layers "F.Cu" "F.Mask" "F.Paste")
			(net "PCA9555_A2")
		)
		(pad "4" smd rect
			(at -2.921 -1.625092 270)
			(size 0.3556 1.4986)
			(layers "F.Cu" "F.Mask" "F.Paste")
			(net "P52V_HS1_FLT")
		)
		(pad "5" smd rect
			(at -2.921 -0.975106 270)
			(size 0.3556 1.4986)
			(layers "F.Cu" "F.Mask" "F.Paste")
			(net "P52V_HS2_FLT")
		)
		(pad "6" smd rect
			(at -2.921 -0.32512 270)
			(size 0.3556 1.4986)
			(layers "F.Cu" "F.Mask" "F.Paste")
			(net "PRSNT_FAN_BP0_N")
		)
		(pad "7" smd rect
			(at -2.921 0.32512 270)
			(size 0.3556 1.4986)
			(layers "F.Cu" "F.Mask" "F.Paste")
			(net "PRSNT_FAN_BP1_N")
		)
		(pad "8" smd rect
			(at -2.921 0.975106 270)
			(size 0.3556 1.4986)
			(layers "F.Cu" "F.Mask" "F.Paste")
			(net "TP_U8_P04")
		)
		(pad "9" smd rect
			(at -2.921 1.625092 270)
			(size 0.3556 1.4986)
			(layers "F.Cu" "F.Mask" "F.Paste")
			(net "TP_U8_P05")
		)
		(pad "10" smd rect
			(at -2.921 2.275078 270)
			(size 0.3556 1.4986)
			(layers "F.Cu" "F.Mask" "F.Paste")
			(net "TP_U8_P06")
		)
		(pad "11" smd rect
			(at -2.921 2.925064 270)
			(size 0.3556 1.4986)
			(layers "F.Cu" "F.Mask" "F.Paste")
			(net "TP_U8_P07")
		)
		(pad "12" smd rect
			(at -2.921 3.57505 270)
			(size 0.3556 1.4986)
			(layers "F.Cu" "F.Mask" "F.Paste")
			(net "GND")
		)
		(pad "13" smd rect
			(at 2.921 3.57505 270)
			(size 0.3556 1.4986)
			(layers "F.Cu" "F.Mask" "F.Paste")
			(net "PWRGD_P52V_HS1_PG")
		)
		(pad "14" smd rect
			(at 2.921 2.925064 270)
			(size 0.3556 1.4986)
			(layers "F.Cu" "F.Mask" "F.Paste")
			(net "PWRGD_P52V_HS2_PG")
		)
		(pad "15" smd rect
			(at 2.921 2.275078 270)
			(size 0.3556 1.4986)
			(layers "F.Cu" "F.Mask" "F.Paste")
			(net "BOARD_ID_0")
		)
		(pad "16" smd rect
			(at 2.921 1.625092 270)
			(size 0.3556 1.4986)
			(layers "F.Cu" "F.Mask" "F.Paste")
			(net "BOARD_ID_1")
		)
		(pad "17" smd rect
			(at 2.921 0.975106 270)
			(size 0.3556 1.4986)
			(layers "F.Cu" "F.Mask" "F.Paste")
			(net "BOARD_ID_2")
		)
		(pad "18" smd rect
			(at 2.921 0.32512 270)
			(size 0.3556 1.4986)
			(layers "F.Cu" "F.Mask" "F.Paste")
			(net "SKU_ID_0")
		)
		(pad "19" smd rect
			(at 2.921 -0.32512 270)
			(size 0.3556 1.4986)
			(layers "F.Cu" "F.Mask" "F.Paste")
			(net "SKU_ID_1")
		)
		(pad "20" smd rect
			(at 2.921 -0.975106 270)
			(size 0.3556 1.4986)
			(layers "F.Cu" "F.Mask" "F.Paste")
			(net "SKU_ID_2")
		)
		(pad "21" smd rect
			(at 2.921 -1.625092 270)
			(size 0.3556 1.4986)
			(layers "F.Cu" "F.Mask" "F.Paste")
			(net "PCA9555_A0")
		)
		(pad "22" smd rect
			(at 2.921 -2.275078 270)
			(size 0.3556 1.4986)
			(layers "F.Cu" "F.Mask" "F.Paste")
			(net "SMB_IOEXP_SCL")
		)
		(pad "23" smd rect
			(at 2.921 -2.925064 270)
			(size 0.3556 1.4986)
			(layers "F.Cu" "F.Mask" "F.Paste")
			(net "SMB_IOEXP_SDA")
		)
		(pad "24" smd rect
			(at 2.921 -3.57505 270)
			(size 0.3556 1.4986)
			(layers "F.Cu" "F.Mask" "F.Paste")
			(net "P3V3_AUX")
		)
	)
	(footprint ""
		(layer "F.Cu")
		(at 447.421 -44.196)
		(property "Reference" "R382"
			(at 0 0 0)
			(layer "F.SilkS")
			(hide yes)
			(effects
				(font
					(size 1.27 1.27)
				)
			)
		)
		(property "Value" ""
			(at 0 0 0)
			(layer "F.Fab")
			(effects
				(font
					(size 1.27 1.27)
				)
			)
		)
		(duplicate_pad_numbers_are_jumpers no)
		(fp_line
			(start -0.7874 -0.4064)
			(end 0.7874 -0.4064)
			(stroke
				(width 0.1524)
				(type default)
			)
			(layer "F.SilkS")
		)
		(fp_line
			(start -0.7874 0.4064)
			(end -0.7874 -0.4064)
			(stroke
				(width 0.1524)
				(type default)
			)
			(layer "F.SilkS")
		)
		(fp_line
			(start 0.7874 -0.4064)
			(end 0.7874 0.4064)
			(stroke
				(width 0.1524)
				(type default)
			)
			(layer "F.SilkS")
		)
		(fp_line
			(start 0.7874 0.4064)
			(end -0.7874 0.4064)
			(stroke
				(width 0.1524)
				(type default)
			)
			(layer "F.SilkS")
		)
		(fp_line
			(start -0.67945 -0.305054)
			(end -0.12065 -0.305054)
			(stroke
				(width 0.1)
				(type default)
			)
			(layer "F.Fab")
		)
		(fp_line
			(start -0.67945 0.3048)
			(end -0.67945 -0.305054)
			(stroke
				(width 0.1)
				(type default)
			)
			(layer "F.Fab")
		)
		(fp_line
			(start -0.12065 -0.305054)
			(end -0.12065 -0.2794)
			(stroke
				(width 0.1)
				(type default)
			)
			(layer "F.Fab")
		)
		(fp_line
			(start -0.12065 -0.2794)
			(end 0.12065 -0.2794)
			(stroke
				(width 0.1)
				(type default)
			)
			(layer "F.Fab")
		)
		(fp_line
			(start -0.12065 0.2794)
			(end -0.12065 0.3048)
			(stroke
				(width 0.1)
				(type default)
			)
			(layer "F.Fab")
		)
		(fp_line
			(start -0.12065 0.3048)
			(end -0.67945 0.3048)
			(stroke
				(width 0.1)
				(type default)
			)
			(layer "F.Fab")
		)
		(fp_line
			(start 0.120396 0.2794)
			(end -0.12065 0.2794)
			(stroke
				(width 0.1)
				(type default)
			)
			(layer "F.Fab")
		)
		(fp_line
			(start 0.120396 0.3048)
			(end 0.120396 0.2794)
			(stroke
				(width 0.1)
				(type default)
			)
			(layer "F.Fab")
		)
		(fp_line
			(start 0.12065 -0.3048)
			(end 0.67945 -0.3048)
			(stroke
				(width 0.1)
				(type default)
			)
			(layer "F.Fab")
		)
		(fp_line
			(start 0.12065 -0.2794)
			(end 0.12065 -0.3048)
			(stroke
				(width 0.1)
				(type default)
			)
			(layer "F.Fab")
		)
		(fp_line
			(start 0.67945 -0.3048)
			(end 0.67945 0.3048)
			(stroke
				(width 0.1)
				(type default)
			)
			(layer "F.Fab")
		)
		(fp_line
			(start 0.67945 0.3048)
			(end 0.120396 0.3048)
			(stroke
				(width 0.1)
				(type default)
			)
			(layer "F.Fab")
		)
		(pad "1" smd circle
			(at -0.40005 0)
			(size 0 0)
			(layers "F.Cu" "F.Mask" "F.Paste")
			(net "GPU_HSC_BUF_R_EN")
		)
		(pad "2" smd circle
			(at 0.40005 0)
			(size 0 0)
			(layers "F.Cu" "F.Mask" "F.Paste")
			(net "GPU_HSC_BUF_EN")
		)
	)
	(footprint ""
		(layer "F.Cu")
		(at 112.988852 -44.0944 -90)
		(property "Reference" "PR6973"
			(at 0 0 270)
			(layer "F.SilkS")
			(hide yes)
			(effects
				(font
					(size 1.27 1.27)
				)
			)
		)
		(property "Value" ""
			(at 0 0 270)
			(layer "F.Fab")
			(effects
				(font
					(size 1.27 1.27)
				)
			)
		)
		(duplicate_pad_numbers_are_jumpers no)
		(fp_line
			(start -1.2954 0.5842)
			(end -1.2954 -0.5842)
			(stroke
				(width 0.1524)
				(type default)
			)
			(layer "F.SilkS")
		)
		(fp_line
			(start 1.2954 0.5842)
			(end -1.2954 0.5842)
			(stroke
				(width 0.1524)
				(type default)
			)
			(layer "F.SilkS")
		)
		(fp_line
			(start -1.2954 -0.5842)
			(end 1.2954 -0.5842)
			(stroke
				(width 0.1524)
				(type default)
			)
			(layer "F.SilkS")
		)
		(fp_line
			(start 1.2954 -0.5842)
			(end 1.2954 0.5842)
			(stroke
				(width 0.1524)
				(type default)
			)
			(layer "F.SilkS")
		)
		(fp_line
			(start -0.8636 0.4572)
			(end -0.8636 0.4318)
			(stroke
				(width 0.1)
				(type default)
			)
			(layer "F.Fab")
		)
		(fp_line
			(start 0.8636 0.4572)
			(end -0.8636 0.4572)
			(stroke
				(width 0.1)
				(type default)
			)
			(layer "F.Fab")
		)
		(fp_line
			(start -0.8636 0.4318)
			(end -0.8636 0.4064)
			(stroke
				(width 0.1)
				(type default)
			)
			(layer "F.Fab")
		)
		(fp_line
			(start -1.1938 0.4064)
			(end -1.1938 -0.406654)
			(stroke
				(width 0.1)
				(type default)
			)
			(layer "F.Fab")
		)
		(fp_line
			(start -0.8636 0.4064)
			(end -1.1938 0.4064)
			(stroke
				(width 0.1)
				(type default)
			)
			(layer "F.Fab")
		)
		(fp_line
			(start 0.8636 0.4064)
			(end 0.8636 0.4572)
			(stroke
				(width 0.1)
				(type default)
			)
			(layer "F.Fab")
		)
		(fp_line
			(start 1.1938 0.4064)
			(end 0.8636 0.4064)
			(stroke
				(width 0.1)
				(type default)
			)
			(layer "F.Fab")
		)
		(fp_line
			(start -1.1938 -0.406654)
			(end -0.8636 -0.406654)
			(stroke
				(width 0.1)
				(type default)
			)
			(layer "F.Fab")
		)
		(fp_line
			(start -0.8636 -0.406654)
			(end -0.8636 -0.4572)
			(stroke
				(width 0.1)
				(type default)
			)
			(layer "F.Fab")
		)
		(fp_line
			(start 0.8636 -0.406654)
			(end 1.1938 -0.406654)
			(stroke
				(width 0.1)
				(type default)
			)
			(layer "F.Fab")
		)
		(fp_line
			(start 1.1938 -0.406654)
			(end 1.1938 0.4064)
			(stroke
				(width 0.1)
				(type default)
			)
			(layer "F.Fab")
		)
		(fp_line
			(start -0.8636 -0.4572)
			(end 0.8636 -0.4572)
			(stroke
				(width 0.1)
				(type default)
			)
			(layer "F.Fab")
		)
		(fp_line
			(start 0.8636 -0.4572)
			(end 0.8636 -0.406654)
			(stroke
				(width 0.1)
				(type default)
			)
			(layer "F.Fab")
		)
		(pad "1" smd rect
			(at -0.7366 0 180)
			(size 0.7112 0.8128)
			(layers "F.Cu" "F.Mask" "F.Paste")
			(net "P52V_HS2_GATE2_R")
		)
		(pad "2" smd rect
			(at 0.7366 0 180)
			(size 0.7112 0.8128)
			(layers "F.Cu" "F.Mask" "F.Paste")
			(net "P52V_HS2_GATE4")
		)
	)
	(footprint ""
		(layer "F.Cu")
		(at 435.991 -41.148 -90)
		(property "Reference" "R1"
			(at 0 0 270)
			(layer "F.SilkS")
			(hide yes)
			(effects
				(font
					(size 1.27 1.27)
				)
			)
		)
		(property "Value" ""
			(at 0 0 270)
			(layer "F.Fab")
			(effects
				(font
					(size 1.27 1.27)
				)
			)
		)
		(duplicate_pad_numbers_are_jumpers no)
		(fp_line
			(start -0.7874 0.4064)
			(end -0.7874 -0.4064)
			(stroke
				(width 0.1524)
				(type default)
			)
			(layer "F.SilkS")
		)
		(fp_line
			(start 0.7874 0.4064)
			(end -0.7874 0.4064)
			(stroke
				(width 0.1524)
				(type default)
			)
			(layer "F.SilkS")
		)
		(fp_line
			(start -0.7874 -0.4064)
			(end 0.7874 -0.4064)
			(stroke
				(width 0.1524)
				(type default)
			)
			(layer "F.SilkS")
		)
		(fp_line
			(start 0.7874 -0.4064)
			(end 0.7874 0.4064)
			(stroke
				(width 0.1524)
				(type default)
			)
			(layer "F.SilkS")
		)
		(fp_line
			(start -0.67945 0.3048)
			(end -0.67945 -0.305054)
			(stroke
				(width 0.1)
				(type default)
			)
			(layer "F.Fab")
		)
		(fp_line
			(start -0.12065 0.3048)
			(end -0.67945 0.3048)
			(stroke
				(width 0.1)
				(type default)
			)
			(layer "F.Fab")
		)
		(fp_line
			(start 0.120396 0.3048)
			(end 0.120396 0.2794)
			(stroke
				(width 0.1)
				(type default)
			)
			(layer "F.Fab")
		)
		(fp_line
			(start 0.67945 0.3048)
			(end 0.120396 0.3048)
			(stroke
				(width 0.1)
				(type default)
			)
			(layer "F.Fab")
		)
		(fp_line
			(start -0.12065 0.2794)
			(end -0.12065 0.3048)
			(stroke
				(width 0.1)
				(type default)
			)
			(layer "F.Fab")
		)
		(fp_line
			(start 0.120396 0.2794)
			(end -0.12065 0.2794)
			(stroke
				(width 0.1)
				(type default)
			)
			(layer "F.Fab")
		)
		(fp_line
			(start -0.12065 -0.2794)
			(end 0.12065 -0.2794)
			(stroke
				(width 0.1)
				(type default)
			)
			(layer "F.Fab")
		)
		(fp_line
			(start 0.12065 -0.2794)
			(end 0.12065 -0.3048)
			(stroke
				(width 0.1)
				(type default)
			)
			(layer "F.Fab")
		)
		(fp_line
			(start 0.12065 -0.3048)
			(end 0.67945 -0.3048)
			(stroke
				(width 0.1)
				(type default)
			)
			(layer "F.Fab")
		)
		(fp_line
			(start 0.67945 -0.3048)
			(end 0.67945 0.3048)
			(stroke
				(width 0.1)
				(type default)
			)
			(layer "F.Fab")
		)
		(fp_line
			(start -0.67945 -0.305054)
			(end -0.12065 -0.305054)
			(stroke
				(width 0.1)
				(type default)
			)
			(layer "F.Fab")
		)
		(fp_line
			(start -0.12065 -0.305054)
			(end -0.12065 -0.2794)
			(stroke
				(width 0.1)
				(type default)
			)
			(layer "F.Fab")
		)
		(pad "1" smd circle
			(at -0.40005 0 270)
			(size 0 0)
			(layers "F.Cu" "F.Mask" "F.Paste")
			(net "SMB_PDB_MISC_SCL_R")
		)
		(pad "2" smd circle
			(at 0.40005 0 270)
			(size 0 0)
			(layers "F.Cu" "F.Mask" "F.Paste")
			(net "P3V3_AUX")
		)
	)
	(footprint ""
		(layer "F.Cu")
		(at 140.79982 -69.977 180)
		(property "Reference" "PR6984"
			(at 0 0 180)
			(layer "F.SilkS")
			(hide yes)
			(effects
				(font
					(size 1.27 1.27)
				)
			)
		)
		(property "Value" ""
			(at 0 0 180)
			(layer "F.Fab")
			(effects
				(font
					(size 1.27 1.27)
				)
			)
		)
		(duplicate_pad_numbers_are_jumpers no)
		(fp_line
			(start 1.2954 0.5842)
			(end -1.2954 0.5842)
			(stroke
				(width 0.1524)
				(type default)
			)
			(layer "F.SilkS")
		)
		(fp_line
			(start 1.2954 -0.5842)
			(end 1.2954 0.5842)
			(stroke
				(width 0.1524)
				(type default)
			)
			(layer "F.SilkS")
		)
		(fp_line
			(start -1.2954 0.5842)
			(end -1.2954 -0.5842)
			(stroke
				(width 0.1524)
				(type default)
			)
			(layer "F.SilkS")
		)
		(fp_line
			(start -1.2954 -0.5842)
			(end 1.2954 -0.5842)
			(stroke
				(width 0.1524)
				(type default)
			)
			(layer "F.SilkS")
		)
		(fp_line
			(start 1.1938 0.4064)
			(end 0.8636 0.4064)
			(stroke
				(width 0.1)
				(type default)
			)
			(layer "F.Fab")
		)
		(fp_line
			(start 1.1938 -0.406654)
			(end 1.1938 0.4064)
			(stroke
				(width 0.1)
				(type default)
			)
			(layer "F.Fab")
		)
		(fp_line
			(start 0.8636 0.4572)
			(end -0.8636 0.4572)
			(stroke
				(width 0.1)
				(type default)
			)
			(layer "F.Fab")
		)
		(fp_line
			(start 0.8636 0.4064)
			(end 0.8636 0.4572)
			(stroke
				(width 0.1)
				(type default)
			)
			(layer "F.Fab")
		)
		(fp_line
			(start 0.8636 -0.406654)
			(end 1.1938 -0.406654)
			(stroke
				(width 0.1)
				(type default)
			)
			(layer "F.Fab")
		)
		(fp_line
			(start 0.8636 -0.4572)
			(end 0.8636 -0.406654)
			(stroke
				(width 0.1)
				(type default)
			)
			(layer "F.Fab")
		)
		(fp_line
			(start -0.8636 0.4572)
			(end -0.8636 0.4318)
			(stroke
				(width 0.1)
				(type default)
			)
			(layer "F.Fab")
		)
		(fp_line
			(start -0.8636 0.4318)
			(end -0.8636 0.4064)
			(stroke
				(width 0.1)
				(type default)
			)
			(layer "F.Fab")
		)
		(fp_line
			(start -0.8636 0.4064)
			(end -1.1938 0.4064)
			(stroke
				(width 0.1)
				(type default)
			)
			(layer "F.Fab")
		)
		(fp_line
			(start -0.8636 -0.406654)
			(end -0.8636 -0.4572)
			(stroke
				(width 0.1)
				(type default)
			)
			(layer "F.Fab")
		)
		(fp_line
			(start -0.8636 -0.4572)
			(end 0.8636 -0.4572)
			(stroke
				(width 0.1)
				(type default)
			)
			(layer "F.Fab")
		)
		(fp_line
			(start -1.1938 0.4064)
			(end -1.1938 -0.406654)
			(stroke
				(width 0.1)
				(type default)
			)
			(layer "F.Fab")
		)
		(fp_line
			(start -1.1938 -0.406654)
			(end -0.8636 -0.406654)
			(stroke
				(width 0.1)
				(type default)
			)
			(layer "F.Fab")
		)
		(pad "1" smd rect
			(at -0.7366 0 90)
			(size 0.7112 0.8128)
			(layers "F.Cu" "F.Mask" "F.Paste")
			(net "P52V_HS2_4287_ADC_N")
		)
		(pad "2" smd rect
			(at 0.7366 0 90)
			(size 0.7112 0.8128)
			(layers "F.Cu" "F.Mask" "F.Paste")
			(net "P52V_HS2_SENSE_N_R1")
		)
	)
	(footprint ""
		(layer "F.Cu")
		(at 33.85439 -32.385 180)
		(property "Reference" "R47"
			(at 0 0 180)
			(layer "F.SilkS")
			(hide yes)
			(effects
				(font
					(size 1.27 1.27)
				)
			)
		)
		(property "Value" ""
			(at 0 0 180)
			(layer "F.Fab")
			(effects
				(font
					(size 1.27 1.27)
				)
			)
		)
		(duplicate_pad_numbers_are_jumpers no)
		(fp_line
			(start 2.234946 0.9271)
			(end -2.234946 0.9271)
			(stroke
				(width 0.1524)
				(type default)
			)
			(layer "F.SilkS")
		)
		(fp_line
			(start 2.234946 -0.9271)
			(end 2.234946 0.9271)
			(stroke
				(width 0.1524)
				(type default)
			)
			(layer "F.SilkS")
		)
		(fp_line
			(start -2.234946 0.9271)
			(end -2.234946 -0.9271)
			(stroke
				(width 0.1524)
				(type default)
			)
			(layer "F.SilkS")
		)
		(fp_line
			(start -2.234946 -0.9271)
			(end 2.234946 -0.9271)
			(stroke
				(width 0.1524)
				(type default)
			)
			(layer "F.SilkS")
		)
		(fp_line
			(start 1.575054 0.824992)
			(end 1.575054 -0.824992)
			(stroke
				(width 0.1)
				(type default)
			)
			(layer "F.Fab")
		)
		(fp_line
			(start 1.575054 -0.824992)
			(end -1.575054 -0.824992)
			(stroke
				(width 0.1)
				(type default)
			)
			(layer "F.Fab")
		)
		(fp_line
			(start -1.575054 0.824992)
			(end 1.575054 0.824992)
			(stroke
				(width 0.1)
				(type default)
			)
			(layer "F.Fab")
		)
		(fp_line
			(start -1.575054 -0.824992)
			(end -1.575054 0.824992)
			(stroke
				(width 0.1)
				(type default)
			)
			(layer "F.Fab")
		)
		(pad "1" smd rect
			(at -1.599946 0 180)
			(size 1.016 1.6002)
			(layers "F.Cu" "F.Mask" "F.Paste")
			(net "LED_D2_R4")
		)
		(pad "2" smd rect
			(at 1.599946 0 180)
			(size 1.016 1.6002)
			(layers "F.Cu" "F.Mask" "F.Paste")
			(net "LED_D2_R5")
		)
	)
	(footprint ""
		(layer "F.Cu")
		(at 378.079 -139.7)
		(property "Reference" "PC28"
			(at 4.4704 -5.18033 0)
			(unlocked yes)
			(layer "F.SilkS")
			(effects
				(font
					(size 0.7874 0.5842)
					(thickness 0.1524)
				)
				(justify left)
			)
		)
		(property "Value" ""
			(at 0 0 0)
			(layer "F.Fab")
			(effects
				(font
					(size 1.27 1.27)
				)
			)
		)
		(duplicate_pad_numbers_are_jumpers no)
		(fp_line
			(start -9.253728 3.750056)
			(end 9.249918 3.750056)
			(stroke
				(width 0.1524)
				(type default)
			)
			(layer "F.SilkS")
		)
		(fp_line
			(start 0 3.750056)
			(end -9.253728 3.750056)
			(stroke
				(width 0.1524)
				(type default)
			)
			(layer "F.SilkS")
		)
		(fp_circle
			(center 0 3.750056)
			(end 9.249918 3.750056)
			(stroke
				(width 0.1524)
				(type default)
			)
			(fill no)
			(layer "F.SilkS")
		)
		(fp_poly
			(pts
				(arc
					(start 9.249918 3.750056)
					(mid 0 12.999974)
					(end -9.249918 3.750056)
				)
			)
			(stroke
				(width 0)
				(type default)
			)
			(fill yes)
			(layer "F.SilkS")
		)
		(fp_circle
			(center 0 3.750056)
			(end 9.249918 3.750056)
			(stroke
				(width 0.1)
				(type default)
			)
			(fill no)
			(layer "F.Fab")
		)
		(pad "1" thru_hole rect
			(at 0 0)
			(size 1.778 1.778)
			(drill 1.27)
			(layers "*.Cu" "*.Mask")
			(remove_unused_layers no)
			(net "P52V_HS1")
			(clearance 0)
			(padstack
				(mode front_inner_back)
				(layer "Inner"
					(shape circle)
					(size 1.778 1.778)
					(clearance 0)
				)
				(layer "B.Cu"
					(shape rect)
					(size 1.778 1.778)
					(clearance 0)
				)
			)
		)
		(pad "2" thru_hole circle
			(at 0 7.500112)
			(size 1.778 1.778)
			(drill 1.27)
			(layers "*.Cu" "*.Mask")
			(remove_unused_layers no)
			(net "GND")
			(clearance 0)
		)
	)
	(footprint ""
		(layer "F.Cu")
		(at 171.831 -84.709 90)
		(property "Reference" "R5907"
			(at 0 0 90)
			(layer "F.SilkS")
			(hide yes)
			(effects
				(font
					(size 1.27 1.27)
				)
			)
		)
		(property "Value" ""
			(at 0 0 90)
			(layer "F.Fab")
			(effects
				(font
					(size 1.27 1.27)
				)
			)
		)
		(duplicate_pad_numbers_are_jumpers no)
		(fp_line
			(start 0.7874 -0.4064)
			(end 0.7874 0.4064)
			(stroke
				(width 0.1524)
				(type default)
			)
			(layer "F.SilkS")
		)
		(fp_line
			(start -0.7874 -0.4064)
			(end 0.7874 -0.4064)
			(stroke
				(width 0.1524)
				(type default)
			)
			(layer "F.SilkS")
		)
		(fp_line
			(start 0.7874 0.4064)
			(end -0.7874 0.4064)
			(stroke
				(width 0.1524)
				(type default)
			)
			(layer "F.SilkS")
		)
		(fp_line
			(start -0.7874 0.4064)
			(end -0.7874 -0.4064)
			(stroke
				(width 0.1524)
				(type default)
			)
			(layer "F.SilkS")
		)
		(fp_line
			(start -0.12065 -0.305054)
			(end -0.12065 -0.2794)
			(stroke
				(width 0.1)
				(type default)
			)
			(layer "F.Fab")
		)
		(fp_line
			(start -0.67945 -0.305054)
			(end -0.12065 -0.305054)
			(stroke
				(width 0.1)
				(type default)
			)
			(layer "F.Fab")
		)
		(fp_line
			(start 0.67945 -0.3048)
			(end 0.67945 0.3048)
			(stroke
				(width 0.1)
				(type default)
			)
			(layer "F.Fab")
		)
		(fp_line
			(start 0.12065 -0.3048)
			(end 0.67945 -0.3048)
			(stroke
				(width 0.1)
				(type default)
			)
			(layer "F.Fab")
		)
		(fp_line
			(start 0.12065 -0.2794)
			(end 0.12065 -0.3048)
			(stroke
				(width 0.1)
				(type default)
			)
			(layer "F.Fab")
		)
		(fp_line
			(start -0.12065 -0.2794)
			(end 0.12065 -0.2794)
			(stroke
				(width 0.1)
				(type default)
			)
			(layer "F.Fab")
		)
		(fp_line
			(start 0.120396 0.2794)
			(end -0.12065 0.2794)
			(stroke
				(width 0.1)
				(type default)
			)
			(layer "F.Fab")
		)
		(fp_line
			(start -0.12065 0.2794)
			(end -0.12065 0.3048)
			(stroke
				(width 0.1)
				(type default)
			)
			(layer "F.Fab")
		)
		(fp_line
			(start 0.67945 0.3048)
			(end 0.120396 0.3048)
			(stroke
				(width 0.1)
				(type default)
			)
			(layer "F.Fab")
		)
		(fp_line
			(start 0.120396 0.3048)
			(end 0.120396 0.2794)
			(stroke
				(width 0.1)
				(type default)
			)
			(layer "F.Fab")
		)
		(fp_line
			(start -0.12065 0.3048)
			(end -0.67945 0.3048)
			(stroke
				(width 0.1)
				(type default)
			)
			(layer "F.Fab")
		)
		(fp_line
			(start -0.67945 0.3048)
			(end -0.67945 -0.305054)
			(stroke
				(width 0.1)
				(type default)
			)
			(layer "F.Fab")
		)
		(pad "1" smd circle
			(at -0.40005 0 90)
			(size 0 0)
			(layers "F.Cu" "F.Mask" "F.Paste")
			(net "P3V3_2_AND")
		)
		(pad "2" smd circle
			(at 0.40005 0 90)
			(size 0 0)
			(layers "F.Cu" "F.Mask" "F.Paste")
			(net "GND")
		)
	)
	(footprint ""
		(layer "F.Cu")
		(at 61.92139 -99.06)
		(property "Reference" "PC39"
			(at -8.17499 -5.05333 0)
			(unlocked yes)
			(layer "F.SilkS")
			(effects
				(font
					(size 0.7874 0.5842)
					(thickness 0.1524)
				)
				(justify left)
			)
		)
		(property "Value" ""
			(at 0 0 0)
			(layer "F.Fab")
			(effects
				(font
					(size 1.27 1.27)
				)
			)
		)
		(duplicate_pad_numbers_are_jumpers no)
		(fp_line
			(start -9.253728 3.750056)
			(end 9.249918 3.750056)
			(stroke
				(width 0.1524)
				(type default)
			)
			(layer "F.SilkS")
		)
		(fp_line
			(start 0 3.750056)
			(end -9.253728 3.750056)
			(stroke
				(width 0.1524)
				(type default)
			)
			(layer "F.SilkS")
		)
		(fp_circle
			(center 0 3.750056)
			(end 9.249918 3.750056)
			(stroke
				(width 0.1524)
				(type default)
			)
			(fill no)
			(layer "F.SilkS")
		)
		(fp_poly
			(pts
				(arc
					(start 9.249918 3.750056)
					(mid 0 12.999974)
					(end -9.249918 3.750056)
				)
			)
			(stroke
				(width 0)
				(type default)
			)
			(fill yes)
			(layer "F.SilkS")
		)
		(fp_circle
			(center 0 3.750056)
			(end 9.249918 3.750056)
			(stroke
				(width 0.1)
				(type default)
			)
			(fill no)
			(layer "F.Fab")
		)
		(pad "1" thru_hole rect
			(at 0 0)
			(size 1.778 1.778)
			(drill 1.27)
			(layers "*.Cu" "*.Mask")
			(remove_unused_layers no)
			(net "P52V_HS2")
			(clearance 0)
			(padstack
				(mode front_inner_back)
				(layer "Inner"
					(shape circle)
					(size 1.778 1.778)
					(clearance 0)
				)
				(layer "B.Cu"
					(shape rect)
					(size 1.778 1.778)
					(clearance 0)
				)
			)
		)
		(pad "2" thru_hole circle
			(at 0 7.500112)
			(size 1.778 1.778)
			(drill 1.27)
			(layers "*.Cu" "*.Mask")
			(remove_unused_layers no)
			(net "GND")
			(clearance 0)
		)
	)
	(footprint ""
		(layer "F.Cu")
		(at 124.483876 -63.373)
		(property "Reference" "PQ39"
			(at 8.913114 -3.609848 0)
			(unlocked yes)
			(layer "F.SilkS")
			(effects
				(font
					(size 0.7874 0.5842)
					(thickness 0.1524)
				)
				(justify left)
			)
		)
		(property "Value" ""
			(at 0 0 0)
			(layer "F.Fab")
			(effects
				(font
					(size 1.27 1.27)
				)
			)
		)
		(duplicate_pad_numbers_are_jumpers no)
		(fp_line
			(start -7.649972 -4.99999)
			(end -7.649972 -3.3274)
			(stroke
				(width 0.1524)
				(type default)
			)
			(layer "F.SilkS")
		)
		(fp_line
			(start -7.649972 -1.7526)
			(end -7.649972 1.7526)
			(stroke
				(width 0.1524)
				(type default)
			)
			(layer "F.SilkS")
		)
		(fp_line
			(start -7.649972 3.3274)
			(end -7.649972 4.99999)
			(stroke
				(width 0.1524)
				(type default)
			)
			(layer "F.SilkS")
		)
		(fp_line
			(start -7.649972 4.99999)
			(end 5.115814 4.99999)
			(stroke
				(width 0.1524)
				(type default)
			)
			(layer "F.SilkS")
		)
		(fp_line
			(start 5.115814 -4.99999)
			(end -7.649972 -4.99999)
			(stroke
				(width 0.1524)
				(type default)
			)
			(layer "F.SilkS")
		)
		(fp_line
			(start 7.630414 4.99999)
			(end 7.649972 4.99999)
			(stroke
				(width 0.1524)
				(type default)
			)
			(layer "F.SilkS")
		)
		(fp_line
			(start 7.649972 -4.99999)
			(end 7.630414 -4.99999)
			(stroke
				(width 0.1524)
				(type default)
			)
			(layer "F.SilkS")
		)
		(fp_line
			(start 7.649972 4.99999)
			(end 7.649972 -4.99999)
			(stroke
				(width 0.1524)
				(type default)
			)
			(layer "F.SilkS")
		)
		(fp_line
			(start -7.649972 -4.99999)
			(end -7.649972 4.99999)
			(stroke
				(width 0.1)
				(type default)
			)
			(layer "F.Fab")
		)
		(fp_line
			(start -7.649972 4.99999)
			(end 7.649972 4.99999)
			(stroke
				(width 0.1)
				(type default)
			)
			(layer "F.Fab")
		)
		(fp_line
			(start 7.649972 -4.99999)
			(end -7.649972 -4.99999)
			(stroke
				(width 0.1)
				(type default)
			)
			(layer "F.Fab")
		)
		(fp_line
			(start 7.649972 4.99999)
			(end 7.649972 -4.99999)
			(stroke
				(width 0.1)
				(type default)
			)
			(layer "F.Fab")
		)
		(pad "D" smd circle
			(at 2.15011 0)
			(size 0 0)
			(layers "F.Cu" "F.Mask" "F.Paste")
			(net "P52V_HS2_DRAIN_1")
		)
		(pad "G" smd rect
			(at -7.050024 -2.54 270)
			(size 1.3208 3.0988)
			(layers "F.Cu" "F.Mask" "F.Paste")
			(net "P52V_HS2_GATE2")
		)
		(pad "S" smd rect
			(at -7.050024 2.54 270)
			(size 1.3208 3.0988)
			(layers "F.Cu" "F.Mask" "F.Paste")
			(net "P52V_HS2")
		)
		(zone
			(layer "F.Cu")
			(hatch none 0.5)
			(connect_pads
				(clearance 0)
			)
			(min_thickness 0.25)
			(keepout
				(tracks not_allowed)
				(vias allowed)
				(pads allowed)
				(copperpour not_allowed)
				(footprints allowed)
			)
			(placement
				(enabled no)
				(sheetname "")
			)
			(fill
				(thermal_gap 0.5)
				(thermal_bridge_width 0.5)
				(island_removal_mode 0)
			)
			(polygon
				(pts
					(xy 129.665476 -68.3514) (xy 116.838476 -68.3514) (xy 116.838476 -66.6242) (xy 119.048276 -66.6242)
					(xy 119.048276 -65.2018) (xy 116.838476 -65.2018) (xy 116.838476 -61.5442) (xy 119.048276 -61.5442)
					(xy 119.048276 -60.1218) (xy 116.838476 -60.1218) (xy 116.838476 -58.3946) (xy 129.665476 -58.3946)
					(xy 129.665476 -59.563) (xy 123.467876 -59.563) (xy 123.467876 -67.183) (xy 129.665476 -67.183)
				)
			)
		)
	)
	(footprint ""
		(layer "F.Cu")
		(at 166.543736 -67.564 180)
		(property "Reference" "R5895"
			(at 0 0 180)
			(layer "F.SilkS")
			(hide yes)
			(effects
				(font
					(size 1.27 1.27)
				)
			)
		)
		(property "Value" ""
			(at 0 0 180)
			(layer "F.Fab")
			(effects
				(font
					(size 1.27 1.27)
				)
			)
		)
		(duplicate_pad_numbers_are_jumpers no)
		(fp_line
			(start 0.7874 0.4064)
			(end -0.7874 0.4064)
			(stroke
				(width 0.1524)
				(type default)
			)
			(layer "F.SilkS")
		)
		(fp_line
			(start 0.7874 -0.4064)
			(end 0.7874 0.4064)
			(stroke
				(width 0.1524)
				(type default)
			)
			(layer "F.SilkS")
		)
		(fp_line
			(start -0.7874 0.4064)
			(end -0.7874 -0.4064)
			(stroke
				(width 0.1524)
				(type default)
			)
			(layer "F.SilkS")
		)
		(fp_line
			(start -0.7874 -0.4064)
			(end 0.7874 -0.4064)
			(stroke
				(width 0.1524)
				(type default)
			)
			(layer "F.SilkS")
		)
		(fp_line
			(start 0.67945 0.3048)
			(end 0.120396 0.3048)
			(stroke
				(width 0.1)
				(type default)
			)
			(layer "F.Fab")
		)
		(fp_line
			(start 0.67945 -0.3048)
			(end 0.67945 0.3048)
			(stroke
				(width 0.1)
				(type default)
			)
			(layer "F.Fab")
		)
		(fp_line
			(start 0.12065 -0.2794)
			(end 0.12065 -0.3048)
			(stroke
				(width 0.1)
				(type default)
			)
			(layer "F.Fab")
		)
		(fp_line
			(start 0.12065 -0.3048)
			(end 0.67945 -0.3048)
			(stroke
				(width 0.1)
				(type default)
			)
			(layer "F.Fab")
		)
		(fp_line
			(start 0.120396 0.3048)
			(end 0.120396 0.2794)
			(stroke
				(width 0.1)
				(type default)
			)
			(layer "F.Fab")
		)
		(fp_line
			(start 0.120396 0.2794)
			(end -0.12065 0.2794)
			(stroke
				(width 0.1)
				(type default)
			)
			(layer "F.Fab")
		)
		(fp_line
			(start -0.12065 0.3048)
			(end -0.67945 0.3048)
			(stroke
				(width 0.1)
				(type default)
			)
			(layer "F.Fab")
		)
		(fp_line
			(start -0.12065 0.2794)
			(end -0.12065 0.3048)
			(stroke
				(width 0.1)
				(type default)
			)
			(layer "F.Fab")
		)
		(fp_line
			(start -0.12065 -0.2794)
			(end 0.12065 -0.2794)
			(stroke
				(width 0.1)
				(type default)
			)
			(layer "F.Fab")
		)
		(fp_line
			(start -0.12065 -0.305054)
			(end -0.12065 -0.2794)
			(stroke
				(width 0.1)
				(type default)
			)
			(layer "F.Fab")
		)
		(fp_line
			(start -0.67945 0.3048)
			(end -0.67945 -0.305054)
			(stroke
				(width 0.1)
				(type default)
			)
			(layer "F.Fab")
		)
		(fp_line
			(start -0.67945 -0.305054)
			(end -0.12065 -0.305054)
			(stroke
				(width 0.1)
				(type default)
			)
			(layer "F.Fab")
		)
		(pad "1" smd circle
			(at -0.40005 0 180)
			(size 0 0)
			(layers "F.Cu" "F.Mask" "F.Paste")
			(net "P52V_HS2_ADR1")
		)
		(pad "2" smd circle
			(at 0.40005 0 180)
			(size 0 0)
			(layers "F.Cu" "F.Mask" "F.Paste")
			(net "GND1_FIELD_SIGNAL")
		)
	)
	(footprint ""
		(layer "F.Cu")
		(at 56.799988 -156.830014 180)
		(property "Reference" "J3"
			(at 4.983988 -7.758684 0)
			(unlocked yes)
			(layer "F.SilkS")
			(effects
				(font
					(size 0.7874 0.5842)
					(thickness 0.1524)
				)
				(justify left)
			)
		)
		(property "Value" ""
			(at 0 0 180)
			(layer "F.Fab")
			(effects
				(font
					(size 1.27 1.27)
				)
			)
		)
		(duplicate_pad_numbers_are_jumpers no)
		(fp_line
			(start 12.925044 28.450032)
			(end -4.92506 28.450032)
			(stroke
				(width 0.1524)
				(type default)
			)
			(layer "F.SilkS")
		)
		(fp_line
			(start 12.925044 -6.849872)
			(end 12.925044 28.450032)
			(stroke
				(width 0.1524)
				(type default)
			)
			(layer "F.SilkS")
		)
		(fp_line
			(start 9.92505 25.450038)
			(end -1.925066 25.450038)
			(stroke
				(width 0.1524)
				(type default)
			)
			(layer "F.SilkS")
		)
		(fp_line
			(start 9.92505 -3.850132)
			(end 9.92505 25.450038)
			(stroke
				(width 0.1524)
				(type default)
			)
			(layer "F.SilkS")
		)
		(fp_line
			(start -1.925066 25.450038)
			(end -1.925066 -3.850132)
			(stroke
				(width 0.1524)
				(type default)
			)
			(layer "F.SilkS")
		)
		(fp_line
			(start -1.925066 14.99997)
			(end 9.92505 14.99997)
			(stroke
				(width 0.1524)
				(type default)
			)
			(layer "F.SilkS")
		)
		(fp_line
			(start -1.925066 -3.850132)
			(end 9.92505 -3.850132)
			(stroke
				(width 0.1524)
				(type default)
			)
			(layer "F.SilkS")
		)
		(fp_line
			(start -4.92506 28.450032)
			(end -4.92506 -6.849872)
			(stroke
				(width 0.1524)
				(type default)
			)
			(layer "F.SilkS")
		)
		(fp_line
			(start -4.92506 -6.849872)
			(end 12.925044 -6.849872)
			(stroke
				(width 0.1524)
				(type default)
			)
			(layer "F.SilkS")
		)
		(fp_poly
			(pts
				(xy 0.045974 -1.23571) (xy 0.807974 -3.14071) (xy -0.716026 -3.14071)
			)
			(stroke
				(width 0)
				(type default)
			)
			(fill yes)
			(layer "F.SilkS")
		)
		(fp_line
			(start 12.925044 28.450032)
			(end -4.92506 28.450032)
			(stroke
				(width 0.1524)
				(type default)
			)
			(layer "B.SilkS")
		)
		(fp_line
			(start 12.925044 -6.849872)
			(end 12.925044 28.450032)
			(stroke
				(width 0.1524)
				(type default)
			)
			(layer "B.SilkS")
		)
		(fp_line
			(start -4.92506 28.450032)
			(end -4.92506 -6.849872)
			(stroke
				(width 0.1524)
				(type default)
			)
			(layer "B.SilkS")
		)
		(fp_line
			(start -4.92506 -6.849872)
			(end 12.925044 -6.849872)
			(stroke
				(width 0.1524)
				(type default)
			)
			(layer "B.SilkS")
		)
		(fp_line
			(start 12.925044 28.450032)
			(end -4.92506 28.450032)
			(stroke
				(width 0.1)
				(type default)
			)
			(layer "B.Fab")
		)
		(fp_line
			(start 12.925044 -6.849872)
			(end 12.925044 28.450032)
			(stroke
				(width 0.1)
				(type default)
			)
			(layer "B.Fab")
		)
		(fp_line
			(start -4.92506 28.450032)
			(end -4.92506 -6.849872)
			(stroke
				(width 0.1)
				(type default)
			)
			(layer "B.Fab")
		)
		(fp_line
			(start -4.92506 -6.849872)
			(end 12.925044 -6.849872)
			(stroke
				(width 0.1)
				(type default)
			)
			(layer "B.Fab")
		)
		(fp_line
			(start 9.92505 25.450038)
			(end -1.925066 25.450038)
			(stroke
				(width 0.1)
				(type default)
			)
			(layer "F.Fab")
		)
		(fp_line
			(start 9.92505 -3.850132)
			(end 9.92505 25.450038)
			(stroke
				(width 0.1)
				(type default)
			)
			(layer "F.Fab")
		)
		(fp_line
			(start -1.925066 25.450038)
			(end -1.925066 -3.850132)
			(stroke
				(width 0.1)
				(type default)
			)
			(layer "F.Fab")
		)
		(fp_line
			(start -1.925066 -3.850132)
			(end 9.92505 -3.850132)
			(stroke
				(width 0.1)
				(type default)
			)
			(layer "F.Fab")
		)
		(fp_poly
			(pts
				(xy -2.108708 0) (xy -4.013708 -0.762) (xy -4.013708 0.762)
			)
			(stroke
				(width 0)
				(type default)
			)
			(fill yes)
			(layer "F.Fab")
		)
		(fp_text user "PRESS-FIT"
			(at 7.474458 -5.30098 0)
			(unlocked yes)
			(layer "F.SilkS")
			(effects
				(font
					(size 0.7874 0.5842)
					(thickness 0.1524)
				)
				(justify left)
			)
		)
		(fp_text user "PRESS-FIT"
			(at 11.594338 -4.684014 270)
			(unlocked yes)
			(layer "B.SilkS")
			(effects
				(font
					(size 1.905 1.4224)
					(thickness 0.1524)
				)
				(justify left mirror)
			)
		)
		(fp_text user "PRESS-FIT"
			(at 11.346942 12.866116 90)
			(unlocked yes)
			(layer "B.Fab")
			(effects
				(font
					(size 1.905 1.4224)
					(thickness 0.1524)
				)
				(justify left mirror)
			)
		)
		(fp_text user "PRESS-FIT"
			(at 11.346942 -3.872484 90)
			(unlocked yes)
			(layer "F.Fab")
			(effects
				(font
					(size 1.905 1.4224)
					(thickness 0.1524)
				)
				(justify left)
			)
		)
		(pad "" np_thru_hole circle
			(at 3.999992 5.500116 180)
			(size 2.1082 2.1082)
			(drill 2.1082)
			(layers "*.Cu" "*.Mask")
			(clearance 0.381)
			(thermal_gap 0.381)
		)
		(pad "A1" thru_hole rect
			(at 0 0 180)
			(size 1.156208 1.156208)
			(drill 0.749808)
			(layers "*.Cu" "*.Mask")
			(remove_unused_layers no)
			(net "P52V_HS2")
			(clearance 0.0508)
			(thermal_gap 0.0508)
			(padstack
				(mode front_inner_back)
				(layer "Inner"
					(shape circle)
					(size 1.156208 1.156208)
					(clearance 0.0508)
				)
				(layer "B.Cu"
					(shape rect)
					(size 1.156208 1.156208)
					(clearance 0.0508)
				)
			)
		)
		(pad "A2" thru_hole circle
			(at 0 1.999996 180)
			(size 1.156208 1.156208)
			(drill 0.749808)
			(layers "*.Cu" "*.Mask")
			(remove_unused_layers no)
			(net "P52V_HS2")
			(clearance 0.0508)
			(thermal_gap 0.0508)
		)
		(pad "A3" thru_hole circle
			(at 0 3.999992 180)
			(size 1.156208 1.156208)
			(drill 0.749808)
			(layers "*.Cu" "*.Mask")
			(remove_unused_layers no)
			(net "P52V_HS2")
			(clearance 0.0508)
			(thermal_gap 0.0508)
		)
		(pad "A4" thru_hole circle
			(at 1.999996 0 180)
			(size 1.156208 1.156208)
			(drill 0.749808)
			(layers "*.Cu" "*.Mask")
			(remove_unused_layers no)
			(net "P52V_HS2")
			(clearance 0.0508)
			(thermal_gap 0.0508)
		)
		(pad "A5" thru_hole circle
			(at 1.999996 1.999996 180)
			(size 1.156208 1.156208)
			(drill 0.749808)
			(layers "*.Cu" "*.Mask")
			(remove_unused_layers no)
			(net "P52V_HS2")
			(clearance 0.0508)
			(thermal_gap 0.0508)
		)
		(pad "A6" thru_hole circle
			(at 1.999996 3.999992 180)
			(size 1.156208 1.156208)
			(drill 0.749808)
			(layers "*.Cu" "*.Mask")
			(remove_unused_layers no)
			(net "P52V_HS2")
			(clearance 0.0508)
			(thermal_gap 0.0508)
		)
		(pad "B1" thru_hole circle
			(at 7.999984 0 180)
			(size 1.156208 1.156208)
			(drill 0.749808)
			(layers "*.Cu" "*.Mask")
			(remove_unused_layers no)
			(net "P52V_HS2")
			(clearance 0.0508)
			(thermal_gap 0.0508)
		)
		(pad "B2" thru_hole circle
			(at 7.999984 1.999996 180)
			(size 1.156208 1.156208)
			(drill 0.749808)
			(layers "*.Cu" "*.Mask")
			(remove_unused_layers no)
			(net "P52V_HS2")
			(clearance 0.0508)
			(thermal_gap 0.0508)
		)
		(pad "B3" thru_hole circle
			(at 7.999984 3.999992 180)
			(size 1.156208 1.156208)
			(drill 0.749808)
			(layers "*.Cu" "*.Mask")
			(remove_unused_layers no)
			(net "P52V_HS2")
			(clearance 0.0508)
			(thermal_gap 0.0508)
		)
		(pad "B4" thru_hole circle
			(at 5.999988 0 180)
			(size 1.156208 1.156208)
			(drill 0.749808)
			(layers "*.Cu" "*.Mask")
			(remove_unused_layers no)
			(net "P52V_HS2")
			(clearance 0.0508)
			(thermal_gap 0.0508)
		)
		(pad "B5" thru_hole circle
			(at 5.999988 1.999996 180)
			(size 1.156208 1.156208)
			(drill 0.749808)
			(layers "*.Cu" "*.Mask")
			(remove_unused_layers no)
			(net "P52V_HS2")
			(clearance 0.0508)
			(thermal_gap 0.0508)
		)
		(pad "B6" thru_hole circle
			(at 5.999988 3.999992 180)
			(size 1.156208 1.156208)
			(drill 0.749808)
			(layers "*.Cu" "*.Mask")
			(remove_unused_layers no)
			(net "P52V_HS2")
			(clearance 0.0508)
			(thermal_gap 0.0508)
		)
		(pad "C1" thru_hole circle
			(at 7.999984 7.999984 180)
			(size 1.156208 1.156208)
			(drill 0.749808)
			(layers "*.Cu" "*.Mask")
			(remove_unused_layers no)
			(net "GND")
			(clearance 0.0508)
			(thermal_gap 0.0508)
		)
		(pad "C2" thru_hole circle
			(at 7.999984 9.99998 180)
			(size 1.156208 1.156208)
			(drill 0.749808)
			(layers "*.Cu" "*.Mask")
			(remove_unused_layers no)
			(net "GND")
			(clearance 0.0508)
			(thermal_gap 0.0508)
		)
		(pad "C3" thru_hole circle
			(at 7.999984 11.999976 180)
			(size 1.156208 1.156208)
			(drill 0.749808)
			(layers "*.Cu" "*.Mask")
			(remove_unused_layers no)
			(net "GND")
			(clearance 0.0508)
			(thermal_gap 0.0508)
		)
		(pad "C4" thru_hole circle
			(at 5.999988 7.999984 180)
			(size 1.156208 1.156208)
			(drill 0.749808)
			(layers "*.Cu" "*.Mask")
			(remove_unused_layers no)
			(net "GND")
			(clearance 0.0508)
			(thermal_gap 0.0508)
		)
		(pad "C5" thru_hole circle
			(at 5.999988 9.99998 180)
			(size 1.156208 1.156208)
			(drill 0.749808)
			(layers "*.Cu" "*.Mask")
			(remove_unused_layers no)
			(net "GND")
			(clearance 0.0508)
			(thermal_gap 0.0508)
		)
		(pad "C6" thru_hole circle
			(at 5.999988 11.999976 180)
			(size 1.156208 1.156208)
			(drill 0.749808)
			(layers "*.Cu" "*.Mask")
			(remove_unused_layers no)
			(net "GND")
			(clearance 0.0508)
			(thermal_gap 0.0508)
		)
		(pad "D1" thru_hole circle
			(at 0 7.999984 180)
			(size 1.156208 1.156208)
			(drill 0.749808)
			(layers "*.Cu" "*.Mask")
			(remove_unused_layers no)
			(net "GND")
			(clearance 0.0508)
			(thermal_gap 0.0508)
		)
		(pad "D2" thru_hole circle
			(at 0 9.99998 180)
			(size 1.156208 1.156208)
			(drill 0.749808)
			(layers "*.Cu" "*.Mask")
			(remove_unused_layers no)
			(net "GND")
			(clearance 0.0508)
			(thermal_gap 0.0508)
		)
		(pad "D3" thru_hole circle
			(at 0 11.999976 180)
			(size 1.156208 1.156208)
			(drill 0.749808)
			(layers "*.Cu" "*.Mask")
			(remove_unused_layers no)
			(net "GND")
			(clearance 0.0508)
			(thermal_gap 0.0508)
		)
		(pad "D4" thru_hole circle
			(at 1.999996 7.999984 180)
			(size 1.156208 1.156208)
			(drill 0.749808)
			(layers "*.Cu" "*.Mask")
			(remove_unused_layers no)
			(net "GND")
			(clearance 0.0508)
			(thermal_gap 0.0508)
		)
		(pad "D5" thru_hole circle
			(at 1.999996 9.99998 180)
			(size 1.156208 1.156208)
			(drill 0.749808)
			(layers "*.Cu" "*.Mask")
			(remove_unused_layers no)
			(net "GND")
			(clearance 0.0508)
			(thermal_gap 0.0508)
		)
		(pad "D6" thru_hole circle
			(at 1.999996 11.999976 180)
			(size 1.156208 1.156208)
			(drill 0.749808)
			(layers "*.Cu" "*.Mask")
			(remove_unused_layers no)
			(net "GND")
			(clearance 0.0508)
			(thermal_gap 0.0508)
		)
		(zone
			(layers "F.Cu" "B.Cu" "In1.Cu" "In2.Cu" "In3.Cu" "In4.Cu" "In5.Cu" "In6.Cu"
				"In7.Cu" "In8.Cu"
			)
			(hatch none 0.5)
			(connect_pads
				(clearance 0)
			)
			(min_thickness 0.25)
			(keepout
				(tracks not_allowed)
				(vias allowed)
				(pads allowed)
				(copperpour not_allowed)
				(footprints allowed)
			)
			(placement
				(enabled no)
				(sheetname "")
			)
			(fill
				(thermal_gap 0.5)
				(thermal_bridge_width 0.5)
				(island_removal_mode 0)
			)
			(polygon
				(pts
					(arc
						(start 54.260496 -162.329876)
						(mid 51.339496 -162.330384)
						(end 54.260496 -162.329876)
					)
				)
			)
		)
		(zone
			(layer "B.Cu")
			(hatch none 0.5)
			(connect_pads
				(clearance 0)
			)
			(min_thickness 0.25)
			(keepout
				(tracks allowed)
				(vias not_allowed)
				(pads allowed)
				(copperpour not_allowed)
				(footprints allowed)
			)
			(placement
				(enabled no)
				(sheetname "")
			)
			(fill
				(thermal_gap 0.5)
				(thermal_bridge_width 0.5)
				(island_removal_mode 0)
			)
			(polygon
				(pts
					(xy 51.441096 -169.46753) (xy 48.164496 -169.46753) (xy 48.164496 -164.18433) (xy 51.441096 -164.18433)
				)
			)
		)
		(zone
			(layer "B.Cu")
			(hatch none 0.5)
			(connect_pads
				(clearance 0)
			)
			(min_thickness 0.25)
			(keepout
				(tracks allowed)
				(vias not_allowed)
				(pads allowed)
				(copperpour not_allowed)
				(footprints allowed)
			)
			(placement
				(enabled no)
				(sheetname "")
			)
			(fill
				(thermal_gap 0.5)
				(thermal_bridge_width 0.5)
				(island_removal_mode 0)
			)
			(polygon
				(pts
					(xy 51.441096 -161.46653) (xy 48.164496 -161.46653) (xy 48.164496 -156.18333) (xy 51.441096 -156.18333)
				)
			)
		)
		(zone
			(layer "B.Cu")
			(hatch none 0.5)
			(connect_pads
				(clearance 0)
			)
			(min_thickness 0.25)
			(keepout
				(tracks allowed)
				(vias not_allowed)
				(pads allowed)
				(copperpour not_allowed)
				(footprints allowed)
			)
			(placement
				(enabled no)
				(sheetname "")
			)
			(fill
				(thermal_gap 0.5)
				(thermal_bridge_width 0.5)
				(island_removal_mode 0)
			)
			(polygon
				(pts
					(xy 57.435496 -169.46753) (xy 54.158896 -169.46753) (xy 54.158896 -164.18433) (xy 57.435496 -164.18433)
				)
			)
		)
		(zone
			(layer "B.Cu")
			(hatch none 0.5)
			(connect_pads
				(clearance 0)
			)
			(min_thickness 0.25)
			(keepout
				(tracks allowed)
				(vias not_allowed)
				(pads allowed)
				(copperpour not_allowed)
				(footprints allowed)
			)
			(placement
				(enabled no)
				(sheetname "")
			)
			(fill
				(thermal_gap 0.5)
				(thermal_bridge_width 0.5)
				(island_removal_mode 0)
			)
			(polygon
				(pts
					(xy 57.435496 -161.46653) (xy 54.158896 -161.46653) (xy 54.158896 -156.18333) (xy 57.435496 -156.18333)
				)
			)
		)
	)
	(footprint ""
		(layer "F.Cu")
		(at 77.0001 -156.830014 180)
		(property "Reference" "J4"
			(at 3.7211 -10.603484 0)
			(unlocked yes)
			(layer "F.SilkS")
			(effects
				(font
					(size 0.7874 0.5842)
					(thickness 0.1524)
				)
				(justify left)
			)
		)
		(property "Value" ""
			(at 0 0 180)
			(layer "F.Fab")
			(effects
				(font
					(size 1.27 1.27)
				)
			)
		)
		(duplicate_pad_numbers_are_jumpers no)
		(fp_line
			(start 18.925032 28.450032)
			(end -4.92506 28.450032)
			(stroke
				(width 0.1524)
				(type default)
			)
			(layer "F.SilkS")
		)
		(fp_line
			(start 18.925032 -6.849872)
			(end 18.925032 28.450032)
			(stroke
				(width 0.1524)
				(type default)
			)
			(layer "F.SilkS")
		)
		(fp_line
			(start 15.925038 25.450038)
			(end 15.925038 -3.849878)
			(stroke
				(width 0.1524)
				(type default)
			)
			(layer "F.SilkS")
		)
		(fp_line
			(start 15.925038 14.99997)
			(end -1.925066 14.99997)
			(stroke
				(width 0.1524)
				(type default)
			)
			(layer "F.SilkS")
		)
		(fp_line
			(start 15.925038 -3.849878)
			(end -1.925066 -3.849878)
			(stroke
				(width 0.1524)
				(type default)
			)
			(layer "F.SilkS")
		)
		(fp_line
			(start 2.0701 -6.849872)
			(end 18.925032 -6.849872)
			(stroke
				(width 0.1524)
				(type default)
			)
			(layer "F.SilkS")
		)
		(fp_line
			(start -1.925066 25.450038)
			(end 15.925038 25.450038)
			(stroke
				(width 0.1524)
				(type default)
			)
			(layer "F.SilkS")
		)
		(fp_line
			(start -1.925066 -3.849878)
			(end -1.925066 25.450038)
			(stroke
				(width 0.1524)
				(type default)
			)
			(layer "F.SilkS")
		)
		(fp_line
			(start -4.92506 28.450032)
			(end -4.92506 -4.125214)
			(stroke
				(width 0.1524)
				(type default)
			)
			(layer "F.SilkS")
		)
		(fp_poly
			(pts
				(xy -3.795014 -0.762) (xy -3.795014 0.762) (xy -2.271014 0)
			)
			(stroke
				(width 0)
				(type default)
			)
			(fill yes)
			(layer "F.SilkS")
		)
		(fp_line
			(start 18.925032 28.450032)
			(end -4.92506 28.450032)
			(stroke
				(width 0.1524)
				(type default)
			)
			(layer "B.SilkS")
		)
		(fp_line
			(start 18.925032 -6.849872)
			(end 18.925032 28.450032)
			(stroke
				(width 0.1524)
				(type default)
			)
			(layer "B.SilkS")
		)
		(fp_line
			(start -4.92506 28.450032)
			(end -4.92506 -6.849872)
			(stroke
				(width 0.1524)
				(type default)
			)
			(layer "B.SilkS")
		)
		(fp_line
			(start -4.92506 -6.849872)
			(end 18.925032 -6.849872)
			(stroke
				(width 0.1524)
				(type default)
			)
			(layer "B.SilkS")
		)
		(fp_line
			(start 18.925032 28.450032)
			(end -4.92506 28.450032)
			(stroke
				(width 0.1)
				(type default)
			)
			(layer "B.Fab")
		)
		(fp_line
			(start 18.925032 -6.849872)
			(end 18.925032 28.450032)
			(stroke
				(width 0.1)
				(type default)
			)
			(layer "B.Fab")
		)
		(fp_line
			(start -4.92506 28.450032)
			(end -4.92506 -6.849872)
			(stroke
				(width 0.1)
				(type default)
			)
			(layer "B.Fab")
		)
		(fp_line
			(start -4.92506 -6.849872)
			(end 18.925032 -6.849872)
			(stroke
				(width 0.1)
				(type default)
			)
			(layer "B.Fab")
		)
		(fp_line
			(start 15.925038 25.450038)
			(end 15.925038 -3.849878)
			(stroke
				(width 0.1)
				(type default)
			)
			(layer "F.Fab")
		)
		(fp_line
			(start 15.925038 -3.849878)
			(end -1.925066 -3.849878)
			(stroke
				(width 0.1)
				(type default)
			)
			(layer "F.Fab")
		)
		(fp_line
			(start -1.925066 25.450038)
			(end 15.925038 25.450038)
			(stroke
				(width 0.1)
				(type default)
			)
			(layer "F.Fab")
		)
		(fp_line
			(start -1.925066 -3.849878)
			(end -1.925066 25.450038)
			(stroke
				(width 0.1)
				(type default)
			)
			(layer "F.Fab")
		)
		(fp_poly
			(pts
				(xy -3.795014 -0.762) (xy -3.795014 0.762) (xy -2.271014 0)
			)
			(stroke
				(width 0)
				(type default)
			)
			(fill yes)
			(layer "F.Fab")
		)
		(fp_text user "D4"
			(at 16.895572 12.001246 180)
			(unlocked yes)
			(layer "F.SilkS")
			(effects
				(font
					(size 0.7874 0.5842)
					(thickness 0.1524)
				)
			)
		)
		(fp_text user "D5"
			(at 16.895572 10.00125 180)
			(unlocked yes)
			(layer "F.SilkS")
			(effects
				(font
					(size 0.7874 0.5842)
					(thickness 0.1524)
				)
			)
		)
		(fp_text user "D6"
			(at 16.895572 8.001254 180)
			(unlocked yes)
			(layer "F.SilkS")
			(effects
				(font
					(size 0.7874 0.5842)
					(thickness 0.1524)
				)
			)
		)
		(fp_text user "C4"
			(at 16.895572 4.001262 180)
			(unlocked yes)
			(layer "F.SilkS")
			(effects
				(font
					(size 0.7874 0.5842)
					(thickness 0.1524)
				)
			)
		)
		(fp_text user "C5"
			(at 16.895572 2.001266 180)
			(unlocked yes)
			(layer "F.SilkS")
			(effects
				(font
					(size 0.7874 0.5842)
					(thickness 0.1524)
				)
			)
		)
		(fp_text user "C6"
			(at 16.895572 0.00127 180)
			(unlocked yes)
			(layer "F.SilkS")
			(effects
				(font
					(size 0.7874 0.5842)
					(thickness 0.1524)
				)
			)
		)
		(fp_text user "PRESS-FIT"
			(at 14.7193 -5.382514 0)
			(unlocked yes)
			(layer "F.SilkS")
			(effects
				(font
					(size 1.27 0.9652)
					(thickness 0.1524)
				)
				(justify left)
			)
		)
		(fp_text user "F3"
			(at -1.3716 12.019026 180)
			(unlocked yes)
			(layer "F.SilkS")
			(effects
				(font
					(size 0.635 0.4064)
					(thickness 0.1524)
				)
			)
		)
		(fp_text user "F2"
			(at -1.3716 10.01903 180)
			(unlocked yes)
			(layer "F.SilkS")
			(effects
				(font
					(size 0.635 0.4064)
					(thickness 0.1524)
				)
			)
		)
		(fp_text user "F1"
			(at -1.3716 8.019034 180)
			(unlocked yes)
			(layer "F.SilkS")
			(effects
				(font
					(size 0.635 0.4064)
					(thickness 0.1524)
				)
			)
		)
		(fp_text user "A3"
			(at -1.3716 4.019042 180)
			(unlocked yes)
			(layer "F.SilkS")
			(effects
				(font
					(size 0.635 0.4064)
					(thickness 0.1524)
				)
			)
		)
		(fp_text user "A2"
			(at -1.3716 2.019046 180)
			(unlocked yes)
			(layer "F.SilkS")
			(effects
				(font
					(size 0.635 0.4064)
					(thickness 0.1524)
				)
			)
		)
		(fp_text user "D4"
			(at 16.223996 11.947906 0)
			(unlocked yes)
			(layer "B.SilkS")
			(effects
				(font
					(size 0.7874 0.5842)
					(thickness 0.1524)
				)
				(justify mirror)
			)
		)
		(fp_text user "D5"
			(at 16.223996 9.94791 0)
			(unlocked yes)
			(layer "B.SilkS")
			(effects
				(font
					(size 0.7874 0.5842)
					(thickness 0.1524)
				)
				(justify mirror)
			)
		)
		(fp_text user "D6"
			(at 16.223996 7.947914 0)
			(unlocked yes)
			(layer "B.SilkS")
			(effects
				(font
					(size 0.7874 0.5842)
					(thickness 0.1524)
				)
				(justify mirror)
			)
		)
		(fp_text user "C4"
			(at 16.223996 3.947922 0)
			(unlocked yes)
			(layer "B.SilkS")
			(effects
				(font
					(size 0.7874 0.5842)
					(thickness 0.1524)
				)
				(justify mirror)
			)
		)
		(fp_text user "C5"
			(at 16.223996 1.947926 0)
			(unlocked yes)
			(layer "B.SilkS")
			(effects
				(font
					(size 0.7874 0.5842)
					(thickness 0.1524)
				)
				(justify mirror)
			)
		)
		(fp_text user "C6"
			(at 16.223996 -0.05207 0)
			(unlocked yes)
			(layer "B.SilkS")
			(effects
				(font
					(size 0.7874 0.5842)
					(thickness 0.1524)
				)
				(justify mirror)
			)
		)
		(fp_text user "F3"
			(at -1.457452 11.973306 0)
			(unlocked yes)
			(layer "B.SilkS")
			(effects
				(font
					(size 0.7874 0.5842)
					(thickness 0.1524)
				)
				(justify mirror)
			)
		)
		(fp_text user "F2"
			(at -1.457452 9.97331 0)
			(unlocked yes)
			(layer "B.SilkS")
			(effects
				(font
					(size 0.7874 0.5842)
					(thickness 0.1524)
				)
				(justify mirror)
			)
		)
		(fp_text user "F1"
			(at -1.457452 7.973314 0)
			(unlocked yes)
			(layer "B.SilkS")
			(effects
				(font
					(size 0.7874 0.5842)
					(thickness 0.1524)
				)
				(justify mirror)
			)
		)
		(fp_text user "A3"
			(at -1.457452 3.973322 0)
			(unlocked yes)
			(layer "B.SilkS")
			(effects
				(font
					(size 0.7874 0.5842)
					(thickness 0.1524)
				)
				(justify mirror)
			)
		)
		(fp_text user "A2"
			(at -1.457452 1.973326 0)
			(unlocked yes)
			(layer "B.SilkS")
			(effects
				(font
					(size 0.7874 0.5842)
					(thickness 0.1524)
				)
				(justify mirror)
			)
		)
		(fp_text user "A1"
			(at -1.482852 -0.007874 0)
			(unlocked yes)
			(layer "B.SilkS")
			(effects
				(font
					(size 0.7874 0.5842)
					(thickness 0.1524)
				)
				(justify mirror)
			)
		)
		(fp_text user "PRESS-FIT"
			(at -4.4323 -3.572764 0)
			(unlocked yes)
			(layer "B.SilkS")
			(effects
				(font
					(size 1.905 1.4224)
					(thickness 0.1524)
				)
				(justify left mirror)
			)
		)
		(fp_text user "D4"
			(at 15.461996 12.001246 180)
			(unlocked yes)
			(layer "B.Fab")
			(effects
				(font
					(size 0.7874 0.5842)
					(thickness 0.1524)
				)
				(justify mirror)
			)
		)
		(fp_text user "D5"
			(at 15.461996 10.00125 180)
			(unlocked yes)
			(layer "B.Fab")
			(effects
				(font
					(size 0.7874 0.5842)
					(thickness 0.1524)
				)
				(justify mirror)
			)
		)
		(fp_text user "D6"
			(at 15.461996 8.001254 180)
			(unlocked yes)
			(layer "B.Fab")
			(effects
				(font
					(size 0.7874 0.5842)
					(thickness 0.1524)
				)
				(justify mirror)
			)
		)
		(fp_text user "C4"
			(at 15.461996 4.001262 180)
			(unlocked yes)
			(layer "B.Fab")
			(effects
				(font
					(size 0.7874 0.5842)
					(thickness 0.1524)
				)
				(justify mirror)
			)
		)
		(fp_text user "C5"
			(at 15.461996 2.001266 180)
			(unlocked yes)
			(layer "B.Fab")
			(effects
				(font
					(size 0.7874 0.5842)
					(thickness 0.1524)
				)
				(justify mirror)
			)
		)
		(fp_text user "C6"
			(at 15.461996 0.00127 180)
			(unlocked yes)
			(layer "B.Fab")
			(effects
				(font
					(size 0.7874 0.5842)
					(thickness 0.1524)
				)
				(justify mirror)
			)
		)
		(fp_text user "PRESS-FIT"
			(at 15.452598 -5.22097 180)
			(unlocked yes)
			(layer "B.Fab")
			(effects
				(font
					(size 1.905 1.4224)
					(thickness 0.1524)
				)
				(justify left mirror)
			)
		)
		(fp_text user "F3"
			(at -1.457452 12.026646 180)
			(unlocked yes)
			(layer "B.Fab")
			(effects
				(font
					(size 0.7874 0.5842)
					(thickness 0.1524)
				)
				(justify mirror)
			)
		)
		(fp_text user "F2"
			(at -1.457452 10.02665 180)
			(unlocked yes)
			(layer "B.Fab")
			(effects
				(font
					(size 0.7874 0.5842)
					(thickness 0.1524)
				)
				(justify mirror)
			)
		)
		(fp_text user "F1"
			(at -1.457452 8.026654 180)
			(unlocked yes)
			(layer "B.Fab")
			(effects
				(font
					(size 0.7874 0.5842)
					(thickness 0.1524)
				)
				(justify mirror)
			)
		)
		(fp_text user "A3"
			(at -1.457452 4.026662 180)
			(unlocked yes)
			(layer "B.Fab")
			(effects
				(font
					(size 0.7874 0.5842)
					(thickness 0.1524)
				)
				(justify mirror)
			)
		)
		(fp_text user "A2"
			(at -1.457452 2.026666 180)
			(unlocked yes)
			(layer "B.Fab")
			(effects
				(font
					(size 0.7874 0.5842)
					(thickness 0.1524)
				)
				(justify mirror)
			)
		)
		(fp_text user "A1"
			(at -1.482852 0.045466 180)
			(unlocked yes)
			(layer "B.Fab")
			(effects
				(font
					(size 0.7874 0.5842)
					(thickness 0.1524)
				)
				(justify mirror)
			)
		)
		(fp_text user "D4"
			(at 16.895572 12.001246 180)
			(unlocked yes)
			(layer "F.Fab")
			(effects
				(font
					(size 0.7874 0.5842)
					(thickness 0.1524)
				)
			)
		)
		(fp_text user "D5"
			(at 16.895572 10.00125 180)
			(unlocked yes)
			(layer "F.Fab")
			(effects
				(font
					(size 0.7874 0.5842)
					(thickness 0.1524)
				)
			)
		)
		(fp_text user "D6"
			(at 16.895572 8.001254 180)
			(unlocked yes)
			(layer "F.Fab")
			(effects
				(font
					(size 0.7874 0.5842)
					(thickness 0.1524)
				)
			)
		)
		(fp_text user "C4"
			(at 16.895572 4.001262 180)
			(unlocked yes)
			(layer "F.Fab")
			(effects
				(font
					(size 0.7874 0.5842)
					(thickness 0.1524)
				)
			)
		)
		(fp_text user "C5"
			(at 16.895572 2.001266 180)
			(unlocked yes)
			(layer "F.Fab")
			(effects
				(font
					(size 0.7874 0.5842)
					(thickness 0.1524)
				)
			)
		)
		(fp_text user "C6"
			(at 16.895572 0.00127 180)
			(unlocked yes)
			(layer "F.Fab")
			(effects
				(font
					(size 0.7874 0.5842)
					(thickness 0.1524)
				)
			)
		)
		(fp_text user "PRESS-FIT"
			(at -1.229614 -5.22097 180)
			(unlocked yes)
			(layer "F.Fab")
			(effects
				(font
					(size 1.905 1.4224)
					(thickness 0.1524)
				)
				(justify left)
			)
		)
		(fp_text user "F3"
			(at -2.8956 11.950446 180)
			(unlocked yes)
			(layer "F.Fab")
			(effects
				(font
					(size 0.7874 0.5842)
					(thickness 0.1524)
				)
			)
		)
		(fp_text user "F2"
			(at -2.8956 9.95045 180)
			(unlocked yes)
			(layer "F.Fab")
			(effects
				(font
					(size 0.7874 0.5842)
					(thickness 0.1524)
				)
			)
		)
		(fp_text user "F1"
			(at -2.8956 7.950454 180)
			(unlocked yes)
			(layer "F.Fab")
			(effects
				(font
					(size 0.7874 0.5842)
					(thickness 0.1524)
				)
			)
		)
		(fp_text user "A3"
			(at -2.8956 3.950462 180)
			(unlocked yes)
			(layer "F.Fab")
			(effects
				(font
					(size 0.7874 0.5842)
					(thickness 0.1524)
				)
			)
		)
		(fp_text user "A2"
			(at -2.8956 1.950466 180)
			(unlocked yes)
			(layer "F.Fab")
			(effects
				(font
					(size 0.7874 0.5842)
					(thickness 0.1524)
				)
			)
		)
		(pad "" np_thru_hole circle
			(at 3.999992 2.800096 180)
			(size 2.159 2.159)
			(drill 2.159)
			(layers "*.Cu" "*.Mask")
			(clearance 0.381)
			(thermal_gap 0.381)
		)
		(pad "" np_thru_hole circle
			(at 9.99998 10.80008 180)
			(size 2.159 2.159)
			(drill 2.159)
			(layers "*.Cu" "*.Mask")
			(clearance 0.381)
			(thermal_gap 0.381)
		)
		(pad "A1" thru_hole rect
			(at 0 0 180)
			(size 1.156208 1.156208)
			(drill 0.749808)
			(layers "*.Cu" "*.Mask")
			(remove_unused_layers no)
			(net "P52V_HS2")
			(clearance 0.0508)
			(thermal_gap 0.0508)
			(padstack
				(mode front_inner_back)
				(layer "Inner"
					(shape circle)
					(size 1.156208 1.156208)
					(clearance 0.0508)
				)
				(layer "B.Cu"
					(shape rect)
					(size 1.156208 1.156208)
					(clearance 0.0508)
				)
			)
		)
		(pad "A2" thru_hole circle
			(at 0 1.999996 180)
			(size 1.156208 1.156208)
			(drill 0.749808)
			(layers "*.Cu" "*.Mask")
			(remove_unused_layers no)
			(net "P52V_HS2")
			(clearance 0.0508)
			(thermal_gap 0.0508)
		)
		(pad "A3" thru_hole circle
			(at 0 3.999992 180)
			(size 1.156208 1.156208)
			(drill 0.749808)
			(layers "*.Cu" "*.Mask")
			(remove_unused_layers no)
			(net "P52V_HS2")
			(clearance 0.0508)
			(thermal_gap 0.0508)
		)
		(pad "A4" thru_hole circle
			(at 1.999996 3.999992 180)
			(size 1.156208 1.156208)
			(drill 0.749808)
			(layers "*.Cu" "*.Mask")
			(remove_unused_layers no)
			(net "P52V_HS2")
			(clearance 0.0508)
			(thermal_gap 0.0508)
		)
		(pad "A5" thru_hole circle
			(at 1.999996 1.999996 180)
			(size 1.156208 1.156208)
			(drill 0.749808)
			(layers "*.Cu" "*.Mask")
			(remove_unused_layers no)
			(net "P52V_HS2")
			(clearance 0.0508)
			(thermal_gap 0.0508)
		)
		(pad "A6" thru_hole circle
			(at 1.999996 0 180)
			(size 1.156208 1.156208)
			(drill 0.749808)
			(layers "*.Cu" "*.Mask")
			(remove_unused_layers no)
			(net "P52V_HS2")
			(clearance 0.0508)
			(thermal_gap 0.0508)
		)
		(pad "B1" thru_hole circle
			(at 5.999988 0 180)
			(size 1.156208 1.156208)
			(drill 0.749808)
			(layers "*.Cu" "*.Mask")
			(remove_unused_layers no)
			(net "P52V_HS2")
			(clearance 0.0508)
			(thermal_gap 0.0508)
		)
		(pad "B2" thru_hole circle
			(at 5.999988 1.999996 180)
			(size 1.156208 1.156208)
			(drill 0.749808)
			(layers "*.Cu" "*.Mask")
			(remove_unused_layers no)
			(net "P52V_HS2")
			(clearance 0.0508)
			(thermal_gap 0.0508)
		)
		(pad "B3" thru_hole circle
			(at 5.999988 3.999992 180)
			(size 1.156208 1.156208)
			(drill 0.749808)
			(layers "*.Cu" "*.Mask")
			(remove_unused_layers no)
			(net "P52V_HS2")
			(clearance 0.0508)
			(thermal_gap 0.0508)
		)
		(pad "B4" thru_hole circle
			(at 7.999984 3.999992 180)
			(size 1.156208 1.156208)
			(drill 0.749808)
			(layers "*.Cu" "*.Mask")
			(remove_unused_layers no)
			(net "P52V_HS2")
			(clearance 0.0508)
			(thermal_gap 0.0508)
		)
		(pad "B5" thru_hole circle
			(at 7.999984 1.999996 180)
			(size 1.156208 1.156208)
			(drill 0.749808)
			(layers "*.Cu" "*.Mask")
			(remove_unused_layers no)
			(net "P52V_HS2")
			(clearance 0.0508)
			(thermal_gap 0.0508)
		)
		(pad "B6" thru_hole circle
			(at 7.999984 0 180)
			(size 1.156208 1.156208)
			(drill 0.749808)
			(layers "*.Cu" "*.Mask")
			(remove_unused_layers no)
			(net "P52V_HS2")
			(clearance 0.0508)
			(thermal_gap 0.0508)
		)
		(pad "C1" thru_hole circle
			(at 11.999976 0 180)
			(size 1.156208 1.156208)
			(drill 0.749808)
			(layers "*.Cu" "*.Mask")
			(remove_unused_layers no)
			(net "P52V_HS2")
			(clearance 0.0508)
			(thermal_gap 0.0508)
		)
		(pad "C2" thru_hole circle
			(at 11.999976 1.999996 180)
			(size 1.156208 1.156208)
			(drill 0.749808)
			(layers "*.Cu" "*.Mask")
			(remove_unused_layers no)
			(net "P52V_HS2")
			(clearance 0.0508)
			(thermal_gap 0.0508)
		)
		(pad "C3" thru_hole circle
			(at 11.999976 3.999992 180)
			(size 1.156208 1.156208)
			(drill 0.749808)
			(layers "*.Cu" "*.Mask")
			(remove_unused_layers no)
			(net "P52V_HS2")
			(clearance 0.0508)
			(thermal_gap 0.0508)
		)
		(pad "C4" thru_hole circle
			(at 13.999972 3.999992 180)
			(size 1.156208 1.156208)
			(drill 0.749808)
			(layers "*.Cu" "*.Mask")
			(remove_unused_layers no)
			(net "P52V_HS2")
			(clearance 0.0508)
			(thermal_gap 0.0508)
		)
		(pad "C5" thru_hole circle
			(at 13.999972 1.999996 180)
			(size 1.156208 1.156208)
			(drill 0.749808)
			(layers "*.Cu" "*.Mask")
			(remove_unused_layers no)
			(net "P52V_HS2")
			(clearance 0.0508)
			(thermal_gap 0.0508)
		)
		(pad "C6" thru_hole circle
			(at 13.999972 0 180)
			(size 1.156208 1.156208)
			(drill 0.749808)
			(layers "*.Cu" "*.Mask")
			(remove_unused_layers no)
			(net "P52V_HS2")
			(clearance 0.0508)
			(thermal_gap 0.0508)
		)
		(pad "D1" thru_hole circle
			(at 11.999976 7.999984 180)
			(size 1.156208 1.156208)
			(drill 0.749808)
			(layers "*.Cu" "*.Mask")
			(remove_unused_layers no)
			(net "GND")
			(clearance 0.0508)
			(thermal_gap 0.0508)
		)
		(pad "D2" thru_hole circle
			(at 11.999976 9.99998 180)
			(size 1.156208 1.156208)
			(drill 0.749808)
			(layers "*.Cu" "*.Mask")
			(remove_unused_layers no)
			(net "GND")
			(clearance 0.0508)
			(thermal_gap 0.0508)
		)
		(pad "D3" thru_hole circle
			(at 11.999976 11.999976 180)
			(size 1.156208 1.156208)
			(drill 0.749808)
			(layers "*.Cu" "*.Mask")
			(remove_unused_layers no)
			(net "GND")
			(clearance 0.0508)
			(thermal_gap 0.0508)
		)
		(pad "D4" thru_hole circle
			(at 13.999972 11.999976 180)
			(size 1.156208 1.156208)
			(drill 0.749808)
			(layers "*.Cu" "*.Mask")
			(remove_unused_layers no)
			(net "GND")
			(clearance 0.0508)
			(thermal_gap 0.0508)
		)
		(pad "D5" thru_hole circle
			(at 13.999972 9.99998 180)
			(size 1.156208 1.156208)
			(drill 0.749808)
			(layers "*.Cu" "*.Mask")
			(remove_unused_layers no)
			(net "GND")
			(clearance 0.0508)
			(thermal_gap 0.0508)
		)
		(pad "D6" thru_hole circle
			(at 13.999972 7.999984 180)
			(size 1.156208 1.156208)
			(drill 0.749808)
			(layers "*.Cu" "*.Mask")
			(remove_unused_layers no)
			(net "GND")
			(clearance 0.0508)
			(thermal_gap 0.0508)
		)
		(pad "E1" thru_hole circle
			(at 5.999988 7.999984 180)
			(size 1.156208 1.156208)
			(drill 0.749808)
			(layers "*.Cu" "*.Mask")
			(remove_unused_layers no)
			(net "GND")
			(clearance 0.0508)
			(thermal_gap 0.0508)
		)
		(pad "E2" thru_hole circle
			(at 5.999988 9.99998 180)
			(size 1.156208 1.156208)
			(drill 0.749808)
			(layers "*.Cu" "*.Mask")
			(remove_unused_layers no)
			(net "GND")
			(clearance 0.0508)
			(thermal_gap 0.0508)
		)
		(pad "E3" thru_hole circle
			(at 5.999988 11.999976 180)
			(size 1.156208 1.156208)
			(drill 0.749808)
			(layers "*.Cu" "*.Mask")
			(remove_unused_layers no)
			(net "GND")
			(clearance 0.0508)
			(thermal_gap 0.0508)
		)
		(pad "E4" thru_hole circle
			(at 7.999984 11.999976 180)
			(size 1.156208 1.156208)
			(drill 0.749808)
			(layers "*.Cu" "*.Mask")
			(remove_unused_layers no)
			(net "GND")
			(clearance 0.0508)
			(thermal_gap 0.0508)
		)
		(pad "E5" thru_hole circle
			(at 7.999984 9.99998 180)
			(size 1.156208 1.156208)
			(drill 0.749808)
			(layers "*.Cu" "*.Mask")
			(remove_unused_layers no)
			(net "GND")
			(clearance 0.0508)
			(thermal_gap 0.0508)
		)
		(pad "E6" thru_hole circle
			(at 7.999984 7.999984 180)
			(size 1.156208 1.156208)
			(drill 0.749808)
			(layers "*.Cu" "*.Mask")
			(remove_unused_layers no)
			(net "GND")
			(clearance 0.0508)
			(thermal_gap 0.0508)
		)
		(pad "F1" thru_hole circle
			(at 0 7.999984 180)
			(size 1.156208 1.156208)
			(drill 0.749808)
			(layers "*.Cu" "*.Mask")
			(remove_unused_layers no)
			(net "GND")
			(clearance 0.0508)
			(thermal_gap 0.0508)
		)
		(pad "F2" thru_hole circle
			(at 0 9.99998 180)
			(size 1.156208 1.156208)
			(drill 0.749808)
			(layers "*.Cu" "*.Mask")
			(remove_unused_layers no)
			(net "GND")
			(clearance 0.0508)
			(thermal_gap 0.0508)
		)
		(pad "F3" thru_hole circle
			(at 0 11.999976 180)
			(size 1.156208 1.156208)
			(drill 0.749808)
			(layers "*.Cu" "*.Mask")
			(remove_unused_layers no)
			(net "GND")
			(clearance 0.0508)
			(thermal_gap 0.0508)
		)
		(pad "F4" thru_hole circle
			(at 1.999996 11.999976 180)
			(size 1.156208 1.156208)
			(drill 0.749808)
			(layers "*.Cu" "*.Mask")
			(remove_unused_layers no)
			(net "GND")
			(clearance 0.0508)
			(thermal_gap 0.0508)
		)
		(pad "F5" thru_hole circle
			(at 1.999996 9.99998 180)
			(size 1.156208 1.156208)
			(drill 0.749808)
			(layers "*.Cu" "*.Mask")
			(remove_unused_layers no)
			(net "GND")
			(clearance 0.0508)
			(thermal_gap 0.0508)
		)
		(pad "F6" thru_hole circle
			(at 1.999996 7.999984 180)
			(size 1.156208 1.156208)
			(drill 0.749808)
			(layers "*.Cu" "*.Mask")
			(remove_unused_layers no)
			(net "GND")
			(clearance 0.0508)
			(thermal_gap 0.0508)
		)
		(zone
			(layers "F.Cu" "B.Cu" "In1.Cu" "In2.Cu" "In3.Cu" "In4.Cu" "In5.Cu" "In6.Cu"
				"In7.Cu" "In8.Cu"
			)
			(hatch none 0.5)
			(connect_pads
				(clearance 0)
			)
			(min_thickness 0.25)
			(keepout
				(tracks not_allowed)
				(vias allowed)
				(pads allowed)
				(copperpour not_allowed)
				(footprints allowed)
			)
			(placement
				(enabled no)
				(sheetname "")
			)
			(fill
				(thermal_gap 0.5)
				(thermal_bridge_width 0.5)
				(island_removal_mode 0)
			)
			(polygon
				(pts
					(arc
						(start 68.48602 -167.630094)
						(mid 65.51422 -167.630094)
						(end 68.48602 -167.630094)
					)
				)
			)
		)
		(zone
			(layers "F.Cu" "B.Cu" "In1.Cu" "In2.Cu" "In3.Cu" "In4.Cu" "In5.Cu" "In6.Cu"
				"In7.Cu" "In8.Cu"
			)
			(hatch none 0.5)
			(connect_pads
				(clearance 0)
			)
			(min_thickness 0.25)
			(keepout
				(tracks not_allowed)
				(vias allowed)
				(pads allowed)
				(copperpour not_allowed)
				(footprints allowed)
			)
			(placement
				(enabled no)
				(sheetname "")
			)
			(fill
				(thermal_gap 0.5)
				(thermal_bridge_width 0.5)
				(island_removal_mode 0)
			)
			(polygon
				(pts
					(arc
						(start 74.486008 -159.63011)
						(mid 71.514208 -159.63011)
						(end 74.486008 -159.63011)
					)
				)
			)
		)
		(zone
			(layer "B.Cu")
			(hatch none 0.5)
			(connect_pads
				(clearance 0)
			)
			(min_thickness 0.25)
			(keepout
				(tracks allowed)
				(vias not_allowed)
				(pads allowed)
				(copperpour not_allowed)
				(footprints allowed)
			)
			(placement
				(enabled no)
				(sheetname "")
			)
			(fill
				(thermal_gap 0.5)
				(thermal_bridge_width 0.5)
				(island_removal_mode 0)
			)
			(polygon
				(pts
					(xy 65.635124 -169.465498) (xy 62.358524 -169.465498) (xy 62.358524 -164.194998) (xy 65.635124 -164.194998)
				)
			)
		)
		(zone
			(layer "B.Cu")
			(hatch none 0.5)
			(connect_pads
				(clearance 0)
			)
			(min_thickness 0.25)
			(keepout
				(tracks allowed)
				(vias not_allowed)
				(pads allowed)
				(copperpour not_allowed)
				(footprints allowed)
			)
			(placement
				(enabled no)
				(sheetname "")
			)
			(fill
				(thermal_gap 0.5)
				(thermal_bridge_width 0.5)
				(island_removal_mode 0)
			)
			(polygon
				(pts
					(xy 65.635124 -161.465514) (xy 62.358524 -161.465514) (xy 62.358524 -156.195014) (xy 65.635124 -156.195014)
				)
			)
		)
		(zone
			(layer "B.Cu")
			(hatch none 0.5)
			(connect_pads
				(clearance 0)
			)
			(min_thickness 0.25)
			(keepout
				(tracks allowed)
				(vias not_allowed)
				(pads allowed)
				(copperpour not_allowed)
				(footprints allowed)
			)
			(placement
				(enabled no)
				(sheetname "")
			)
			(fill
				(thermal_gap 0.5)
				(thermal_bridge_width 0.5)
				(island_removal_mode 0)
			)
			(polygon
				(pts
					(xy 71.635112 -169.465498) (xy 68.358512 -169.465498) (xy 68.358512 -164.194998) (xy 71.635112 -164.194998)
				)
			)
		)
		(zone
			(layer "B.Cu")
			(hatch none 0.5)
			(connect_pads
				(clearance 0)
			)
			(min_thickness 0.25)
			(keepout
				(tracks allowed)
				(vias not_allowed)
				(pads allowed)
				(copperpour not_allowed)
				(footprints allowed)
			)
			(placement
				(enabled no)
				(sheetname "")
			)
			(fill
				(thermal_gap 0.5)
				(thermal_bridge_width 0.5)
				(island_removal_mode 0)
			)
			(polygon
				(pts
					(xy 71.635112 -161.465514) (xy 68.358512 -161.465514) (xy 68.358512 -156.195014) (xy 71.635112 -156.195014)
				)
			)
		)
		(zone
			(layer "B.Cu")
			(hatch none 0.5)
			(connect_pads
				(clearance 0)
			)
			(min_thickness 0.25)
			(keepout
				(tracks allowed)
				(vias not_allowed)
				(pads allowed)
				(copperpour not_allowed)
				(footprints allowed)
			)
			(placement
				(enabled no)
				(sheetname "")
			)
			(fill
				(thermal_gap 0.5)
				(thermal_bridge_width 0.5)
				(island_removal_mode 0)
			)
			(polygon
				(pts
					(xy 77.6351 -169.465498) (xy 74.3585 -169.465498) (xy 74.3585 -164.194998) (xy 77.6351 -164.194998)
				)
			)
		)
		(zone
			(layer "B.Cu")
			(hatch none 0.5)
			(connect_pads
				(clearance 0)
			)
			(min_thickness 0.25)
			(keepout
				(tracks allowed)
				(vias not_allowed)
				(pads allowed)
				(copperpour not_allowed)
				(footprints allowed)
			)
			(placement
				(enabled no)
				(sheetname "")
			)
			(fill
				(thermal_gap 0.5)
				(thermal_bridge_width 0.5)
				(island_removal_mode 0)
			)
			(polygon
				(pts
					(xy 77.6351 -161.465514) (xy 74.3585 -161.465514) (xy 74.3585 -156.195014) (xy 77.6351 -156.195014)
				)
			)
		)
	)
	(footprint ""
		(layer "F.Cu")
		(at 14.99997 -126.500128 180)
		(property "Reference" "H36"
			(at -2.58953 -5.762498 0)
			(unlocked yes)
			(layer "F.SilkS")
			(effects
				(font
					(size 0.7874 0.5842)
					(thickness 0.1524)
				)
				(justify left)
			)
		)
		(property "Value" ""
			(at 0 0 180)
			(layer "F.Fab")
			(effects
				(font
					(size 1.27 1.27)
				)
			)
		)
		(duplicate_pad_numbers_are_jumpers no)
		(pad "1" thru_hole circle
			(at 0 0 180)
			(size 10.16 10.16)
			(drill 6.4008
				(offset 0 0)
			)
			(layers "*.Cu" "*.Mask")
			(remove_unused_layers no)
			(net "GND")
			(clearance -1.6256)
			(padstack
				(mode front_inner_back)
				(layer "Inner"
					(shape circle)
					(size 10.16 10.16)
					(clearance -1.6256)
				)
				(layer "B.Cu"
					(shape oval)
					(size 10.0076 17.018)
					(offset 0 3.499866)
					(clearance -1.5494)
				)
			)
		)
	)
	(footprint ""
		(layer "F.Cu")
		(at 168.529 -80.264 -90)
		(property "Reference" "R5908"
			(at 0 0 270)
			(layer "F.SilkS")
			(hide yes)
			(effects
				(font
					(size 1.27 1.27)
				)
			)
		)
		(property "Value" ""
			(at 0 0 270)
			(layer "F.Fab")
			(effects
				(font
					(size 1.27 1.27)
				)
			)
		)
		(duplicate_pad_numbers_are_jumpers no)
		(fp_line
			(start -0.7874 0.4064)
			(end -0.7874 -0.4064)
			(stroke
				(width 0.1524)
				(type default)
			)
			(layer "F.SilkS")
		)
		(fp_line
			(start 0.7874 0.4064)
			(end -0.7874 0.4064)
			(stroke
				(width 0.1524)
				(type default)
			)
			(layer "F.SilkS")
		)
		(fp_line
			(start -0.7874 -0.4064)
			(end 0.7874 -0.4064)
			(stroke
				(width 0.1524)
				(type default)
			)
			(layer "F.SilkS")
		)
		(fp_line
			(start 0.7874 -0.4064)
			(end 0.7874 0.4064)
			(stroke
				(width 0.1524)
				(type default)
			)
			(layer "F.SilkS")
		)
		(fp_line
			(start -0.67945 0.3048)
			(end -0.67945 -0.305054)
			(stroke
				(width 0.1)
				(type default)
			)
			(layer "F.Fab")
		)
		(fp_line
			(start -0.12065 0.3048)
			(end -0.67945 0.3048)
			(stroke
				(width 0.1)
				(type default)
			)
			(layer "F.Fab")
		)
		(fp_line
			(start 0.120396 0.3048)
			(end 0.120396 0.2794)
			(stroke
				(width 0.1)
				(type default)
			)
			(layer "F.Fab")
		)
		(fp_line
			(start 0.67945 0.3048)
			(end 0.120396 0.3048)
			(stroke
				(width 0.1)
				(type default)
			)
			(layer "F.Fab")
		)
		(fp_line
			(start -0.12065 0.2794)
			(end -0.12065 0.3048)
			(stroke
				(width 0.1)
				(type default)
			)
			(layer "F.Fab")
		)
		(fp_line
			(start 0.120396 0.2794)
			(end -0.12065 0.2794)
			(stroke
				(width 0.1)
				(type default)
			)
			(layer "F.Fab")
		)
		(fp_line
			(start -0.12065 -0.2794)
			(end 0.12065 -0.2794)
			(stroke
				(width 0.1)
				(type default)
			)
			(layer "F.Fab")
		)
		(fp_line
			(start 0.12065 -0.2794)
			(end 0.12065 -0.3048)
			(stroke
				(width 0.1)
				(type default)
			)
			(layer "F.Fab")
		)
		(fp_line
			(start 0.12065 -0.3048)
			(end 0.67945 -0.3048)
			(stroke
				(width 0.1)
				(type default)
			)
			(layer "F.Fab")
		)
		(fp_line
			(start 0.67945 -0.3048)
			(end 0.67945 0.3048)
			(stroke
				(width 0.1)
				(type default)
			)
			(layer "F.Fab")
		)
		(fp_line
			(start -0.67945 -0.305054)
			(end -0.12065 -0.305054)
			(stroke
				(width 0.1)
				(type default)
			)
			(layer "F.Fab")
		)
		(fp_line
			(start -0.12065 -0.305054)
			(end -0.12065 -0.2794)
			(stroke
				(width 0.1)
				(type default)
			)
			(layer "F.Fab")
		)
		(pad "1" smd circle
			(at -0.40005 0 270)
			(size 0 0)
			(layers "F.Cu" "F.Mask" "F.Paste")
			(net "FM_HS2_EN_BUSBAR")
		)
		(pad "2" smd circle
			(at 0.40005 0 270)
			(size 0 0)
			(layers "F.Cu" "F.Mask" "F.Paste")
			(net "GND")
		)
	)
	(footprint ""
		(layer "F.Cu")
		(at 81.661 -17.907 -90)
		(property "Reference" "R77"
			(at 0 0 270)
			(layer "F.SilkS")
			(hide yes)
			(effects
				(font
					(size 1.27 1.27)
				)
			)
		)
		(property "Value" ""
			(at 0 0 270)
			(layer "F.Fab")
			(effects
				(font
					(size 1.27 1.27)
				)
			)
		)
		(duplicate_pad_numbers_are_jumpers no)
		(fp_line
			(start -0.7874 0.4064)
			(end -0.7874 -0.4064)
			(stroke
				(width 0.1524)
				(type default)
			)
			(layer "F.SilkS")
		)
		(fp_line
			(start 0.7874 0.4064)
			(end -0.7874 0.4064)
			(stroke
				(width 0.1524)
				(type default)
			)
			(layer "F.SilkS")
		)
		(fp_line
			(start -0.7874 -0.4064)
			(end 0.7874 -0.4064)
			(stroke
				(width 0.1524)
				(type default)
			)
			(layer "F.SilkS")
		)
		(fp_line
			(start 0.7874 -0.4064)
			(end 0.7874 0.4064)
			(stroke
				(width 0.1524)
				(type default)
			)
			(layer "F.SilkS")
		)
		(fp_line
			(start -0.67945 0.3048)
			(end -0.67945 -0.305054)
			(stroke
				(width 0.1)
				(type default)
			)
			(layer "F.Fab")
		)
		(fp_line
			(start -0.12065 0.3048)
			(end -0.67945 0.3048)
			(stroke
				(width 0.1)
				(type default)
			)
			(layer "F.Fab")
		)
		(fp_line
			(start 0.120396 0.3048)
			(end 0.120396 0.2794)
			(stroke
				(width 0.1)
				(type default)
			)
			(layer "F.Fab")
		)
		(fp_line
			(start 0.67945 0.3048)
			(end 0.120396 0.3048)
			(stroke
				(width 0.1)
				(type default)
			)
			(layer "F.Fab")
		)
		(fp_line
			(start -0.12065 0.2794)
			(end -0.12065 0.3048)
			(stroke
				(width 0.1)
				(type default)
			)
			(layer "F.Fab")
		)
		(fp_line
			(start 0.120396 0.2794)
			(end -0.12065 0.2794)
			(stroke
				(width 0.1)
				(type default)
			)
			(layer "F.Fab")
		)
		(fp_line
			(start -0.12065 -0.2794)
			(end 0.12065 -0.2794)
			(stroke
				(width 0.1)
				(type default)
			)
			(layer "F.Fab")
		)
		(fp_line
			(start 0.12065 -0.2794)
			(end 0.12065 -0.3048)
			(stroke
				(width 0.1)
				(type default)
			)
			(layer "F.Fab")
		)
		(fp_line
			(start 0.12065 -0.3048)
			(end 0.67945 -0.3048)
			(stroke
				(width 0.1)
				(type default)
			)
			(layer "F.Fab")
		)
		(fp_line
			(start 0.67945 -0.3048)
			(end 0.67945 0.3048)
			(stroke
				(width 0.1)
				(type default)
			)
			(layer "F.Fab")
		)
		(fp_line
			(start -0.67945 -0.305054)
			(end -0.12065 -0.305054)
			(stroke
				(width 0.1)
				(type default)
			)
			(layer "F.Fab")
		)
		(fp_line
			(start -0.12065 -0.305054)
			(end -0.12065 -0.2794)
			(stroke
				(width 0.1)
				(type default)
			)
			(layer "F.Fab")
		)
		(pad "1" smd circle
			(at -0.40005 0 270)
			(size 0 0)
			(layers "F.Cu" "F.Mask" "F.Paste")
			(net "SMB_PDB_FAN_1_SDA")
		)
		(pad "2" smd circle
			(at 0.40005 0 270)
			(size 0 0)
			(layers "F.Cu" "F.Mask" "F.Paste")
			(net "SMB_PDB_FAN_1_R_SDA")
		)
	)
	(footprint ""
		(layer "F.Cu")
		(at 238.810038 -22.474936)
		(property "Reference" "H35"
			(at -1.9812 -4.079748 0)
			(unlocked yes)
			(layer "B.SilkS")
			(effects
				(font
					(size 0.7874 0.5842)
					(thickness 0.1524)
				)
				(justify left mirror)
			)
		)
		(property "Value" ""
			(at 0 0 0)
			(layer "F.Fab")
			(effects
				(font
					(size 1.27 1.27)
				)
			)
		)
		(duplicate_pad_numbers_are_jumpers no)
		(pad "1" thru_hole circle
			(at 0 0)
			(size 8.001 8.001)
			(drill 4.2418)
			(layers "*.Cu" "*.Mask")
			(remove_unused_layers no)
			(net "TP_H35")
			(clearance -1.6256)
			(padstack
				(mode front_inner_back)
				(layer "Inner"
					(shape circle)
					(size 6.0198 6.0198)
					(clearance -0.635)
				)
				(layer "B.Cu"
					(shape circle)
					(size 8.001 8.001)
					(clearance -1.6256)
				)
			)
		)
		(zone
			(layers "F.Cu" "B.Cu" "In1.Cu" "In2.Cu" "In3.Cu" "In4.Cu" "In5.Cu" "In6.Cu"
				"In7.Cu" "In8.Cu"
			)
			(hatch none 0.5)
			(connect_pads
				(clearance 0)
			)
			(min_thickness 0.25)
			(keepout
				(tracks not_allowed)
				(vias allowed)
				(pads allowed)
				(copperpour not_allowed)
				(footprints allowed)
			)
			(placement
				(enabled no)
				(sheetname "")
			)
			(fill
				(thermal_gap 0.5)
				(thermal_bridge_width 0.5)
				(island_removal_mode 0)
			)
			(polygon
				(pts
					(arc
						(start 242.320064 -22.474936)
						(mid 235.300012 -22.474936)
						(end 242.320064 -22.474936)
					)
				)
			)
		)
	)
	(footprint ""
		(layer "F.Cu")
		(at 222.6564 -97.028 180)
		(property "Reference" "PR97"
			(at 0 0 180)
			(layer "F.SilkS")
			(hide yes)
			(effects
				(font
					(size 1.27 1.27)
				)
			)
		)
		(property "Value" ""
			(at 0 0 180)
			(layer "F.Fab")
			(effects
				(font
					(size 1.27 1.27)
				)
			)
		)
		(duplicate_pad_numbers_are_jumpers no)
		(fp_line
			(start 0.7874 0.4064)
			(end -0.7874 0.4064)
			(stroke
				(width 0.1524)
				(type default)
			)
			(layer "F.SilkS")
		)
		(fp_line
			(start 0.7874 -0.4064)
			(end 0.7874 0.4064)
			(stroke
				(width 0.1524)
				(type default)
			)
			(layer "F.SilkS")
		)
		(fp_line
			(start -0.7874 0.4064)
			(end -0.7874 -0.4064)
			(stroke
				(width 0.1524)
				(type default)
			)
			(layer "F.SilkS")
		)
		(fp_line
			(start -0.7874 -0.4064)
			(end 0.7874 -0.4064)
			(stroke
				(width 0.1524)
				(type default)
			)
			(layer "F.SilkS")
		)
		(fp_line
			(start 0.67945 0.3048)
			(end 0.120396 0.3048)
			(stroke
				(width 0.1)
				(type default)
			)
			(layer "F.Fab")
		)
		(fp_line
			(start 0.67945 -0.3048)
			(end 0.67945 0.3048)
			(stroke
				(width 0.1)
				(type default)
			)
			(layer "F.Fab")
		)
		(fp_line
			(start 0.12065 -0.2794)
			(end 0.12065 -0.3048)
			(stroke
				(width 0.1)
				(type default)
			)
			(layer "F.Fab")
		)
		(fp_line
			(start 0.12065 -0.3048)
			(end 0.67945 -0.3048)
			(stroke
				(width 0.1)
				(type default)
			)
			(layer "F.Fab")
		)
		(fp_line
			(start 0.120396 0.3048)
			(end 0.120396 0.2794)
			(stroke
				(width 0.1)
				(type default)
			)
			(layer "F.Fab")
		)
		(fp_line
			(start 0.120396 0.2794)
			(end -0.12065 0.2794)
			(stroke
				(width 0.1)
				(type default)
			)
			(layer "F.Fab")
		)
		(fp_line
			(start -0.12065 0.3048)
			(end -0.67945 0.3048)
			(stroke
				(width 0.1)
				(type default)
			)
			(layer "F.Fab")
		)
		(fp_line
			(start -0.12065 0.2794)
			(end -0.12065 0.3048)
			(stroke
				(width 0.1)
				(type default)
			)
			(layer "F.Fab")
		)
		(fp_line
			(start -0.12065 -0.2794)
			(end 0.12065 -0.2794)
			(stroke
				(width 0.1)
				(type default)
			)
			(layer "F.Fab")
		)
		(fp_line
			(start -0.12065 -0.305054)
			(end -0.12065 -0.2794)
			(stroke
				(width 0.1)
				(type default)
			)
			(layer "F.Fab")
		)
		(fp_line
			(start -0.67945 0.3048)
			(end -0.67945 -0.305054)
			(stroke
				(width 0.1)
				(type default)
			)
			(layer "F.Fab")
		)
		(fp_line
			(start -0.67945 -0.305054)
			(end -0.12065 -0.305054)
			(stroke
				(width 0.1)
				(type default)
			)
			(layer "F.Fab")
		)
		(pad "1" smd circle
			(at -0.40005 0 180)
			(size 0 0)
			(layers "F.Cu" "F.Mask" "F.Paste")
			(net "SMB_P52V_PDB_SDA")
		)
		(pad "2" smd circle
			(at 0.40005 0 180)
			(size 0 0)
			(layers "F.Cu" "F.Mask" "F.Paste")
			(net "SMB_P52V_PDB_DEBUG_SDA")
		)
	)
	(footprint ""
		(layer "F.Cu")
		(at 442.595 -30.353)
		(property "Reference" "U18"
			(at -5.6515 -4.78663 0)
			(unlocked yes)
			(layer "F.SilkS")
			(effects
				(font
					(size 0.7874 0.5842)
					(thickness 0.1524)
				)
				(justify left)
			)
		)
		(property "Value" ""
			(at 0 0 0)
			(layer "F.Fab")
			(effects
				(font
					(size 1.27 1.27)
				)
			)
		)
		(duplicate_pad_numbers_are_jumpers no)
		(fp_line
			(start -1.4224 -4.3688)
			(end -0.4572 -4.3688)
			(stroke
				(width 0.1524)
				(type default)
			)
			(layer "F.SilkS")
		)
		(fp_line
			(start -1.4224 4.3688)
			(end -1.4224 -4.3688)
			(stroke
				(width 0.1524)
				(type default)
			)
			(layer "F.SilkS")
		)
		(fp_line
			(start -0.4572 -4.3688)
			(end 0 -3.9116)
			(stroke
				(width 0.1524)
				(type default)
			)
			(layer "F.SilkS")
		)
		(fp_line
			(start 0 -3.9116)
			(end 0.4572 -4.3688)
			(stroke
				(width 0.1524)
				(type default)
			)
			(layer "F.SilkS")
		)
		(fp_line
			(start 0.4572 -4.3688)
			(end 1.4224 -4.3688)
			(stroke
				(width 0.1524)
				(type default)
			)
			(layer "F.SilkS")
		)
		(fp_line
			(start 1.4224 -4.3688)
			(end 1.4224 4.3688)
			(stroke
				(width 0.1524)
				(type default)
			)
			(layer "F.SilkS")
		)
		(fp_line
			(start 1.4224 4.3688)
			(end -1.4224 4.3688)
			(stroke
				(width 0.1524)
				(type default)
			)
			(layer "F.SilkS")
		)
		(fp_poly
			(pts
				(xy -2.728214 -4.318) (xy -3.109214 -5.08) (xy -2.347214 -5.08)
			)
			(stroke
				(width 0)
				(type default)
			)
			(fill yes)
			(layer "F.SilkS")
		)
		(fp_line
			(start -2.6416 -4.141216)
			(end -2.0066 -4.141216)
			(stroke
				(width 0.1)
				(type default)
			)
			(layer "F.Fab")
		)
		(fp_line
			(start -2.6416 4.140708)
			(end -2.6416 -4.141216)
			(stroke
				(width 0.1)
				(type default)
			)
			(layer "F.Fab")
		)
		(fp_line
			(start -2.0066 -4.3688)
			(end 2.0066 -4.3688)
			(stroke
				(width 0.1)
				(type default)
			)
			(layer "F.Fab")
		)
		(fp_line
			(start -2.0066 -4.141216)
			(end -2.0066 -4.3688)
			(stroke
				(width 0.1)
				(type default)
			)
			(layer "F.Fab")
		)
		(fp_line
			(start -2.0066 4.140708)
			(end -2.6416 4.140708)
			(stroke
				(width 0.1)
				(type default)
			)
			(layer "F.Fab")
		)
		(fp_line
			(start -2.0066 4.3688)
			(end -2.0066 4.140708)
			(stroke
				(width 0.1)
				(type default)
			)
			(layer "F.Fab")
		)
		(fp_line
			(start 2.0066 -4.3688)
			(end 2.0066 -4.143756)
			(stroke
				(width 0.1)
				(type default)
			)
			(layer "F.Fab")
		)
		(fp_line
			(start 2.0066 -4.143756)
			(end 2.6416 -4.143756)
			(stroke
				(width 0.1)
				(type default)
			)
			(layer "F.Fab")
		)
		(fp_line
			(start 2.0066 4.139438)
			(end 2.0066 4.3688)
			(stroke
				(width 0.1)
				(type default)
			)
			(layer "F.Fab")
		)
		(fp_line
			(start 2.0066 4.3688)
			(end -2.0066 4.3688)
			(stroke
				(width 0.1)
				(type default)
			)
			(layer "F.Fab")
		)
		(fp_line
			(start 2.6416 -4.143756)
			(end 2.6416 4.139438)
			(stroke
				(width 0.1)
				(type default)
			)
			(layer "F.Fab")
		)
		(fp_line
			(start 2.6416 4.139438)
			(end 2.0066 4.139438)
			(stroke
				(width 0.1)
				(type default)
			)
			(layer "F.Fab")
		)
		(fp_poly
			(pts
				(xy -3.6576 -3.850386) (xy -4.4196 -3.469386) (xy -4.4196 -4.231386)
			)
			(stroke
				(width 0)
				(type default)
			)
			(fill yes)
			(layer "F.Fab")
		)
		(pad "1" smd rect
			(at -2.6416 -3.81 270)
			(size 0.5588 1.7272)
			(layers "F.Cu" "F.Mask" "F.Paste")
			(net "PD_9543_FAN_A0")
		)
		(pad "2" smd rect
			(at -2.6416 -2.54 270)
			(size 0.5588 1.7272)
			(layers "F.Cu" "F.Mask" "F.Paste")
			(net "PD_9543_FAN_A1")
		)
		(pad "3" smd rect
			(at -2.6416 -1.27 270)
			(size 0.5588 1.7272)
			(layers "F.Cu" "F.Mask" "F.Paste")
			(net "RST_SMB_PDB_BUF_N")
		)
		(pad "4" smd rect
			(at -2.6416 0 270)
			(size 0.5588 1.7272)
			(layers "F.Cu" "F.Mask" "F.Paste")
			(net "PU_9543_0_FAN")
		)
		(pad "5" smd rect
			(at -2.6416 1.27 270)
			(size 0.5588 1.7272)
			(layers "F.Cu" "F.Mask" "F.Paste")
			(net "SMB_PDB_FAN_0_SDA")
		)
		(pad "6" smd rect
			(at -2.6416 2.54 270)
			(size 0.5588 1.7272)
			(layers "F.Cu" "F.Mask" "F.Paste")
			(net "SMB_PDB_FAN_0_SCL")
		)
		(pad "7" smd rect
			(at -2.6416 3.81 270)
			(size 0.5588 1.7272)
			(layers "F.Cu" "F.Mask" "F.Paste")
			(net "GND")
		)
		(pad "8" smd rect
			(at 2.6416 3.81 270)
			(size 0.5588 1.7272)
			(layers "F.Cu" "F.Mask" "F.Paste")
			(net "PU_9543_1_FAN")
		)
		(pad "9" smd rect
			(at 2.6416 2.54 270)
			(size 0.5588 1.7272)
			(layers "F.Cu" "F.Mask" "F.Paste")
			(net "SMB_PDB_FAN_1_SDA")
		)
		(pad "10" smd rect
			(at 2.6416 1.27 270)
			(size 0.5588 1.7272)
			(layers "F.Cu" "F.Mask" "F.Paste")
			(net "SMB_PDB_FAN_1_SCL")
		)
		(pad "11" smd rect
			(at 2.6416 0 270)
			(size 0.5588 1.7272)
			(layers "F.Cu" "F.Mask" "F.Paste")
			(net "TP_9543_FAN_INT_N")
		)
		(pad "12" smd rect
			(at 2.6416 -1.27 270)
			(size 0.5588 1.7272)
			(layers "F.Cu" "F.Mask" "F.Paste")
			(net "SMB_FAN_MUX_SCL")
		)
		(pad "13" smd rect
			(at 2.6416 -2.54 270)
			(size 0.5588 1.7272)
			(layers "F.Cu" "F.Mask" "F.Paste")
			(net "SMB_FAN_MUX_SDA")
		)
		(pad "14" smd rect
			(at 2.6416 -3.81 270)
			(size 0.5588 1.7272)
			(layers "F.Cu" "F.Mask" "F.Paste")
			(net "P3V3_AUX")
		)
	)
	(footprint ""
		(layer "F.Cu")
		(at 453.7964 -62.23 -90)
		(property "Reference" "PC51"
			(at 0 0 270)
			(layer "F.SilkS")
			(hide yes)
			(effects
				(font
					(size 1.27 1.27)
				)
			)
		)
		(property "Value" ""
			(at 0 0 270)
			(layer "F.Fab")
			(effects
				(font
					(size 1.27 1.27)
				)
			)
		)
		(duplicate_pad_numbers_are_jumpers no)
		(fp_line
			(start -0.7874 0.4064)
			(end -0.7874 -0.4064)
			(stroke
				(width 0.1524)
				(type default)
			)
			(layer "F.SilkS")
		)
		(fp_line
			(start 0.7874 0.4064)
			(end -0.7874 0.4064)
			(stroke
				(width 0.1524)
				(type default)
			)
			(layer "F.SilkS")
		)
		(fp_line
			(start -0.7874 -0.4064)
			(end 0.7874 -0.4064)
			(stroke
				(width 0.1524)
				(type default)
			)
			(layer "F.SilkS")
		)
		(fp_line
			(start 0.7874 -0.4064)
			(end 0.7874 0.4064)
			(stroke
				(width 0.1524)
				(type default)
			)
			(layer "F.SilkS")
		)
		(fp_line
			(start -0.67945 0.3048)
			(end -0.67945 -0.305054)
			(stroke
				(width 0.1)
				(type default)
			)
			(layer "F.Fab")
		)
		(fp_line
			(start -0.12065 0.3048)
			(end -0.67945 0.3048)
			(stroke
				(width 0.1)
				(type default)
			)
			(layer "F.Fab")
		)
		(fp_line
			(start 0.120396 0.3048)
			(end 0.120396 0.2794)
			(stroke
				(width 0.1)
				(type default)
			)
			(layer "F.Fab")
		)
		(fp_line
			(start 0.67945 0.3048)
			(end 0.120396 0.3048)
			(stroke
				(width 0.1)
				(type default)
			)
			(layer "F.Fab")
		)
		(fp_line
			(start -0.12065 0.2794)
			(end -0.12065 0.3048)
			(stroke
				(width 0.1)
				(type default)
			)
			(layer "F.Fab")
		)
		(fp_line
			(start 0.120396 0.2794)
			(end -0.12065 0.2794)
			(stroke
				(width 0.1)
				(type default)
			)
			(layer "F.Fab")
		)
		(fp_line
			(start -0.12065 -0.2794)
			(end 0.12065 -0.2794)
			(stroke
				(width 0.1)
				(type default)
			)
			(layer "F.Fab")
		)
		(fp_line
			(start 0.12065 -0.2794)
			(end 0.12065 -0.3048)
			(stroke
				(width 0.1)
				(type default)
			)
			(layer "F.Fab")
		)
		(fp_line
			(start 0.12065 -0.3048)
			(end 0.67945 -0.3048)
			(stroke
				(width 0.1)
				(type default)
			)
			(layer "F.Fab")
		)
		(fp_line
			(start 0.67945 -0.3048)
			(end 0.67945 0.3048)
			(stroke
				(width 0.1)
				(type default)
			)
			(layer "F.Fab")
		)
		(fp_line
			(start -0.67945 -0.305054)
			(end -0.12065 -0.305054)
			(stroke
				(width 0.1)
				(type default)
			)
			(layer "F.Fab")
		)
		(fp_line
			(start -0.12065 -0.305054)
			(end -0.12065 -0.2794)
			(stroke
				(width 0.1)
				(type default)
			)
			(layer "F.Fab")
		)
		(pad "1" smd circle
			(at -0.40005 0 270)
			(size 0 0)
			(layers "F.Cu" "F.Mask" "F.Paste")
			(net "P3V3_AUX")
		)
		(pad "2" smd circle
			(at 0.40005 0 270)
			(size 0 0)
			(layers "F.Cu" "F.Mask" "F.Paste")
			(net "GND")
		)
	)
	(footprint ""
		(layer "F.Cu")
		(at 427.228 -47.371 180)
		(property "Reference" "R49"
			(at 0 0 180)
			(layer "F.SilkS")
			(hide yes)
			(effects
				(font
					(size 1.27 1.27)
				)
			)
		)
		(property "Value" ""
			(at 0 0 180)
			(layer "F.Fab")
			(effects
				(font
					(size 1.27 1.27)
				)
			)
		)
		(duplicate_pad_numbers_are_jumpers no)
		(fp_line
			(start 0.7874 0.4064)
			(end -0.7874 0.4064)
			(stroke
				(width 0.1524)
				(type default)
			)
			(layer "F.SilkS")
		)
		(fp_line
			(start 0.7874 -0.4064)
			(end 0.7874 0.4064)
			(stroke
				(width 0.1524)
				(type default)
			)
			(layer "F.SilkS")
		)
		(fp_line
			(start -0.7874 0.4064)
			(end -0.7874 -0.4064)
			(stroke
				(width 0.1524)
				(type default)
			)
			(layer "F.SilkS")
		)
		(fp_line
			(start -0.7874 -0.4064)
			(end 0.7874 -0.4064)
			(stroke
				(width 0.1524)
				(type default)
			)
			(layer "F.SilkS")
		)
		(fp_line
			(start 0.67945 0.3048)
			(end 0.120396 0.3048)
			(stroke
				(width 0.1)
				(type default)
			)
			(layer "F.Fab")
		)
		(fp_line
			(start 0.67945 -0.3048)
			(end 0.67945 0.3048)
			(stroke
				(width 0.1)
				(type default)
			)
			(layer "F.Fab")
		)
		(fp_line
			(start 0.12065 -0.2794)
			(end 0.12065 -0.3048)
			(stroke
				(width 0.1)
				(type default)
			)
			(layer "F.Fab")
		)
		(fp_line
			(start 0.12065 -0.3048)
			(end 0.67945 -0.3048)
			(stroke
				(width 0.1)
				(type default)
			)
			(layer "F.Fab")
		)
		(fp_line
			(start 0.120396 0.3048)
			(end 0.120396 0.2794)
			(stroke
				(width 0.1)
				(type default)
			)
			(layer "F.Fab")
		)
		(fp_line
			(start 0.120396 0.2794)
			(end -0.12065 0.2794)
			(stroke
				(width 0.1)
				(type default)
			)
			(layer "F.Fab")
		)
		(fp_line
			(start -0.12065 0.3048)
			(end -0.67945 0.3048)
			(stroke
				(width 0.1)
				(type default)
			)
			(layer "F.Fab")
		)
		(fp_line
			(start -0.12065 0.2794)
			(end -0.12065 0.3048)
			(stroke
				(width 0.1)
				(type default)
			)
			(layer "F.Fab")
		)
		(fp_line
			(start -0.12065 -0.2794)
			(end 0.12065 -0.2794)
			(stroke
				(width 0.1)
				(type default)
			)
			(layer "F.Fab")
		)
		(fp_line
			(start -0.12065 -0.305054)
			(end -0.12065 -0.2794)
			(stroke
				(width 0.1)
				(type default)
			)
			(layer "F.Fab")
		)
		(fp_line
			(start -0.67945 0.3048)
			(end -0.67945 -0.305054)
			(stroke
				(width 0.1)
				(type default)
			)
			(layer "F.Fab")
		)
		(fp_line
			(start -0.67945 -0.305054)
			(end -0.12065 -0.305054)
			(stroke
				(width 0.1)
				(type default)
			)
			(layer "F.Fab")
		)
		(pad "1" smd circle
			(at -0.40005 0 180)
			(size 0 0)
			(layers "F.Cu" "F.Mask" "F.Paste")
			(net "SMB_PDB_MISC_SDA")
		)
		(pad "2" smd circle
			(at 0.40005 0 180)
			(size 0 0)
			(layers "F.Cu" "F.Mask" "F.Paste")
			(net "SMB_IOEXP_SDA")
		)
	)
	(footprint ""
		(layer "F.Cu")
		(at 168.956736 -65.024 180)
		(property "Reference" "PR7032"
			(at 0 0 180)
			(layer "F.SilkS")
			(hide yes)
			(effects
				(font
					(size 1.27 1.27)
				)
			)
		)
		(property "Value" ""
			(at 0 0 180)
			(layer "F.Fab")
			(effects
				(font
					(size 1.27 1.27)
				)
			)
		)
		(duplicate_pad_numbers_are_jumpers no)
		(fp_line
			(start 0.7874 0.4064)
			(end -0.7874 0.4064)
			(stroke
				(width 0.1524)
				(type default)
			)
			(layer "F.SilkS")
		)
		(fp_line
			(start 0.7874 -0.4064)
			(end 0.7874 0.4064)
			(stroke
				(width 0.1524)
				(type default)
			)
			(layer "F.SilkS")
		)
		(fp_line
			(start -0.7874 0.4064)
			(end -0.7874 -0.4064)
			(stroke
				(width 0.1524)
				(type default)
			)
			(layer "F.SilkS")
		)
		(fp_line
			(start -0.7874 -0.4064)
			(end 0.7874 -0.4064)
			(stroke
				(width 0.1524)
				(type default)
			)
			(layer "F.SilkS")
		)
		(fp_line
			(start 0.67945 0.3048)
			(end 0.120396 0.3048)
			(stroke
				(width 0.1)
				(type default)
			)
			(layer "F.Fab")
		)
		(fp_line
			(start 0.67945 -0.3048)
			(end 0.67945 0.3048)
			(stroke
				(width 0.1)
				(type default)
			)
			(layer "F.Fab")
		)
		(fp_line
			(start 0.12065 -0.2794)
			(end 0.12065 -0.3048)
			(stroke
				(width 0.1)
				(type default)
			)
			(layer "F.Fab")
		)
		(fp_line
			(start 0.12065 -0.3048)
			(end 0.67945 -0.3048)
			(stroke
				(width 0.1)
				(type default)
			)
			(layer "F.Fab")
		)
		(fp_line
			(start 0.120396 0.3048)
			(end 0.120396 0.2794)
			(stroke
				(width 0.1)
				(type default)
			)
			(layer "F.Fab")
		)
		(fp_line
			(start 0.120396 0.2794)
			(end -0.12065 0.2794)
			(stroke
				(width 0.1)
				(type default)
			)
			(layer "F.Fab")
		)
		(fp_line
			(start -0.12065 0.3048)
			(end -0.67945 0.3048)
			(stroke
				(width 0.1)
				(type default)
			)
			(layer "F.Fab")
		)
		(fp_line
			(start -0.12065 0.2794)
			(end -0.12065 0.3048)
			(stroke
				(width 0.1)
				(type default)
			)
			(layer "F.Fab")
		)
		(fp_line
			(start -0.12065 -0.2794)
			(end 0.12065 -0.2794)
			(stroke
				(width 0.1)
				(type default)
			)
			(layer "F.Fab")
		)
		(fp_line
			(start -0.12065 -0.305054)
			(end -0.12065 -0.2794)
			(stroke
				(width 0.1)
				(type default)
			)
			(layer "F.Fab")
		)
		(fp_line
			(start -0.67945 0.3048)
			(end -0.67945 -0.305054)
			(stroke
				(width 0.1)
				(type default)
			)
			(layer "F.Fab")
		)
		(fp_line
			(start -0.67945 -0.305054)
			(end -0.12065 -0.305054)
			(stroke
				(width 0.1)
				(type default)
			)
			(layer "F.Fab")
		)
		(pad "1" smd circle
			(at -0.40005 0 180)
			(size 0 0)
			(layers "F.Cu" "F.Mask" "F.Paste")
			(net "P52V_HS2_EFAULT_R")
		)
		(pad "2" smd circle
			(at 0.40005 0 180)
			(size 0 0)
			(layers "F.Cu" "F.Mask" "F.Paste")
			(net "P52V_HS2_EFAULT")
		)
	)
	(footprint ""
		(layer "F.Cu")
		(at 208.810098 -51.049936 180)
		(property "Reference" "J7"
			(at 9.775698 -41.778936 0)
			(unlocked yes)
			(layer "F.SilkS")
			(effects
				(font
					(size 10.16 7.62)
					(thickness 1.778)
				)
			)
		)
		(property "Value" ""
			(at 0 0 180)
			(layer "F.Fab")
			(effects
				(font
					(size 1.27 1.27)
				)
			)
		)
		(duplicate_pad_numbers_are_jumpers no)
		(fp_line
			(start 14.109954 34.36493)
			(end -6.469888 34.36493)
			(stroke
				(width 0.1524)
				(type default)
			)
			(layer "F.SilkS")
		)
		(fp_line
			(start 14.109954 -34.36493)
			(end 14.109954 34.36493)
			(stroke
				(width 0.1524)
				(type default)
			)
			(layer "F.SilkS")
		)
		(fp_line
			(start 11.10996 31.364936)
			(end 4.213098 31.364936)
			(stroke
				(width 0.1524)
				(type default)
			)
			(layer "F.SilkS")
		)
		(fp_line
			(start 11.10996 -31.364936)
			(end 11.10996 31.364936)
			(stroke
				(width 0.1524)
				(type default)
			)
			(layer "F.SilkS")
		)
		(fp_line
			(start 4.263898 -31.364936)
			(end 11.10996 -31.364936)
			(stroke
				(width 0.1524)
				(type default)
			)
			(layer "F.SilkS")
		)
		(fp_line
			(start -3.469894 26.115264)
			(end -3.469894 -26.005536)
			(stroke
				(width 0.1524)
				(type default)
			)
			(layer "F.SilkS")
		)
		(fp_line
			(start -6.469888 34.36493)
			(end -6.469888 -34.36493)
			(stroke
				(width 0.1524)
				(type default)
			)
			(layer "F.SilkS")
		)
		(fp_line
			(start -6.469888 -34.36493)
			(end 14.109954 -34.36493)
			(stroke
				(width 0.1524)
				(type default)
			)
			(layer "F.SilkS")
		)
		(fp_poly
			(pts
				(xy -5.0038 -0.508) (xy -5.0038 0.508) (xy -3.9878 0)
			)
			(stroke
				(width 0)
				(type default)
			)
			(fill yes)
			(layer "F.SilkS")
		)
		(fp_line
			(start 14.109954 34.36493)
			(end -6.469888 34.36493)
			(stroke
				(width 0.1524)
				(type default)
			)
			(layer "B.SilkS")
		)
		(fp_line
			(start 14.109954 -34.36493)
			(end 14.109954 34.36493)
			(stroke
				(width 0.1524)
				(type default)
			)
			(layer "B.SilkS")
		)
		(fp_line
			(start -6.469888 34.36493)
			(end -6.469888 -34.36493)
			(stroke
				(width 0.1524)
				(type default)
			)
			(layer "B.SilkS")
		)
		(fp_line
			(start -6.469888 -34.36493)
			(end 14.109954 -34.36493)
			(stroke
				(width 0.1524)
				(type default)
			)
			(layer "B.SilkS")
		)
		(fp_line
			(start 14.109954 34.36493)
			(end -6.469888 34.36493)
			(stroke
				(width 0.1)
				(type default)
			)
			(layer "B.Fab")
		)
		(fp_line
			(start 14.109954 -34.36493)
			(end 14.109954 34.36493)
			(stroke
				(width 0.1)
				(type default)
			)
			(layer "B.Fab")
		)
		(fp_line
			(start -6.469888 34.36493)
			(end -6.469888 -34.36493)
			(stroke
				(width 0.1)
				(type default)
			)
			(layer "B.Fab")
		)
		(fp_line
			(start -6.469888 -34.36493)
			(end 14.109954 -34.36493)
			(stroke
				(width 0.1)
				(type default)
			)
			(layer "B.Fab")
		)
		(fp_line
			(start 11.10996 31.364936)
			(end -3.469894 31.364936)
			(stroke
				(width 0.1)
				(type default)
			)
			(layer "F.Fab")
		)
		(fp_line
			(start 11.10996 -31.364936)
			(end 11.10996 31.364936)
			(stroke
				(width 0.1)
				(type default)
			)
			(layer "F.Fab")
		)
		(fp_line
			(start -3.469894 31.364936)
			(end -3.469894 -31.364936)
			(stroke
				(width 0.1)
				(type default)
			)
			(layer "F.Fab")
		)
		(fp_line
			(start -3.469894 -31.364936)
			(end 11.10996 -31.364936)
			(stroke
				(width 0.1)
				(type default)
			)
			(layer "F.Fab")
		)
		(fp_poly
			(pts
				(xy -5.0038 -0.508) (xy -5.0038 0.508) (xy -3.9878 0)
			)
			(stroke
				(width 0)
				(type default)
			)
			(fill yes)
			(layer "F.Fab")
		)
		(fp_text user "PRESS-FIT"
			(at 12.63015 -0.0127 90)
			(unlocked yes)
			(layer "F.SilkS")
			(effects
				(font
					(size 1.905 1.4224)
					(thickness 0.1524)
				)
			)
		)
		(fp_text user "PRESS-FIT"
			(at 12.855448 0.639064 270)
			(unlocked yes)
			(layer "B.SilkS")
			(effects
				(font
					(size 1.905 1.4224)
					(thickness 0.1524)
				)
				(justify mirror)
			)
		)
		(fp_text user "PRESS-FIT"
			(at 12.63015 -0.0127 90)
			(unlocked yes)
			(layer "B.Fab")
			(effects
				(font
					(size 1.905 1.4224)
					(thickness 0.1524)
				)
				(justify mirror)
			)
		)
		(fp_text user "PRESS-FIT"
			(at 12.63015 -0.0127 90)
			(unlocked yes)
			(layer "F.Fab")
			(effects
				(font
					(size 1.905 1.4224)
					(thickness 0.1524)
				)
			)
		)
		(pad "" np_thru_hole circle
			(at 0 -28.575 180)
			(size 0 0)
			(drill 3.2004)
			(layers "*.Cu" "*.Mask")
			(clearance 0)
		)
		(pad "" np_thru_hole circle
			(at 0 28.575 180)
			(size 0 0)
			(drill 3.2004)
			(layers "*.Cu" "*.Mask")
			(clearance 0)
		)
		(pad "A1" thru_hole rect
			(at 0 0 180)
			(size 1.52781 1.52781)
			(drill 1.01981)
			(layers "*.Cu" "*.Mask")
			(remove_unused_layers no)
			(net "P52V_2_BUSBAR")
			(clearance 0)
			(padstack
				(mode front_inner_back)
				(layer "Inner"
					(shape circle)
					(size 1.52781 1.52781)
					(clearance 0)
				)
				(layer "B.Cu"
					(shape rect)
					(size 1.52781 1.52781)
					(clearance 0)
				)
			)
		)
		(pad "B1" thru_hole circle
			(at 2.54 0 180)
			(size 1.52781 1.52781)
			(drill 1.01981)
			(layers "*.Cu" "*.Mask")
			(remove_unused_layers no)
			(net "GND_2_BUSBAR")
			(clearance 0)
		)
		(pad "C1" thru_hole circle
			(at 5.08 0 180)
			(size 1.52781 1.52781)
			(drill 1.01981)
			(layers "*.Cu" "*.Mask")
			(remove_unused_layers no)
			(net "NC_J7_C1")
			(clearance 0)
		)
		(pad "D1" thru_hole circle
			(at 7.62 0 180)
			(size 1.52781 1.52781)
			(drill 1.01981)
			(layers "*.Cu" "*.Mask")
			(remove_unused_layers no)
			(net "NC_J7_D1")
			(clearance 0)
		)
		(pad "P1_1" thru_hole circle
			(at 7.62 -16.51 180)
			(size 1.52781 1.52781)
			(drill 1.01981)
			(layers "*.Cu" "*.Mask")
			(remove_unused_layers no)
			(net "P52V_2")
			(clearance 0)
		)
		(pad "P1_2" thru_hole circle
			(at 5.08 -16.51 180)
			(size 1.52781 1.52781)
			(drill 1.01981)
			(layers "*.Cu" "*.Mask")
			(remove_unused_layers no)
			(net "P52V_2")
			(clearance 0)
		)
		(pad "P1_3" thru_hole circle
			(at 2.54 -16.51 180)
			(size 1.52781 1.52781)
			(drill 1.01981)
			(layers "*.Cu" "*.Mask")
			(remove_unused_layers no)
			(net "P52V_2")
			(clearance 0)
		)
		(pad "P1_4" thru_hole circle
			(at 0 -16.51 180)
			(size 1.52781 1.52781)
			(drill 1.01981)
			(layers "*.Cu" "*.Mask")
			(remove_unused_layers no)
			(net "P52V_2")
			(clearance 0)
		)
		(pad "P1_5" thru_hole circle
			(at 7.62 -13.97 180)
			(size 1.52781 1.52781)
			(drill 1.01981)
			(layers "*.Cu" "*.Mask")
			(remove_unused_layers no)
			(net "P52V_2")
			(clearance 0)
		)
		(pad "P1_6" thru_hole circle
			(at 5.08 -13.97 180)
			(size 1.52781 1.52781)
			(drill 1.01981)
			(layers "*.Cu" "*.Mask")
			(remove_unused_layers no)
			(net "P52V_2")
			(clearance 0)
		)
		(pad "P1_7" thru_hole circle
			(at 2.54 -13.97 180)
			(size 1.52781 1.52781)
			(drill 1.01981)
			(layers "*.Cu" "*.Mask")
			(remove_unused_layers no)
			(net "P52V_2")
			(clearance 0)
		)
		(pad "P1_8" thru_hole circle
			(at 0 -13.97 180)
			(size 1.52781 1.52781)
			(drill 1.01981)
			(layers "*.Cu" "*.Mask")
			(remove_unused_layers no)
			(net "P52V_2")
			(clearance 0)
		)
		(pad "P2_1" thru_hole circle
			(at 7.62 -7.62 180)
			(size 1.52781 1.52781)
			(drill 1.01981)
			(layers "*.Cu" "*.Mask")
			(remove_unused_layers no)
			(net "P52V_2")
			(clearance 0)
		)
		(pad "P2_2" thru_hole circle
			(at 5.08 -7.62 180)
			(size 1.52781 1.52781)
			(drill 1.01981)
			(layers "*.Cu" "*.Mask")
			(remove_unused_layers no)
			(net "P52V_2")
			(clearance 0)
		)
		(pad "P2_3" thru_hole circle
			(at 2.54 -7.62 180)
			(size 1.52781 1.52781)
			(drill 1.01981)
			(layers "*.Cu" "*.Mask")
			(remove_unused_layers no)
			(net "P52V_2")
			(clearance 0)
		)
		(pad "P2_4" thru_hole circle
			(at 0 -7.62 180)
			(size 1.52781 1.52781)
			(drill 1.01981)
			(layers "*.Cu" "*.Mask")
			(remove_unused_layers no)
			(net "P52V_2")
			(clearance 0)
		)
		(pad "P2_5" thru_hole circle
			(at 7.62 -5.08 180)
			(size 1.52781 1.52781)
			(drill 1.01981)
			(layers "*.Cu" "*.Mask")
			(remove_unused_layers no)
			(net "P52V_2")
			(clearance 0)
		)
		(pad "P2_6" thru_hole circle
			(at 5.08 -5.08 180)
			(size 1.52781 1.52781)
			(drill 1.01981)
			(layers "*.Cu" "*.Mask")
			(remove_unused_layers no)
			(net "P52V_2")
			(clearance 0)
		)
		(pad "P2_7" thru_hole circle
			(at 2.54 -5.08 180)
			(size 1.52781 1.52781)
			(drill 1.01981)
			(layers "*.Cu" "*.Mask")
			(remove_unused_layers no)
			(net "P52V_2")
			(clearance 0)
		)
		(pad "P2_8" thru_hole circle
			(at 0 -5.08 180)
			(size 1.52781 1.52781)
			(drill 1.01981)
			(layers "*.Cu" "*.Mask")
			(remove_unused_layers no)
			(net "P52V_2")
			(clearance 0)
		)
		(pad "P3_1" thru_hole circle
			(at 7.62 5.08 180)
			(size 1.52781 1.52781)
			(drill 1.01981)
			(layers "*.Cu" "*.Mask")
			(remove_unused_layers no)
			(net "GND")
			(clearance 0)
		)
		(pad "P3_2" thru_hole circle
			(at 5.08 5.08 180)
			(size 1.52781 1.52781)
			(drill 1.01981)
			(layers "*.Cu" "*.Mask")
			(remove_unused_layers no)
			(net "GND")
			(clearance 0)
		)
		(pad "P3_3" thru_hole circle
			(at 2.54 5.08 180)
			(size 1.52781 1.52781)
			(drill 1.01981)
			(layers "*.Cu" "*.Mask")
			(remove_unused_layers no)
			(net "GND")
			(clearance 0)
		)
		(pad "P3_4" thru_hole circle
			(at 0 5.08 180)
			(size 1.52781 1.52781)
			(drill 1.01981)
			(layers "*.Cu" "*.Mask")
			(remove_unused_layers no)
			(net "GND")
			(clearance 0)
		)
		(pad "P3_5" thru_hole circle
			(at 7.62 7.62 180)
			(size 1.52781 1.52781)
			(drill 1.01981)
			(layers "*.Cu" "*.Mask")
			(remove_unused_layers no)
			(net "GND")
			(clearance 0)
		)
		(pad "P3_6" thru_hole circle
			(at 5.08 7.62 180)
			(size 1.52781 1.52781)
			(drill 1.01981)
			(layers "*.Cu" "*.Mask")
			(remove_unused_layers no)
			(net "GND")
			(clearance 0)
		)
		(pad "P3_7" thru_hole circle
			(at 2.54 7.62 180)
			(size 1.52781 1.52781)
			(drill 1.01981)
			(layers "*.Cu" "*.Mask")
			(remove_unused_layers no)
			(net "GND")
			(clearance 0)
		)
		(pad "P3_8" thru_hole circle
			(at 0 7.62 180)
			(size 1.52781 1.52781)
			(drill 1.01981)
			(layers "*.Cu" "*.Mask")
			(remove_unused_layers no)
			(net "GND")
			(clearance 0)
		)
		(pad "P4_1" thru_hole circle
			(at 7.62 13.97 180)
			(size 1.52781 1.52781)
			(drill 1.01981)
			(layers "*.Cu" "*.Mask")
			(remove_unused_layers no)
			(net "GND")
			(clearance 0)
		)
		(pad "P4_2" thru_hole circle
			(at 5.08 13.97 180)
			(size 1.52781 1.52781)
			(drill 1.01981)
			(layers "*.Cu" "*.Mask")
			(remove_unused_layers no)
			(net "GND")
			(clearance 0)
		)
		(pad "P4_3" thru_hole circle
			(at 2.54 13.97 180)
			(size 1.52781 1.52781)
			(drill 1.01981)
			(layers "*.Cu" "*.Mask")
			(remove_unused_layers no)
			(net "GND")
			(clearance 0)
		)
		(pad "P4_4" thru_hole circle
			(at 0 13.97 180)
			(size 1.52781 1.52781)
			(drill 1.01981)
			(layers "*.Cu" "*.Mask")
			(remove_unused_layers no)
			(net "GND")
			(clearance 0)
		)
		(pad "P4_5" thru_hole circle
			(at 7.62 16.51 180)
			(size 1.52781 1.52781)
			(drill 1.01981)
			(layers "*.Cu" "*.Mask")
			(remove_unused_layers no)
			(net "GND")
			(clearance 0)
		)
		(pad "P4_6" thru_hole circle
			(at 5.08 16.51 180)
			(size 1.52781 1.52781)
			(drill 1.01981)
			(layers "*.Cu" "*.Mask")
			(remove_unused_layers no)
			(net "GND")
			(clearance 0)
		)
		(pad "P4_7" thru_hole circle
			(at 2.54 16.51 180)
			(size 1.52781 1.52781)
			(drill 1.01981)
			(layers "*.Cu" "*.Mask")
			(remove_unused_layers no)
			(net "GND")
			(clearance 0)
		)
		(pad "P4_8" thru_hole circle
			(at 0 16.51 180)
			(size 1.52781 1.52781)
			(drill 1.01981)
			(layers "*.Cu" "*.Mask")
			(remove_unused_layers no)
			(net "GND")
			(clearance 0)
		)
		(zone
			(layers "F.Cu" "B.Cu" "In1.Cu" "In2.Cu" "In3.Cu" "In4.Cu" "In5.Cu" "In6.Cu"
				"In7.Cu" "In8.Cu"
			)
			(hatch none 0.5)
			(connect_pads
				(clearance 0)
			)
			(min_thickness 0.25)
			(keepout
				(tracks not_allowed)
				(vias allowed)
				(pads allowed)
				(copperpour not_allowed)
				(footprints allowed)
			)
			(placement
				(enabled no)
				(sheetname "")
			)
			(fill
				(thermal_gap 0.5)
				(thermal_bridge_width 0.5)
				(island_removal_mode 0)
			)
			(polygon
				(pts
					(arc
						(start 212.442298 -79.624936)
						(mid 205.177898 -79.624936)
						(end 212.442298 -79.624936)
					)
				)
			)
		)
		(zone
			(layers "F.Cu" "B.Cu" "In1.Cu" "In2.Cu" "In3.Cu" "In4.Cu" "In5.Cu" "In6.Cu"
				"In7.Cu" "In8.Cu"
			)
			(hatch none 0.5)
			(connect_pads
				(clearance 0)
			)
			(min_thickness 0.25)
			(keepout
				(tracks not_allowed)
				(vias allowed)
				(pads allowed)
				(copperpour not_allowed)
				(footprints allowed)
			)
			(placement
				(enabled no)
				(sheetname "")
			)
			(fill
				(thermal_gap 0.5)
				(thermal_bridge_width 0.5)
				(island_removal_mode 0)
			)
			(polygon
				(pts
					(arc
						(start 212.442298 -22.474936)
						(mid 205.177898 -22.474936)
						(end 212.442298 -22.474936)
					)
				)
			)
		)
		(zone
			(layer "B.Cu")
			(hatch none 0.5)
			(connect_pads
				(clearance 0)
			)
			(min_thickness 0.25)
			(keepout
				(tracks allowed)
				(vias not_allowed)
				(pads allowed)
				(copperpour not_allowed)
				(footprints allowed)
			)
			(placement
				(enabled no)
				(sheetname "")
			)
			(fill
				(thermal_gap 0.5)
				(thermal_bridge_width 0.5)
				(island_removal_mode 0)
			)
			(polygon
				(pts
					(xy 209.637376 -33.712658) (xy 209.637376 -68.387214) (xy 200.36282 -68.387214) (xy 200.36282 -33.712658)
				)
			)
		)
	)
	(footprint ""
		(layer "F.Cu")
		(at 185.117994 -76.35113 180)
		(property "Reference" "R5945"
			(at 0 0 180)
			(layer "F.SilkS")
			(hide yes)
			(effects
				(font
					(size 1.27 1.27)
				)
			)
		)
		(property "Value" ""
			(at 0 0 180)
			(layer "F.Fab")
			(effects
				(font
					(size 1.27 1.27)
				)
			)
		)
		(duplicate_pad_numbers_are_jumpers no)
		(fp_line
			(start 0.7874 0.4064)
			(end -0.7874 0.4064)
			(stroke
				(width 0.1524)
				(type default)
			)
			(layer "F.SilkS")
		)
		(fp_line
			(start 0.7874 -0.4064)
			(end 0.7874 0.4064)
			(stroke
				(width 0.1524)
				(type default)
			)
			(layer "F.SilkS")
		)
		(fp_line
			(start -0.7874 0.4064)
			(end -0.7874 -0.4064)
			(stroke
				(width 0.1524)
				(type default)
			)
			(layer "F.SilkS")
		)
		(fp_line
			(start -0.7874 -0.4064)
			(end 0.7874 -0.4064)
			(stroke
				(width 0.1524)
				(type default)
			)
			(layer "F.SilkS")
		)
		(fp_line
			(start 0.67945 0.3048)
			(end 0.120396 0.3048)
			(stroke
				(width 0.1)
				(type default)
			)
			(layer "F.Fab")
		)
		(fp_line
			(start 0.67945 -0.3048)
			(end 0.67945 0.3048)
			(stroke
				(width 0.1)
				(type default)
			)
			(layer "F.Fab")
		)
		(fp_line
			(start 0.12065 -0.2794)
			(end 0.12065 -0.3048)
			(stroke
				(width 0.1)
				(type default)
			)
			(layer "F.Fab")
		)
		(fp_line
			(start 0.12065 -0.3048)
			(end 0.67945 -0.3048)
			(stroke
				(width 0.1)
				(type default)
			)
			(layer "F.Fab")
		)
		(fp_line
			(start 0.120396 0.3048)
			(end 0.120396 0.2794)
			(stroke
				(width 0.1)
				(type default)
			)
			(layer "F.Fab")
		)
		(fp_line
			(start 0.120396 0.2794)
			(end -0.12065 0.2794)
			(stroke
				(width 0.1)
				(type default)
			)
			(layer "F.Fab")
		)
		(fp_line
			(start -0.12065 0.3048)
			(end -0.67945 0.3048)
			(stroke
				(width 0.1)
				(type default)
			)
			(layer "F.Fab")
		)
		(fp_line
			(start -0.12065 0.2794)
			(end -0.12065 0.3048)
			(stroke
				(width 0.1)
				(type default)
			)
			(layer "F.Fab")
		)
		(fp_line
			(start -0.12065 -0.2794)
			(end 0.12065 -0.2794)
			(stroke
				(width 0.1)
				(type default)
			)
			(layer "F.Fab")
		)
		(fp_line
			(start -0.12065 -0.305054)
			(end -0.12065 -0.2794)
			(stroke
				(width 0.1)
				(type default)
			)
			(layer "F.Fab")
		)
		(fp_line
			(start -0.67945 0.3048)
			(end -0.67945 -0.305054)
			(stroke
				(width 0.1)
				(type default)
			)
			(layer "F.Fab")
		)
		(fp_line
			(start -0.67945 -0.305054)
			(end -0.12065 -0.305054)
			(stroke
				(width 0.1)
				(type default)
			)
			(layer "F.Fab")
		)
		(pad "1" smd circle
			(at -0.40005 0 180)
			(size 0 0)
			(layers "F.Cu" "F.Mask" "F.Paste")
			(net "P3V3_AUX")
		)
		(pad "2" smd circle
			(at 0.40005 0 180)
			(size 0 0)
			(layers "F.Cu" "F.Mask" "F.Paste")
			(net "FM_HS2_EN_FUSE_BUF")
		)
	)
	(footprint ""
		(layer "F.Cu")
		(at 302.4124 -69.977 180)
		(property "Reference" "PR6960"
			(at 0 0 180)
			(layer "F.SilkS")
			(hide yes)
			(effects
				(font
					(size 1.27 1.27)
				)
			)
		)
		(property "Value" ""
			(at 0 0 180)
			(layer "F.Fab")
			(effects
				(font
					(size 1.27 1.27)
				)
			)
		)
		(duplicate_pad_numbers_are_jumpers no)
		(fp_line
			(start 1.2954 0.5842)
			(end -1.2954 0.5842)
			(stroke
				(width 0.1524)
				(type default)
			)
			(layer "F.SilkS")
		)
		(fp_line
			(start 1.2954 -0.5842)
			(end 1.2954 0.5842)
			(stroke
				(width 0.1524)
				(type default)
			)
			(layer "F.SilkS")
		)
		(fp_line
			(start -1.2954 0.5842)
			(end -1.2954 -0.5842)
			(stroke
				(width 0.1524)
				(type default)
			)
			(layer "F.SilkS")
		)
		(fp_line
			(start -1.2954 -0.5842)
			(end 1.2954 -0.5842)
			(stroke
				(width 0.1524)
				(type default)
			)
			(layer "F.SilkS")
		)
		(fp_line
			(start 1.1938 0.4064)
			(end 0.8636 0.4064)
			(stroke
				(width 0.1)
				(type default)
			)
			(layer "F.Fab")
		)
		(fp_line
			(start 1.1938 -0.406654)
			(end 1.1938 0.4064)
			(stroke
				(width 0.1)
				(type default)
			)
			(layer "F.Fab")
		)
		(fp_line
			(start 0.8636 0.4572)
			(end -0.8636 0.4572)
			(stroke
				(width 0.1)
				(type default)
			)
			(layer "F.Fab")
		)
		(fp_line
			(start 0.8636 0.4064)
			(end 0.8636 0.4572)
			(stroke
				(width 0.1)
				(type default)
			)
			(layer "F.Fab")
		)
		(fp_line
			(start 0.8636 -0.406654)
			(end 1.1938 -0.406654)
			(stroke
				(width 0.1)
				(type default)
			)
			(layer "F.Fab")
		)
		(fp_line
			(start 0.8636 -0.4572)
			(end 0.8636 -0.406654)
			(stroke
				(width 0.1)
				(type default)
			)
			(layer "F.Fab")
		)
		(fp_line
			(start -0.8636 0.4572)
			(end -0.8636 0.4318)
			(stroke
				(width 0.1)
				(type default)
			)
			(layer "F.Fab")
		)
		(fp_line
			(start -0.8636 0.4318)
			(end -0.8636 0.4064)
			(stroke
				(width 0.1)
				(type default)
			)
			(layer "F.Fab")
		)
		(fp_line
			(start -0.8636 0.4064)
			(end -1.1938 0.4064)
			(stroke
				(width 0.1)
				(type default)
			)
			(layer "F.Fab")
		)
		(fp_line
			(start -0.8636 -0.406654)
			(end -0.8636 -0.4572)
			(stroke
				(width 0.1)
				(type default)
			)
			(layer "F.Fab")
		)
		(fp_line
			(start -0.8636 -0.4572)
			(end 0.8636 -0.4572)
			(stroke
				(width 0.1)
				(type default)
			)
			(layer "F.Fab")
		)
		(fp_line
			(start -1.1938 0.4064)
			(end -1.1938 -0.406654)
			(stroke
				(width 0.1)
				(type default)
			)
			(layer "F.Fab")
		)
		(fp_line
			(start -1.1938 -0.406654)
			(end -0.8636 -0.406654)
			(stroke
				(width 0.1)
				(type default)
			)
			(layer "F.Fab")
		)
		(pad "1" smd rect
			(at -0.7366 0 90)
			(size 0.7112 0.8128)
			(layers "F.Cu" "F.Mask" "F.Paste")
			(net "P52V_HS_1272_S_P")
		)
		(pad "2" smd rect
			(at 0.7366 0 90)
			(size 0.7112 0.8128)
			(layers "F.Cu" "F.Mask" "F.Paste")
			(net "P52V_HS1_SENSE_P_R1")
		)
	)
	(footprint ""
		(layer "F.Cu")
		(at 14.99997 -60.099956)
		(property "Reference" "H22"
			(at -1.02997 -8.961374 0)
			(unlocked yes)
			(layer "F.SilkS")
			(effects
				(font
					(size 0.7874 0.5842)
					(thickness 0.1524)
				)
				(justify left)
			)
		)
		(property "Value" ""
			(at 0 0 0)
			(layer "F.Fab")
			(effects
				(font
					(size 1.27 1.27)
				)
			)
		)
		(duplicate_pad_numbers_are_jumpers no)
		(fp_circle
			(center 0 0)
			(end 7.999984 0)
			(stroke
				(width 0.1524)
				(type default)
			)
			(fill no)
			(layer "F.SilkS")
		)
		(fp_circle
			(center 0 0)
			(end 7.999984 0)
			(stroke
				(width 0.1524)
				(type default)
			)
			(fill no)
			(layer "B.SilkS")
		)
		(fp_circle
			(center 0 0)
			(end 7.999984 0)
			(stroke
				(width 0.1)
				(type default)
			)
			(fill no)
			(layer "B.Fab")
		)
		(fp_circle
			(center 0 0)
			(end 7.999984 0)
			(stroke
				(width 0.1)
				(type default)
			)
			(fill no)
			(layer "F.Fab")
		)
		(pad "" np_thru_hole circle
			(at 0 0)
			(size 4.0132 4.0132)
			(drill 4.0132)
			(layers "*.Cu" "*.Mask")
			(clearance 0.381)
			(thermal_gap 0.381)
		)
		(pad "2" thru_hole circle
			(at 0 -3.50012)
			(size 0.762 0.762)
			(drill 0.5588)
			(layers "*.Cu" "*.Mask")
			(remove_unused_layers no)
			(net "GND")
			(clearance 0.1524)
			(thermal_gap 0.1524)
		)
		(pad "3" thru_hole circle
			(at -2.500122 -2.500122)
			(size 0.762 0.762)
			(drill 0.5588)
			(layers "*.Cu" "*.Mask")
			(remove_unused_layers no)
			(net "GND")
			(clearance 0.1524)
			(thermal_gap 0.1524)
		)
		(pad "4" thru_hole circle
			(at -3.50012 0)
			(size 0.762 0.762)
			(drill 0.5588)
			(layers "*.Cu" "*.Mask")
			(remove_unused_layers no)
			(net "GND")
			(clearance 0.1524)
			(thermal_gap 0.1524)
		)
		(pad "5" thru_hole circle
			(at -2.500122 2.500122)
			(size 0.762 0.762)
			(drill 0.5588)
			(layers "*.Cu" "*.Mask")
			(remove_unused_layers no)
			(net "GND")
			(clearance 0.1524)
			(thermal_gap 0.1524)
		)
		(pad "6" thru_hole circle
			(at 0 3.50012)
			(size 0.762 0.762)
			(drill 0.5588)
			(layers "*.Cu" "*.Mask")
			(remove_unused_layers no)
			(net "GND")
			(clearance 0.1524)
			(thermal_gap 0.1524)
		)
		(pad "7" thru_hole circle
			(at 2.500122 2.500122)
			(size 0.762 0.762)
			(drill 0.5588)
			(layers "*.Cu" "*.Mask")
			(remove_unused_layers no)
			(net "GND")
			(clearance 0.1524)
			(thermal_gap 0.1524)
		)
		(pad "8" thru_hole circle
			(at 3.50012 0)
			(size 0.762 0.762)
			(drill 0.5588)
			(layers "*.Cu" "*.Mask")
			(remove_unused_layers no)
			(net "GND")
			(clearance 0.1524)
			(thermal_gap 0.1524)
		)
		(pad "9" thru_hole circle
			(at 2.500122 -2.500122)
			(size 0.762 0.762)
			(drill 0.5588)
			(layers "*.Cu" "*.Mask")
			(remove_unused_layers no)
			(net "GND")
			(clearance 0.1524)
			(thermal_gap 0.1524)
		)
		(zone
			(layers "F.Cu" "B.Cu" "In1.Cu" "In2.Cu" "In3.Cu" "In4.Cu" "In5.Cu" "In6.Cu"
				"In7.Cu" "In8.Cu"
			)
			(hatch none 0.5)
			(connect_pads
				(clearance 0)
			)
			(min_thickness 0.25)
			(keepout
				(tracks not_allowed)
				(vias allowed)
				(pads allowed)
				(copperpour not_allowed)
				(footprints allowed)
			)
			(placement
				(enabled no)
				(sheetname "")
			)
			(fill
				(thermal_gap 0.5)
				(thermal_bridge_width 0.5)
				(island_removal_mode 0)
			)
			(polygon
				(pts
					(arc
						(start 17.51457 -60.099956)
						(mid 12.48537 -60.099956)
						(end 17.51457 -60.099956)
					)
				)
			)
		)
	)
	(footprint ""
		(layer "F.Cu")
		(at 447.263266 -82.01787)
		(property "Reference" "PC60"
			(at 0 0 0)
			(layer "F.SilkS")
			(hide yes)
			(effects
				(font
					(size 1.27 1.27)
				)
			)
		)
		(property "Value" ""
			(at 0 0 0)
			(layer "F.Fab")
			(effects
				(font
					(size 1.27 1.27)
				)
			)
		)
		(duplicate_pad_numbers_are_jumpers no)
		(fp_line
			(start -0.7874 -0.4064)
			(end 0.7874 -0.4064)
			(stroke
				(width 0.1524)
				(type default)
			)
			(layer "F.SilkS")
		)
		(fp_line
			(start -0.7874 0.4064)
			(end -0.7874 -0.4064)
			(stroke
				(width 0.1524)
				(type default)
			)
			(layer "F.SilkS")
		)
		(fp_line
			(start 0.7874 -0.4064)
			(end 0.7874 0.4064)
			(stroke
				(width 0.1524)
				(type default)
			)
			(layer "F.SilkS")
		)
		(fp_line
			(start 0.7874 0.4064)
			(end -0.7874 0.4064)
			(stroke
				(width 0.1524)
				(type default)
			)
			(layer "F.SilkS")
		)
		(fp_line
			(start -0.6858 -0.3048)
			(end -0.1016 -0.3048)
			(stroke
				(width 0.1)
				(type default)
			)
			(layer "F.Fab")
		)
		(fp_line
			(start -0.6858 0.3048)
			(end -0.6858 -0.3048)
			(stroke
				(width 0.1)
				(type default)
			)
			(layer "F.Fab")
		)
		(fp_line
			(start -0.1016 -0.3048)
			(end -0.1016 -0.2794)
			(stroke
				(width 0.1)
				(type default)
			)
			(layer "F.Fab")
		)
		(fp_line
			(start -0.1016 -0.2794)
			(end 0.1016 -0.2794)
			(stroke
				(width 0.1)
				(type default)
			)
			(layer "F.Fab")
		)
		(fp_line
			(start -0.1016 0.2794)
			(end -0.1016 0.3048)
			(stroke
				(width 0.1)
				(type default)
			)
			(layer "F.Fab")
		)
		(fp_line
			(start -0.1016 0.3048)
			(end -0.6858 0.3048)
			(stroke
				(width 0.1)
				(type default)
			)
			(layer "F.Fab")
		)
		(fp_line
			(start 0.1016 -0.3048)
			(end 0.6858 -0.3048)
			(stroke
				(width 0.1)
				(type default)
			)
			(layer "F.Fab")
		)
		(fp_line
			(start 0.1016 -0.2794)
			(end 0.1016 -0.3048)
			(stroke
				(width 0.1)
				(type default)
			)
			(layer "F.Fab")
		)
		(fp_line
			(start 0.1016 0.2794)
			(end -0.1016 0.2794)
			(stroke
				(width 0.1)
				(type default)
			)
			(layer "F.Fab")
		)
		(fp_line
			(start 0.1016 0.3048)
			(end 0.1016 0.2794)
			(stroke
				(width 0.1)
				(type default)
			)
			(layer "F.Fab")
		)
		(fp_line
			(start 0.6858 -0.3048)
			(end 0.6858 0.3048)
			(stroke
				(width 0.1)
				(type default)
			)
			(layer "F.Fab")
		)
		(fp_line
			(start 0.6858 0.3048)
			(end 0.1016 0.3048)
			(stroke
				(width 0.1)
				(type default)
			)
			(layer "F.Fab")
		)
		(pad "1" smd rect
			(at -0.40005 0 180)
			(size 0.4572 0.508)
			(layers "F.Cu" "F.Mask" "F.Paste")
			(net "SW_P3V3_HPDB_FLT")
		)
		(pad "2" smd rect
			(at 0.40005 0 180)
			(size 0.4572 0.508)
			(layers "F.Cu" "F.Mask" "F.Paste")
			(net "GND")
		)
	)
	(footprint ""
		(layer "F.Cu")
		(at 406.146 -35.56)
		(property "Reference" "R42"
			(at 0 0 0)
			(layer "F.SilkS")
			(hide yes)
			(effects
				(font
					(size 1.27 1.27)
				)
			)
		)
		(property "Value" ""
			(at 0 0 0)
			(layer "F.Fab")
			(effects
				(font
					(size 1.27 1.27)
				)
			)
		)
		(duplicate_pad_numbers_are_jumpers no)
		(fp_line
			(start -2.234946 -0.9271)
			(end 2.234946 -0.9271)
			(stroke
				(width 0.1524)
				(type default)
			)
			(layer "F.SilkS")
		)
		(fp_line
			(start -2.234946 0.9271)
			(end -2.234946 -0.9271)
			(stroke
				(width 0.1524)
				(type default)
			)
			(layer "F.SilkS")
		)
		(fp_line
			(start 2.234946 -0.9271)
			(end 2.234946 0.9271)
			(stroke
				(width 0.1524)
				(type default)
			)
			(layer "F.SilkS")
		)
		(fp_line
			(start 2.234946 0.9271)
			(end -2.234946 0.9271)
			(stroke
				(width 0.1524)
				(type default)
			)
			(layer "F.SilkS")
		)
		(fp_line
			(start -1.575054 -0.824992)
			(end -1.575054 0.824992)
			(stroke
				(width 0.1)
				(type default)
			)
			(layer "F.Fab")
		)
		(fp_line
			(start -1.575054 0.824992)
			(end 1.575054 0.824992)
			(stroke
				(width 0.1)
				(type default)
			)
			(layer "F.Fab")
		)
		(fp_line
			(start 1.575054 -0.824992)
			(end -1.575054 -0.824992)
			(stroke
				(width 0.1)
				(type default)
			)
			(layer "F.Fab")
		)
		(fp_line
			(start 1.575054 0.824992)
			(end 1.575054 -0.824992)
			(stroke
				(width 0.1)
				(type default)
			)
			(layer "F.Fab")
		)
		(pad "1" smd rect
			(at -1.599946 0)
			(size 1.016 1.6002)
			(layers "F.Cu" "F.Mask" "F.Paste")
			(net "LED_D1_R2")
		)
		(pad "2" smd rect
			(at 1.599946 0)
			(size 1.016 1.6002)
			(layers "F.Cu" "F.Mask" "F.Paste")
			(net "LED_D1_R3")
		)
	)
	(footprint ""
		(layer "F.Cu")
		(at 112.988852 -21.5392 -90)
		(property "Reference" "PR6975"
			(at 0 0 270)
			(layer "F.SilkS")
			(hide yes)
			(effects
				(font
					(size 1.27 1.27)
				)
			)
		)
		(property "Value" ""
			(at 0 0 270)
			(layer "F.Fab")
			(effects
				(font
					(size 1.27 1.27)
				)
			)
		)
		(duplicate_pad_numbers_are_jumpers no)
		(fp_line
			(start -1.2954 0.5842)
			(end -1.2954 -0.5842)
			(stroke
				(width 0.1524)
				(type default)
			)
			(layer "F.SilkS")
		)
		(fp_line
			(start 1.2954 0.5842)
			(end -1.2954 0.5842)
			(stroke
				(width 0.1524)
				(type default)
			)
			(layer "F.SilkS")
		)
		(fp_line
			(start -1.2954 -0.5842)
			(end 1.2954 -0.5842)
			(stroke
				(width 0.1524)
				(type default)
			)
			(layer "F.SilkS")
		)
		(fp_line
			(start 1.2954 -0.5842)
			(end 1.2954 0.5842)
			(stroke
				(width 0.1524)
				(type default)
			)
			(layer "F.SilkS")
		)
		(fp_line
			(start -0.8636 0.4572)
			(end -0.8636 0.4318)
			(stroke
				(width 0.1)
				(type default)
			)
			(layer "F.Fab")
		)
		(fp_line
			(start 0.8636 0.4572)
			(end -0.8636 0.4572)
			(stroke
				(width 0.1)
				(type default)
			)
			(layer "F.Fab")
		)
		(fp_line
			(start -0.8636 0.4318)
			(end -0.8636 0.4064)
			(stroke
				(width 0.1)
				(type default)
			)
			(layer "F.Fab")
		)
		(fp_line
			(start -1.1938 0.4064)
			(end -1.1938 -0.406654)
			(stroke
				(width 0.1)
				(type default)
			)
			(layer "F.Fab")
		)
		(fp_line
			(start -0.8636 0.4064)
			(end -1.1938 0.4064)
			(stroke
				(width 0.1)
				(type default)
			)
			(layer "F.Fab")
		)
		(fp_line
			(start 0.8636 0.4064)
			(end 0.8636 0.4572)
			(stroke
				(width 0.1)
				(type default)
			)
			(layer "F.Fab")
		)
		(fp_line
			(start 1.1938 0.4064)
			(end 0.8636 0.4064)
			(stroke
				(width 0.1)
				(type default)
			)
			(layer "F.Fab")
		)
		(fp_line
			(start -1.1938 -0.406654)
			(end -0.8636 -0.406654)
			(stroke
				(width 0.1)
				(type default)
			)
			(layer "F.Fab")
		)
		(fp_line
			(start -0.8636 -0.406654)
			(end -0.8636 -0.4572)
			(stroke
				(width 0.1)
				(type default)
			)
			(layer "F.Fab")
		)
		(fp_line
			(start 0.8636 -0.406654)
			(end 1.1938 -0.406654)
			(stroke
				(width 0.1)
				(type default)
			)
			(layer "F.Fab")
		)
		(fp_line
			(start 1.1938 -0.406654)
			(end 1.1938 0.4064)
			(stroke
				(width 0.1)
				(type default)
			)
			(layer "F.Fab")
		)
		(fp_line
			(start -0.8636 -0.4572)
			(end 0.8636 -0.4572)
			(stroke
				(width 0.1)
				(type default)
			)
			(layer "F.Fab")
		)
		(fp_line
			(start 0.8636 -0.4572)
			(end 0.8636 -0.406654)
			(stroke
				(width 0.1)
				(type default)
			)
			(layer "F.Fab")
		)
		(pad "1" smd rect
			(at -0.7366 0 180)
			(size 0.7112 0.8128)
			(layers "F.Cu" "F.Mask" "F.Paste")
			(net "P52V_HS2_GATE2_R")
		)
		(pad "2" smd rect
			(at 0.7366 0 180)
			(size 0.7112 0.8128)
			(layers "F.Cu" "F.Mask" "F.Paste")
			(net "P52V_HS2_GATE6")
		)
	)
	(footprint ""
		(layer "F.Cu")
		(at 33.85439 -39.243)
		(property "Reference" "R41"
			(at 0 0 0)
			(layer "F.SilkS")
			(hide yes)
			(effects
				(font
					(size 1.27 1.27)
				)
			)
		)
		(property "Value" ""
			(at 0 0 0)
			(layer "F.Fab")
			(effects
				(font
					(size 1.27 1.27)
				)
			)
		)
		(duplicate_pad_numbers_are_jumpers no)
		(fp_line
			(start -2.234946 -0.9271)
			(end 2.234946 -0.9271)
			(stroke
				(width 0.1524)
				(type default)
			)
			(layer "F.SilkS")
		)
		(fp_line
			(start -2.234946 0.9271)
			(end -2.234946 -0.9271)
			(stroke
				(width 0.1524)
				(type default)
			)
			(layer "F.SilkS")
		)
		(fp_line
			(start 2.234946 -0.9271)
			(end 2.234946 0.9271)
			(stroke
				(width 0.1524)
				(type default)
			)
			(layer "F.SilkS")
		)
		(fp_line
			(start 2.234946 0.9271)
			(end -2.234946 0.9271)
			(stroke
				(width 0.1524)
				(type default)
			)
			(layer "F.SilkS")
		)
		(fp_line
			(start -1.575054 -0.824992)
			(end -1.575054 0.824992)
			(stroke
				(width 0.1)
				(type default)
			)
			(layer "F.Fab")
		)
		(fp_line
			(start -1.575054 0.824992)
			(end 1.575054 0.824992)
			(stroke
				(width 0.1)
				(type default)
			)
			(layer "F.Fab")
		)
		(fp_line
			(start 1.575054 -0.824992)
			(end -1.575054 -0.824992)
			(stroke
				(width 0.1)
				(type default)
			)
			(layer "F.Fab")
		)
		(fp_line
			(start 1.575054 0.824992)
			(end 1.575054 -0.824992)
			(stroke
				(width 0.1)
				(type default)
			)
			(layer "F.Fab")
		)
		(pad "1" smd rect
			(at -1.599946 0)
			(size 1.016 1.6002)
			(layers "F.Cu" "F.Mask" "F.Paste")
			(net "LED_D2_R1")
		)
		(pad "2" smd rect
			(at 1.599946 0)
			(size 1.016 1.6002)
			(layers "F.Cu" "F.Mask" "F.Paste")
			(net "LED_D2_R2")
		)
	)
	(footprint ""
		(layer "F.Cu")
		(at 275.3614 -64.897)
		(property "Reference" "R358"
			(at 0 0 0)
			(layer "F.SilkS")
			(hide yes)
			(effects
				(font
					(size 1.27 1.27)
				)
			)
		)
		(property "Value" ""
			(at 0 0 0)
			(layer "F.Fab")
			(effects
				(font
					(size 1.27 1.27)
				)
			)
		)
		(duplicate_pad_numbers_are_jumpers no)
		(fp_line
			(start -0.7874 -0.4064)
			(end 0.7874 -0.4064)
			(stroke
				(width 0.1524)
				(type default)
			)
			(layer "F.SilkS")
		)
		(fp_line
			(start -0.7874 0.4064)
			(end -0.7874 -0.4064)
			(stroke
				(width 0.1524)
				(type default)
			)
			(layer "F.SilkS")
		)
		(fp_line
			(start 0.7874 -0.4064)
			(end 0.7874 0.4064)
			(stroke
				(width 0.1524)
				(type default)
			)
			(layer "F.SilkS")
		)
		(fp_line
			(start 0.7874 0.4064)
			(end -0.7874 0.4064)
			(stroke
				(width 0.1524)
				(type default)
			)
			(layer "F.SilkS")
		)
		(fp_line
			(start -0.67945 -0.305054)
			(end -0.12065 -0.305054)
			(stroke
				(width 0.1)
				(type default)
			)
			(layer "F.Fab")
		)
		(fp_line
			(start -0.67945 0.3048)
			(end -0.67945 -0.305054)
			(stroke
				(width 0.1)
				(type default)
			)
			(layer "F.Fab")
		)
		(fp_line
			(start -0.12065 -0.305054)
			(end -0.12065 -0.2794)
			(stroke
				(width 0.1)
				(type default)
			)
			(layer "F.Fab")
		)
		(fp_line
			(start -0.12065 -0.2794)
			(end 0.12065 -0.2794)
			(stroke
				(width 0.1)
				(type default)
			)
			(layer "F.Fab")
		)
		(fp_line
			(start -0.12065 0.2794)
			(end -0.12065 0.3048)
			(stroke
				(width 0.1)
				(type default)
			)
			(layer "F.Fab")
		)
		(fp_line
			(start -0.12065 0.3048)
			(end -0.67945 0.3048)
			(stroke
				(width 0.1)
				(type default)
			)
			(layer "F.Fab")
		)
		(fp_line
			(start 0.120396 0.2794)
			(end -0.12065 0.2794)
			(stroke
				(width 0.1)
				(type default)
			)
			(layer "F.Fab")
		)
		(fp_line
			(start 0.120396 0.3048)
			(end 0.120396 0.2794)
			(stroke
				(width 0.1)
				(type default)
			)
			(layer "F.Fab")
		)
		(fp_line
			(start 0.12065 -0.3048)
			(end 0.67945 -0.3048)
			(stroke
				(width 0.1)
				(type default)
			)
			(layer "F.Fab")
		)
		(fp_line
			(start 0.12065 -0.2794)
			(end 0.12065 -0.3048)
			(stroke
				(width 0.1)
				(type default)
			)
			(layer "F.Fab")
		)
		(fp_line
			(start 0.67945 -0.3048)
			(end 0.67945 0.3048)
			(stroke
				(width 0.1)
				(type default)
			)
			(layer "F.Fab")
		)
		(fp_line
			(start 0.67945 0.3048)
			(end 0.120396 0.3048)
			(stroke
				(width 0.1)
				(type default)
			)
			(layer "F.Fab")
		)
		(pad "1" smd circle
			(at -0.40005 0)
			(size 0 0)
			(layers "F.Cu" "F.Mask" "F.Paste")
			(net "P52V_HS1_GPO1")
		)
		(pad "2" smd circle
			(at 0.40005 0)
			(size 0 0)
			(layers "F.Cu" "F.Mask" "F.Paste")
			(net "P52V_HS1_FLT")
		)
	)
	(footprint ""
		(layer "F.Cu")
		(at 378.079 -99.06)
		(property "Reference" "PC32"
			(at 5.1054 -4.79933 0)
			(unlocked yes)
			(layer "F.SilkS")
			(effects
				(font
					(size 0.7874 0.5842)
					(thickness 0.1524)
				)
				(justify left)
			)
		)
		(property "Value" ""
			(at 0 0 0)
			(layer "F.Fab")
			(effects
				(font
					(size 1.27 1.27)
				)
			)
		)
		(duplicate_pad_numbers_are_jumpers no)
		(fp_line
			(start -9.253728 3.750056)
			(end 9.249918 3.750056)
			(stroke
				(width 0.1524)
				(type default)
			)
			(layer "F.SilkS")
		)
		(fp_line
			(start 0 3.750056)
			(end -9.253728 3.750056)
			(stroke
				(width 0.1524)
				(type default)
			)
			(layer "F.SilkS")
		)
		(fp_circle
			(center 0 3.750056)
			(end 9.249918 3.750056)
			(stroke
				(width 0.1524)
				(type default)
			)
			(fill no)
			(layer "F.SilkS")
		)
		(fp_poly
			(pts
				(arc
					(start 9.249918 3.750056)
					(mid 0 12.999974)
					(end -9.249918 3.750056)
				)
			)
			(stroke
				(width 0)
				(type default)
			)
			(fill yes)
			(layer "F.SilkS")
		)
		(fp_circle
			(center 0 3.750056)
			(end 9.249918 3.750056)
			(stroke
				(width 0.1)
				(type default)
			)
			(fill no)
			(layer "F.Fab")
		)
		(pad "1" thru_hole rect
			(at 0 0)
			(size 1.778 1.778)
			(drill 1.27)
			(layers "*.Cu" "*.Mask")
			(remove_unused_layers no)
			(net "P52V_HS1")
			(clearance 0)
			(padstack
				(mode front_inner_back)
				(layer "Inner"
					(shape circle)
					(size 1.778 1.778)
					(clearance 0)
				)
				(layer "B.Cu"
					(shape rect)
					(size 1.778 1.778)
					(clearance 0)
				)
			)
		)
		(pad "2" thru_hole circle
			(at 0 7.500112)
			(size 1.778 1.778)
			(drill 1.27)
			(layers "*.Cu" "*.Mask")
			(remove_unused_layers no)
			(net "GND")
			(clearance 0)
		)
	)
	(footprint ""
		(layer "F.Cu")
		(at 472.175078 -79.810102)
		(property "Reference" "J11"
			(at -5.5118 -17.948148 0)
			(unlocked yes)
			(layer "F.SilkS")
			(effects
				(font
					(size 0.7874 0.5842)
					(thickness 0.1524)
				)
				(justify left)
			)
		)
		(property "Value" ""
			(at 0 0 0)
			(layer "F.Fab")
			(effects
				(font
					(size 1.27 1.27)
				)
			)
		)
		(duplicate_pad_numbers_are_jumpers no)
		(fp_line
			(start -5.530088 -17.210024)
			(end 1.720088 -17.210024)
			(stroke
				(width 0.1524)
				(type default)
			)
			(layer "F.SilkS")
		)
		(fp_line
			(start -5.530088 29.29001)
			(end -5.530088 -17.210024)
			(stroke
				(width 0.1524)
				(type default)
			)
			(layer "F.SilkS")
		)
		(fp_line
			(start 1.720088 -17.210024)
			(end 1.720088 29.29001)
			(stroke
				(width 0.1524)
				(type default)
			)
			(layer "F.SilkS")
		)
		(fp_line
			(start 1.720088 29.29001)
			(end -5.530088 29.29001)
			(stroke
				(width 0.1524)
				(type default)
			)
			(layer "F.SilkS")
		)
		(fp_poly
			(pts
				(xy 2.9464 0.508) (xy 2.9464 -0.508) (xy 1.9304 0)
			)
			(stroke
				(width 0)
				(type default)
			)
			(fill yes)
			(layer "F.SilkS")
		)
		(fp_line
			(start -5.530088 -17.210024)
			(end 1.720088 -17.210024)
			(stroke
				(width 0.1)
				(type default)
			)
			(layer "F.Fab")
		)
		(fp_line
			(start -5.530088 29.29001)
			(end -5.530088 -17.210024)
			(stroke
				(width 0.1)
				(type default)
			)
			(layer "F.Fab")
		)
		(fp_line
			(start 1.720088 -17.210024)
			(end 1.720088 29.29001)
			(stroke
				(width 0.1)
				(type default)
			)
			(layer "F.Fab")
		)
		(fp_line
			(start 1.720088 29.29001)
			(end -5.530088 29.29001)
			(stroke
				(width 0.1)
				(type default)
			)
			(layer "F.Fab")
		)
		(fp_poly
			(pts
				(xy 2.9464 0.508) (xy 2.9464 -0.508) (xy 1.9304 0)
			)
			(stroke
				(width 0)
				(type default)
			)
			(fill yes)
			(layer "F.Fab")
		)
		(pad "" np_thru_hole circle
			(at -1.905 23.82012 90)
			(size 2.1844 2.1844)
			(drill 2.1844)
			(layers "*.Cu" "*.Mask")
			(clearance 0.381)
			(thermal_gap 0.381)
		)
		(pad "" np_thru_hole circle
			(at -0.55499 -11.73988 90)
			(size 2.1844 2.1844)
			(drill 2.1844)
			(layers "*.Cu" "*.Mask")
			(clearance 0.381)
			(thermal_gap 0.381)
		)
		(pad "P1" thru_hole circle
			(at -0.55499 21.28012 90)
			(size 1.5494 1.5494)
			(drill 1.0414)
			(layers "*.Cu" "*.Mask")
			(remove_unused_layers no)
			(net "GND")
			(clearance 0)
		)
		(pad "P2" thru_hole circle
			(at -0.55499 18.74012 90)
			(size 1.5494 1.5494)
			(drill 1.0414)
			(layers "*.Cu" "*.Mask")
			(remove_unused_layers no)
			(net "GND")
			(clearance 0)
		)
		(pad "P3" thru_hole circle
			(at -0.55499 16.20012 90)
			(size 1.5494 1.5494)
			(drill 1.0414)
			(layers "*.Cu" "*.Mask")
			(remove_unused_layers no)
			(net "GND")
			(clearance 0)
		)
		(pad "P4" thru_hole circle
			(at -0.55499 13.66012 90)
			(size 1.5494 1.5494)
			(drill 1.0414)
			(layers "*.Cu" "*.Mask")
			(remove_unused_layers no)
			(net "GND")
			(clearance 0)
		)
		(pad "P5" thru_hole circle
			(at -0.55499 11.12012 90)
			(size 1.5494 1.5494)
			(drill 1.0414)
			(layers "*.Cu" "*.Mask")
			(remove_unused_layers no)
			(net "P52V_FAN")
			(clearance 0)
		)
		(pad "P6" thru_hole circle
			(at -0.55499 8.58012 90)
			(size 1.5494 1.5494)
			(drill 1.0414)
			(layers "*.Cu" "*.Mask")
			(remove_unused_layers no)
			(net "P52V_FAN")
			(clearance 0)
		)
		(pad "P7" thru_hole circle
			(at -0.55499 6.04012 90)
			(size 1.5494 1.5494)
			(drill 1.0414)
			(layers "*.Cu" "*.Mask")
			(remove_unused_layers no)
			(net "P52V_FAN")
			(clearance 0)
		)
		(pad "P8" thru_hole circle
			(at -0.55499 3.50012 90)
			(size 1.5494 1.5494)
			(drill 1.0414)
			(layers "*.Cu" "*.Mask")
			(remove_unused_layers no)
			(net "P52V_FAN")
			(clearance 0)
		)
		(pad "P9" thru_hole circle
			(at -3.25501 3.50012 90)
			(size 1.5494 1.5494)
			(drill 1.0414)
			(layers "*.Cu" "*.Mask")
			(remove_unused_layers no)
			(net "P52V_FAN")
			(clearance 0)
		)
		(pad "P10" thru_hole circle
			(at -3.25501 6.04012 90)
			(size 1.5494 1.5494)
			(drill 1.0414)
			(layers "*.Cu" "*.Mask")
			(remove_unused_layers no)
			(net "P52V_FAN")
			(clearance 0)
		)
		(pad "P11" thru_hole circle
			(at -3.25501 8.58012 90)
			(size 1.5494 1.5494)
			(drill 1.0414)
			(layers "*.Cu" "*.Mask")
			(remove_unused_layers no)
			(net "P52V_FAN")
			(clearance 0)
		)
		(pad "P12" thru_hole circle
			(at -3.25501 11.12012 90)
			(size 1.5494 1.5494)
			(drill 1.0414)
			(layers "*.Cu" "*.Mask")
			(remove_unused_layers no)
			(net "P52V_FAN")
			(clearance 0)
		)
		(pad "P13" thru_hole circle
			(at -3.25501 13.66012 90)
			(size 1.5494 1.5494)
			(drill 1.0414)
			(layers "*.Cu" "*.Mask")
			(remove_unused_layers no)
			(net "GND")
			(clearance 0)
		)
		(pad "P14" thru_hole circle
			(at -3.25501 16.20012 90)
			(size 1.5494 1.5494)
			(drill 1.0414)
			(layers "*.Cu" "*.Mask")
			(remove_unused_layers no)
			(net "GND")
			(clearance 0)
		)
		(pad "P15" thru_hole circle
			(at -3.25501 18.74012 90)
			(size 1.5494 1.5494)
			(drill 1.0414)
			(layers "*.Cu" "*.Mask")
			(remove_unused_layers no)
			(net "GND")
			(clearance 0)
		)
		(pad "P16" thru_hole circle
			(at -3.25501 21.28012 90)
			(size 1.5494 1.5494)
			(drill 1.0414)
			(layers "*.Cu" "*.Mask")
			(remove_unused_layers no)
			(net "GND")
			(clearance 0)
		)
		(pad "S1" thru_hole circle
			(at 0 0 90)
			(size 1.5494 1.5494)
			(drill 1.0414)
			(layers "*.Cu" "*.Mask")
			(remove_unused_layers no)
			(net "GND")
			(clearance 0)
		)
		(pad "S2" thru_hole circle
			(at -1.27 -1.27 90)
			(size 1.5494 1.5494)
			(drill 1.0414)
			(layers "*.Cu" "*.Mask")
			(remove_unused_layers no)
			(net "PWRGD_P3V3_HPDB")
			(clearance 0)
		)
		(pad "S3" thru_hole circle
			(at 0 -2.54 90)
			(size 1.5494 1.5494)
			(drill 1.0414)
			(layers "*.Cu" "*.Mask")
			(remove_unused_layers no)
			(net "GND")
			(clearance 0)
		)
		(pad "S4" thru_hole circle
			(at -1.27 -3.81 90)
			(size 1.5494 1.5494)
			(drill 1.0414)
			(layers "*.Cu" "*.Mask")
			(remove_unused_layers no)
			(net "PWRGD_P52V_HS_PG")
			(clearance 0)
		)
		(pad "S5" thru_hole circle
			(at 0 -5.08 90)
			(size 1.5494 1.5494)
			(drill 1.0414)
			(layers "*.Cu" "*.Mask")
			(remove_unused_layers no)
			(net "SMB_P52V_R_SDA")
			(clearance 0)
		)
		(pad "S6" thru_hole circle
			(at -1.27 -6.35 90)
			(size 1.5494 1.5494)
			(drill 1.0414)
			(layers "*.Cu" "*.Mask")
			(remove_unused_layers no)
			(net "SMB_P52V_R_SCL")
			(clearance 0)
		)
		(pad "S7" thru_hole circle
			(at 0 -7.62 90)
			(size 1.5494 1.5494)
			(drill 1.0414)
			(layers "*.Cu" "*.Mask")
			(remove_unused_layers no)
			(net "SMB_PDB_R_SDA")
			(clearance 0)
		)
		(pad "S8" thru_hole circle
			(at -1.27 -8.89 90)
			(size 1.5494 1.5494)
			(drill 1.0414)
			(layers "*.Cu" "*.Mask")
			(remove_unused_layers no)
			(net "SMB_PDB_R_SCL")
			(clearance 0)
		)
		(pad "S9" thru_hole circle
			(at -3.81 -8.89 90)
			(size 1.5494 1.5494)
			(drill 1.0414)
			(layers "*.Cu" "*.Mask")
			(remove_unused_layers no)
			(net "P12V_HPDB")
			(clearance 0)
		)
		(pad "S10" thru_hole circle
			(at -2.54 -7.62 90)
			(size 1.5494 1.5494)
			(drill 1.0414)
			(layers "*.Cu" "*.Mask")
			(remove_unused_layers no)
			(net "P12V_HPDB")
			(clearance 0)
		)
		(pad "S11" thru_hole circle
			(at -3.81 -6.35 90)
			(size 1.5494 1.5494)
			(drill 1.0414)
			(layers "*.Cu" "*.Mask")
			(remove_unused_layers no)
			(net "PWRGD_P3V3_AUX_MB_BUF")
			(clearance 0)
		)
		(pad "S12" thru_hole circle
			(at -2.54 -5.08 90)
			(size 1.5494 1.5494)
			(drill 1.0414)
			(layers "*.Cu" "*.Mask")
			(remove_unused_layers no)
			(net "FAN_PWR_EN_BUF")
			(clearance 0)
		)
		(pad "S13" thru_hole circle
			(at -3.81 -3.81 90)
			(size 1.5494 1.5494)
			(drill 1.0414)
			(layers "*.Cu" "*.Mask")
			(remove_unused_layers no)
			(net "P12V_HPDB")
			(clearance 0)
		)
		(pad "S14" thru_hole circle
			(at -2.54 -2.54 90)
			(size 1.5494 1.5494)
			(drill 1.0414)
			(layers "*.Cu" "*.Mask")
			(remove_unused_layers no)
			(net "GPU_HSC_EN")
			(clearance 0)
		)
		(pad "S15" thru_hole circle
			(at -3.81 -1.27 90)
			(size 1.5494 1.5494)
			(drill 1.0414)
			(layers "*.Cu" "*.Mask")
			(remove_unused_layers no)
			(net "RST_SMB_PDB_BUF_N")
			(clearance 0)
		)
		(pad "S16" thru_hole circle
			(at -2.54 0 90)
			(size 1.5494 1.5494)
			(drill 1.0414)
			(layers "*.Cu" "*.Mask")
			(remove_unused_layers no)
			(net "P12V_HPDB_PWRGD")
			(clearance 0)
		)
		(zone
			(layers "F.Cu" "B.Cu" "In1.Cu" "In2.Cu" "In3.Cu" "In4.Cu" "In5.Cu" "In6.Cu"
				"In7.Cu" "In8.Cu"
			)
			(hatch none 0.5)
			(connect_pads
				(clearance 0)
			)
			(min_thickness 0.25)
			(keepout
				(tracks not_allowed)
				(vias allowed)
				(pads allowed)
				(copperpour not_allowed)
				(footprints allowed)
			)
			(placement
				(enabled no)
				(sheetname "")
			)
			(fill
				(thermal_gap 0.5)
				(thermal_bridge_width 0.5)
				(island_removal_mode 0)
			)
			(polygon
				(pts
					(arc
						(start 471.870278 -55.989982)
						(mid 468.669878 -55.989982)
						(end 471.870278 -55.989982)
					)
				)
			)
		)
		(zone
			(layers "F.Cu" "B.Cu" "In1.Cu" "In2.Cu" "In3.Cu" "In4.Cu" "In5.Cu" "In6.Cu"
				"In7.Cu" "In8.Cu"
			)
			(hatch none 0.5)
			(connect_pads
				(clearance 0)
			)
			(min_thickness 0.25)
			(keepout
				(tracks not_allowed)
				(vias allowed)
				(pads allowed)
				(copperpour not_allowed)
				(footprints allowed)
			)
			(placement
				(enabled no)
				(sheetname "")
			)
			(fill
				(thermal_gap 0.5)
				(thermal_bridge_width 0.5)
				(island_removal_mode 0)
			)
			(polygon
				(pts
					(arc
						(start 473.220288 -91.549982)
						(mid 470.019888 -91.549982)
						(end 473.220288 -91.549982)
					)
				)
			)
		)
	)
	(footprint ""
		(layer "F.Cu")
		(at 261.1374 -48.387)
		(property "Reference" "R154"
			(at 0 0 0)
			(layer "F.SilkS")
			(hide yes)
			(effects
				(font
					(size 1.27 1.27)
				)
			)
		)
		(property "Value" ""
			(at 0 0 0)
			(layer "F.Fab")
			(effects
				(font
					(size 1.27 1.27)
				)
			)
		)
		(duplicate_pad_numbers_are_jumpers no)
		(fp_line
			(start -1.651 -0.8382)
			(end 1.651 -0.8382)
			(stroke
				(width 0.1524)
				(type default)
			)
			(layer "F.SilkS")
		)
		(fp_line
			(start -1.651 0.8382)
			(end -1.651 -0.8382)
			(stroke
				(width 0.1524)
				(type default)
			)
			(layer "F.SilkS")
		)
		(fp_line
			(start 1.651 -0.8382)
			(end 1.651 0.8382)
			(stroke
				(width 0.1524)
				(type default)
			)
			(layer "F.SilkS")
		)
		(fp_line
			(start 1.651 0.8382)
			(end -1.651 0.8382)
			(stroke
				(width 0.1524)
				(type default)
			)
			(layer "F.SilkS")
		)
		(fp_line
			(start -1.559814 -0.7366)
			(end -1.559814 0.7366)
			(stroke
				(width 0.1)
				(type default)
			)
			(layer "F.Fab")
		)
		(fp_line
			(start -1.559814 0.7366)
			(end -1.524 0.7366)
			(stroke
				(width 0.1)
				(type default)
			)
			(layer "F.Fab")
		)
		(fp_line
			(start -1.524 -0.7366)
			(end -1.559814 -0.7366)
			(stroke
				(width 0.1)
				(type default)
			)
			(layer "F.Fab")
		)
		(fp_line
			(start -1.524 0.7366)
			(end 1.524 0.7366)
			(stroke
				(width 0.1)
				(type default)
			)
			(layer "F.Fab")
		)
		(fp_line
			(start 1.524 -0.7366)
			(end -1.524 -0.7366)
			(stroke
				(width 0.1)
				(type default)
			)
			(layer "F.Fab")
		)
		(fp_line
			(start 1.524 0.7366)
			(end 1.560576 0.7366)
			(stroke
				(width 0.1)
				(type default)
			)
			(layer "F.Fab")
		)
		(fp_line
			(start 1.560576 -0.7366)
			(end 1.524 -0.7366)
			(stroke
				(width 0.1)
				(type default)
			)
			(layer "F.Fab")
		)
		(fp_line
			(start 1.560576 0.7366)
			(end 1.560576 -0.7366)
			(stroke
				(width 0.1)
				(type default)
			)
			(layer "F.Fab")
		)
		(pad "1" smd rect
			(at -0.94996 0 180)
			(size 1.1176 1.3716)
			(layers "F.Cu" "F.Mask" "F.Paste")
			(net "P52V_1_FUSE_1")
		)
		(pad "2" smd rect
			(at 0.94996 0 180)
			(size 1.1176 1.3716)
			(layers "F.Cu" "F.Mask" "F.Paste")
			(net "GPU_HSC1_BUF_EN_N")
		)
	)
	(footprint ""
		(layer "F.Cu")
		(at 438.023 -44.45 180)
		(property "Reference" "R381"
			(at 0 0 180)
			(layer "F.SilkS")
			(hide yes)
			(effects
				(font
					(size 1.27 1.27)
				)
			)
		)
		(property "Value" ""
			(at 0 0 180)
			(layer "F.Fab")
			(effects
				(font
					(size 1.27 1.27)
				)
			)
		)
		(duplicate_pad_numbers_are_jumpers no)
		(fp_line
			(start 0.7874 0.4064)
			(end -0.7874 0.4064)
			(stroke
				(width 0.1524)
				(type default)
			)
			(layer "F.SilkS")
		)
		(fp_line
			(start 0.7874 -0.4064)
			(end 0.7874 0.4064)
			(stroke
				(width 0.1524)
				(type default)
			)
			(layer "F.SilkS")
		)
		(fp_line
			(start -0.7874 0.4064)
			(end -0.7874 -0.4064)
			(stroke
				(width 0.1524)
				(type default)
			)
			(layer "F.SilkS")
		)
		(fp_line
			(start -0.7874 -0.4064)
			(end 0.7874 -0.4064)
			(stroke
				(width 0.1524)
				(type default)
			)
			(layer "F.SilkS")
		)
		(fp_line
			(start 0.67945 0.3048)
			(end 0.120396 0.3048)
			(stroke
				(width 0.1)
				(type default)
			)
			(layer "F.Fab")
		)
		(fp_line
			(start 0.67945 -0.3048)
			(end 0.67945 0.3048)
			(stroke
				(width 0.1)
				(type default)
			)
			(layer "F.Fab")
		)
		(fp_line
			(start 0.12065 -0.2794)
			(end 0.12065 -0.3048)
			(stroke
				(width 0.1)
				(type default)
			)
			(layer "F.Fab")
		)
		(fp_line
			(start 0.12065 -0.3048)
			(end 0.67945 -0.3048)
			(stroke
				(width 0.1)
				(type default)
			)
			(layer "F.Fab")
		)
		(fp_line
			(start 0.120396 0.3048)
			(end 0.120396 0.2794)
			(stroke
				(width 0.1)
				(type default)
			)
			(layer "F.Fab")
		)
		(fp_line
			(start 0.120396 0.2794)
			(end -0.12065 0.2794)
			(stroke
				(width 0.1)
				(type default)
			)
			(layer "F.Fab")
		)
		(fp_line
			(start -0.12065 0.3048)
			(end -0.67945 0.3048)
			(stroke
				(width 0.1)
				(type default)
			)
			(layer "F.Fab")
		)
		(fp_line
			(start -0.12065 0.2794)
			(end -0.12065 0.3048)
			(stroke
				(width 0.1)
				(type default)
			)
			(layer "F.Fab")
		)
		(fp_line
			(start -0.12065 -0.2794)
			(end 0.12065 -0.2794)
			(stroke
				(width 0.1)
				(type default)
			)
			(layer "F.Fab")
		)
		(fp_line
			(start -0.12065 -0.305054)
			(end -0.12065 -0.2794)
			(stroke
				(width 0.1)
				(type default)
			)
			(layer "F.Fab")
		)
		(fp_line
			(start -0.67945 0.3048)
			(end -0.67945 -0.305054)
			(stroke
				(width 0.1)
				(type default)
			)
			(layer "F.Fab")
		)
		(fp_line
			(start -0.67945 -0.305054)
			(end -0.12065 -0.305054)
			(stroke
				(width 0.1)
				(type default)
			)
			(layer "F.Fab")
		)
		(pad "1" smd circle
			(at -0.40005 0 180)
			(size 0 0)
			(layers "F.Cu" "F.Mask" "F.Paste")
			(net "GPU_HSC_EN")
		)
		(pad "2" smd circle
			(at 0.40005 0 180)
			(size 0 0)
			(layers "F.Cu" "F.Mask" "F.Paste")
			(net "P3V3_AUX")
		)
	)
	(footprint ""
		(layer "F.Cu")
		(at 412.7754 -51.435)
		(property "Reference" "R160"
			(at 0 0 0)
			(layer "F.SilkS")
			(hide yes)
			(effects
				(font
					(size 1.27 1.27)
				)
			)
		)
		(property "Value" ""
			(at 0 0 0)
			(layer "F.Fab")
			(effects
				(font
					(size 1.27 1.27)
				)
			)
		)
		(duplicate_pad_numbers_are_jumpers no)
		(fp_line
			(start -1.651 -0.8382)
			(end 1.651 -0.8382)
			(stroke
				(width 0.1524)
				(type default)
			)
			(layer "F.SilkS")
		)
		(fp_line
			(start -1.651 0.8382)
			(end -1.651 -0.8382)
			(stroke
				(width 0.1524)
				(type default)
			)
			(layer "F.SilkS")
		)
		(fp_line
			(start 1.651 -0.8382)
			(end 1.651 0.8382)
			(stroke
				(width 0.1524)
				(type default)
			)
			(layer "F.SilkS")
		)
		(fp_line
			(start 1.651 0.8382)
			(end -1.651 0.8382)
			(stroke
				(width 0.1524)
				(type default)
			)
			(layer "F.SilkS")
		)
		(fp_line
			(start -1.559814 -0.7366)
			(end -1.559814 0.7366)
			(stroke
				(width 0.1)
				(type default)
			)
			(layer "F.Fab")
		)
		(fp_line
			(start -1.559814 0.7366)
			(end -1.524 0.7366)
			(stroke
				(width 0.1)
				(type default)
			)
			(layer "F.Fab")
		)
		(fp_line
			(start -1.524 -0.7366)
			(end -1.559814 -0.7366)
			(stroke
				(width 0.1)
				(type default)
			)
			(layer "F.Fab")
		)
		(fp_line
			(start -1.524 0.7366)
			(end 1.524 0.7366)
			(stroke
				(width 0.1)
				(type default)
			)
			(layer "F.Fab")
		)
		(fp_line
			(start 1.524 -0.7366)
			(end -1.524 -0.7366)
			(stroke
				(width 0.1)
				(type default)
			)
			(layer "F.Fab")
		)
		(fp_line
			(start 1.524 0.7366)
			(end 1.560576 0.7366)
			(stroke
				(width 0.1)
				(type default)
			)
			(layer "F.Fab")
		)
		(fp_line
			(start 1.560576 -0.7366)
			(end 1.524 -0.7366)
			(stroke
				(width 0.1)
				(type default)
			)
			(layer "F.Fab")
		)
		(fp_line
			(start 1.560576 0.7366)
			(end 1.560576 -0.7366)
			(stroke
				(width 0.1)
				(type default)
			)
			(layer "F.Fab")
		)
		(pad "1" smd rect
			(at -0.94996 0 180)
			(size 1.1176 1.3716)
			(layers "F.Cu" "F.Mask" "F.Paste")
			(net "P52V_HS1")
		)
		(pad "2" smd rect
			(at 0.94996 0 180)
			(size 1.1176 1.3716)
			(layers "F.Cu" "F.Mask" "F.Paste")
			(net "PWRGD_P52V_HS1_4287_PG_R_N")
		)
	)
	(footprint ""
		(layer "F.Cu")
		(at 436.1434 -37.211 -90)
		(property "Reference" "R8"
			(at 0 0 270)
			(layer "F.SilkS")
			(hide yes)
			(effects
				(font
					(size 1.27 1.27)
				)
			)
		)
		(property "Value" ""
			(at 0 0 270)
			(layer "F.Fab")
			(effects
				(font
					(size 1.27 1.27)
				)
			)
		)
		(duplicate_pad_numbers_are_jumpers no)
		(fp_line
			(start -0.7874 0.4064)
			(end -0.7874 -0.4064)
			(stroke
				(width 0.1524)
				(type default)
			)
			(layer "F.SilkS")
		)
		(fp_line
			(start 0.7874 0.4064)
			(end -0.7874 0.4064)
			(stroke
				(width 0.1524)
				(type default)
			)
			(layer "F.SilkS")
		)
		(fp_line
			(start -0.7874 -0.4064)
			(end 0.7874 -0.4064)
			(stroke
				(width 0.1524)
				(type default)
			)
			(layer "F.SilkS")
		)
		(fp_line
			(start 0.7874 -0.4064)
			(end 0.7874 0.4064)
			(stroke
				(width 0.1524)
				(type default)
			)
			(layer "F.SilkS")
		)
		(fp_line
			(start -0.67945 0.3048)
			(end -0.67945 -0.305054)
			(stroke
				(width 0.1)
				(type default)
			)
			(layer "F.Fab")
		)
		(fp_line
			(start -0.12065 0.3048)
			(end -0.67945 0.3048)
			(stroke
				(width 0.1)
				(type default)
			)
			(layer "F.Fab")
		)
		(fp_line
			(start 0.120396 0.3048)
			(end 0.120396 0.2794)
			(stroke
				(width 0.1)
				(type default)
			)
			(layer "F.Fab")
		)
		(fp_line
			(start 0.67945 0.3048)
			(end 0.120396 0.3048)
			(stroke
				(width 0.1)
				(type default)
			)
			(layer "F.Fab")
		)
		(fp_line
			(start -0.12065 0.2794)
			(end -0.12065 0.3048)
			(stroke
				(width 0.1)
				(type default)
			)
			(layer "F.Fab")
		)
		(fp_line
			(start 0.120396 0.2794)
			(end -0.12065 0.2794)
			(stroke
				(width 0.1)
				(type default)
			)
			(layer "F.Fab")
		)
		(fp_line
			(start -0.12065 -0.2794)
			(end 0.12065 -0.2794)
			(stroke
				(width 0.1)
				(type default)
			)
			(layer "F.Fab")
		)
		(fp_line
			(start 0.12065 -0.2794)
			(end 0.12065 -0.3048)
			(stroke
				(width 0.1)
				(type default)
			)
			(layer "F.Fab")
		)
		(fp_line
			(start 0.12065 -0.3048)
			(end 0.67945 -0.3048)
			(stroke
				(width 0.1)
				(type default)
			)
			(layer "F.Fab")
		)
		(fp_line
			(start 0.67945 -0.3048)
			(end 0.67945 0.3048)
			(stroke
				(width 0.1)
				(type default)
			)
			(layer "F.Fab")
		)
		(fp_line
			(start -0.67945 -0.305054)
			(end -0.12065 -0.305054)
			(stroke
				(width 0.1)
				(type default)
			)
			(layer "F.Fab")
		)
		(fp_line
			(start -0.12065 -0.305054)
			(end -0.12065 -0.2794)
			(stroke
				(width 0.1)
				(type default)
			)
			(layer "F.Fab")
		)
		(pad "1" smd circle
			(at -0.40005 0 270)
			(size 0 0)
			(layers "F.Cu" "F.Mask" "F.Paste")
			(net "SMB_P52V_PDB_SCL_R")
		)
		(pad "2" smd circle
			(at 0.40005 0 270)
			(size 0 0)
			(layers "F.Cu" "F.Mask" "F.Paste")
			(net "P3V3_AUX")
		)
	)
	(footprint ""
		(layer "F.Cu")
		(at 151.003 -80.772)
		(property "Reference" "R5905"
			(at 0 0 0)
			(layer "F.SilkS")
			(hide yes)
			(effects
				(font
					(size 1.27 1.27)
				)
			)
		)
		(property "Value" ""
			(at 0 0 0)
			(layer "F.Fab")
			(effects
				(font
					(size 1.27 1.27)
				)
			)
		)
		(duplicate_pad_numbers_are_jumpers no)
		(fp_line
			(start -1.651 -0.8382)
			(end 1.651 -0.8382)
			(stroke
				(width 0.1524)
				(type default)
			)
			(layer "F.SilkS")
		)
		(fp_line
			(start -1.651 0.8382)
			(end -1.651 -0.8382)
			(stroke
				(width 0.1524)
				(type default)
			)
			(layer "F.SilkS")
		)
		(fp_line
			(start 1.651 -0.8382)
			(end 1.651 0.8382)
			(stroke
				(width 0.1524)
				(type default)
			)
			(layer "F.SilkS")
		)
		(fp_line
			(start 1.651 0.8382)
			(end -1.651 0.8382)
			(stroke
				(width 0.1524)
				(type default)
			)
			(layer "F.SilkS")
		)
		(fp_line
			(start -1.559814 -0.7366)
			(end -1.559814 0.7366)
			(stroke
				(width 0.1)
				(type default)
			)
			(layer "F.Fab")
		)
		(fp_line
			(start -1.559814 0.7366)
			(end -1.524 0.7366)
			(stroke
				(width 0.1)
				(type default)
			)
			(layer "F.Fab")
		)
		(fp_line
			(start -1.524 -0.7366)
			(end -1.559814 -0.7366)
			(stroke
				(width 0.1)
				(type default)
			)
			(layer "F.Fab")
		)
		(fp_line
			(start -1.524 0.7366)
			(end 1.524 0.7366)
			(stroke
				(width 0.1)
				(type default)
			)
			(layer "F.Fab")
		)
		(fp_line
			(start 1.524 -0.7366)
			(end -1.524 -0.7366)
			(stroke
				(width 0.1)
				(type default)
			)
			(layer "F.Fab")
		)
		(fp_line
			(start 1.524 0.7366)
			(end 1.560576 0.7366)
			(stroke
				(width 0.1)
				(type default)
			)
			(layer "F.Fab")
		)
		(fp_line
			(start 1.560576 -0.7366)
			(end 1.524 -0.7366)
			(stroke
				(width 0.1)
				(type default)
			)
			(layer "F.Fab")
		)
		(fp_line
			(start 1.560576 0.7366)
			(end 1.560576 -0.7366)
			(stroke
				(width 0.1)
				(type default)
			)
			(layer "F.Fab")
		)
		(pad "1" smd rect
			(at -0.94996 0 180)
			(size 1.1176 1.3716)
			(layers "F.Cu" "F.Mask" "F.Paste")
			(net "P52V_2")
		)
		(pad "2" smd rect
			(at 0.94996 0 180)
			(size 1.1176 1.3716)
			(layers "F.Cu" "F.Mask" "F.Paste")
			(net "P3V3_2_AND")
		)
	)
	(footprint ""
		(layer "F.Cu")
		(at 183.642 -78.486 -90)
		(property "Reference" "U45"
			(at -3.26263 1.0795 0)
			(unlocked yes)
			(layer "F.SilkS")
			(effects
				(font
					(size 0.7874 0.5842)
					(thickness 0.1524)
				)
				(justify left)
			)
		)
		(property "Value" ""
			(at 0 0 270)
			(layer "F.Fab")
			(effects
				(font
					(size 1.27 1.27)
				)
			)
		)
		(duplicate_pad_numbers_are_jumpers no)
		(fp_line
			(start -1.400048 1.100074)
			(end -1.400048 -1.100074)
			(stroke
				(width 0.1524)
				(type default)
			)
			(layer "F.SilkS")
		)
		(fp_line
			(start 1.400048 1.100074)
			(end -1.400048 1.100074)
			(stroke
				(width 0.1524)
				(type default)
			)
			(layer "F.SilkS")
		)
		(fp_line
			(start 1.400048 -1.100074)
			(end 1.400048 1.100074)
			(stroke
				(width 0.1524)
				(type default)
			)
			(layer "F.SilkS")
		)
		(fp_line
			(start 1.400048 -1.100074)
			(end -1.400048 -1.100074)
			(stroke
				(width 0.1524)
				(type default)
			)
			(layer "F.SilkS")
		)
		(fp_poly
			(pts
				(xy -1.590548 -0.649986) (xy -2.606548 -1.157986) (xy -2.606548 -0.141986)
			)
			(stroke
				(width 0)
				(type default)
			)
			(fill yes)
			(layer "F.SilkS")
		)
		(fp_line
			(start -0.674878 1.100074)
			(end -0.674878 -1.100074)
			(stroke
				(width 0.1)
				(type default)
			)
			(layer "F.Fab")
		)
		(fp_line
			(start 0.674878 1.100074)
			(end -0.674878 1.100074)
			(stroke
				(width 0.1)
				(type default)
			)
			(layer "F.Fab")
		)
		(fp_line
			(start -0.674878 -1.100074)
			(end 0.674878 -1.100074)
			(stroke
				(width 0.1)
				(type default)
			)
			(layer "F.Fab")
		)
		(fp_line
			(start 0.674878 -1.100074)
			(end 0.674878 1.100074)
			(stroke
				(width 0.1)
				(type default)
			)
			(layer "F.Fab")
		)
		(fp_poly
			(pts
				(xy -1.590548 -0.649986) (xy -2.606548 -1.157986) (xy -2.606548 -0.141986)
			)
			(stroke
				(width 0)
				(type default)
			)
			(fill yes)
			(layer "F.Fab")
		)
		(pad "1" smd rect
			(at -0.94996 -0.649986 180)
			(size 0.4318 0.6096)
			(layers "F.Cu" "F.Mask" "F.Paste")
			(net "Net_415")
		)
		(pad "2" smd rect
			(at -0.94996 0 180)
			(size 0.4318 0.6096)
			(layers "F.Cu" "F.Mask" "F.Paste")
			(net "FM_HS2_EN_FUSE")
		)
		(pad "3" smd rect
			(at -0.94996 0.649986 180)
			(size 0.4318 0.6096)
			(layers "F.Cu" "F.Mask" "F.Paste")
			(net "GND")
		)
		(pad "4" smd rect
			(at 0.94996 0.649986 180)
			(size 0.4318 0.6096)
			(layers "F.Cu" "F.Mask" "F.Paste")
			(net "FM_HS2_EN_FUSE_BUF")
		)
		(pad "5" smd rect
			(at 0.94996 -0.649986 180)
			(size 0.4318 0.6096)
			(layers "F.Cu" "F.Mask" "F.Paste")
			(net "P3V3_AUX")
		)
	)
	(footprint ""
		(layer "F.Cu")
		(at 435.0004 -48.133 180)
		(property "Reference" "C89"
			(at 0 0 180)
			(layer "F.SilkS")
			(hide yes)
			(effects
				(font
					(size 1.27 1.27)
				)
			)
		)
		(property "Value" ""
			(at 0 0 180)
			(layer "F.Fab")
			(effects
				(font
					(size 1.27 1.27)
				)
			)
		)
		(duplicate_pad_numbers_are_jumpers no)
		(fp_line
			(start 0.7874 0.4064)
			(end -0.7874 0.4064)
			(stroke
				(width 0.1524)
				(type default)
			)
			(layer "F.SilkS")
		)
		(fp_line
			(start 0.7874 -0.4064)
			(end 0.7874 0.4064)
			(stroke
				(width 0.1524)
				(type default)
			)
			(layer "F.SilkS")
		)
		(fp_line
			(start -0.7874 0.4064)
			(end -0.7874 -0.4064)
			(stroke
				(width 0.1524)
				(type default)
			)
			(layer "F.SilkS")
		)
		(fp_line
			(start -0.7874 -0.4064)
			(end 0.7874 -0.4064)
			(stroke
				(width 0.1524)
				(type default)
			)
			(layer "F.SilkS")
		)
		(fp_line
			(start 0.67945 0.3048)
			(end 0.120396 0.3048)
			(stroke
				(width 0.1)
				(type default)
			)
			(layer "F.Fab")
		)
		(fp_line
			(start 0.67945 -0.3048)
			(end 0.67945 0.3048)
			(stroke
				(width 0.1)
				(type default)
			)
			(layer "F.Fab")
		)
		(fp_line
			(start 0.12065 -0.2794)
			(end 0.12065 -0.3048)
			(stroke
				(width 0.1)
				(type default)
			)
			(layer "F.Fab")
		)
		(fp_line
			(start 0.12065 -0.3048)
			(end 0.67945 -0.3048)
			(stroke
				(width 0.1)
				(type default)
			)
			(layer "F.Fab")
		)
		(fp_line
			(start 0.120396 0.3048)
			(end 0.120396 0.2794)
			(stroke
				(width 0.1)
				(type default)
			)
			(layer "F.Fab")
		)
		(fp_line
			(start 0.120396 0.2794)
			(end -0.12065 0.2794)
			(stroke
				(width 0.1)
				(type default)
			)
			(layer "F.Fab")
		)
		(fp_line
			(start -0.12065 0.3048)
			(end -0.67945 0.3048)
			(stroke
				(width 0.1)
				(type default)
			)
			(layer "F.Fab")
		)
		(fp_line
			(start -0.12065 0.2794)
			(end -0.12065 0.3048)
			(stroke
				(width 0.1)
				(type default)
			)
			(layer "F.Fab")
		)
		(fp_line
			(start -0.12065 -0.2794)
			(end 0.12065 -0.2794)
			(stroke
				(width 0.1)
				(type default)
			)
			(layer "F.Fab")
		)
		(fp_line
			(start -0.12065 -0.305054)
			(end -0.12065 -0.2794)
			(stroke
				(width 0.1)
				(type default)
			)
			(layer "F.Fab")
		)
		(fp_line
			(start -0.67945 0.3048)
			(end -0.67945 -0.305054)
			(stroke
				(width 0.1)
				(type default)
			)
			(layer "F.Fab")
		)
		(fp_line
			(start -0.67945 -0.305054)
			(end -0.12065 -0.305054)
			(stroke
				(width 0.1)
				(type default)
			)
			(layer "F.Fab")
		)
		(pad "1" smd circle
			(at -0.40005 0 180)
			(size 0 0)
			(layers "F.Cu" "F.Mask" "F.Paste")
			(net "P3V3_AUX")
		)
		(pad "2" smd circle
			(at 0.40005 0 180)
			(size 0 0)
			(layers "F.Cu" "F.Mask" "F.Paste")
			(net "GND")
		)
	)
	(footprint ""
		(layer "F.Cu")
		(at 450.309234 -100.58908 180)
		(property "Reference" "PL1"
			(at -0.315976 -3.380232 0)
			(unlocked yes)
			(layer "F.SilkS")
			(effects
				(font
					(size 0.7874 0.5842)
					(thickness 0.1524)
				)
				(justify left)
			)
		)
		(property "Value" ""
			(at 0 0 180)
			(layer "F.Fab")
			(effects
				(font
					(size 1.27 1.27)
				)
			)
		)
		(duplicate_pad_numbers_are_jumpers no)
		(fp_line
			(start 2.249932 2.249932)
			(end -2.249932 2.249932)
			(stroke
				(width 0.1524)
				(type default)
			)
			(layer "F.SilkS")
		)
		(fp_line
			(start 2.249932 1.3843)
			(end 2.249932 2.249932)
			(stroke
				(width 0.1524)
				(type default)
			)
			(layer "F.SilkS")
		)
		(fp_line
			(start 2.249932 -2.249932)
			(end 2.249932 -1.3843)
			(stroke
				(width 0.1524)
				(type default)
			)
			(layer "F.SilkS")
		)
		(fp_line
			(start -2.249932 2.249932)
			(end -2.249932 1.3843)
			(stroke
				(width 0.1524)
				(type default)
			)
			(layer "F.SilkS")
		)
		(fp_line
			(start -2.249932 -1.3843)
			(end -2.249932 -2.249932)
			(stroke
				(width 0.1524)
				(type default)
			)
			(layer "F.SilkS")
		)
		(fp_line
			(start -2.249932 -2.249932)
			(end 2.249932 -2.249932)
			(stroke
				(width 0.1524)
				(type default)
			)
			(layer "F.SilkS")
		)
		(fp_line
			(start 2.249932 2.249932)
			(end -2.249932 2.249932)
			(stroke
				(width 0.1)
				(type default)
			)
			(layer "F.Fab")
		)
		(fp_line
			(start 2.249932 -2.249932)
			(end 2.249932 2.249932)
			(stroke
				(width 0.1)
				(type default)
			)
			(layer "F.Fab")
		)
		(fp_line
			(start -2.249932 2.249932)
			(end -2.249932 -2.249932)
			(stroke
				(width 0.1)
				(type default)
			)
			(layer "F.Fab")
		)
		(fp_line
			(start -2.249932 -2.249932)
			(end 2.249932 -2.249932)
			(stroke
				(width 0.1)
				(type default)
			)
			(layer "F.Fab")
		)
		(pad "1" smd rect
			(at -1.82499 0 180)
			(size 1.0668 2.5146)
			(layers "F.Cu" "F.Mask" "F.Paste")
			(net "P12V_HPDB")
		)
		(pad "2" smd rect
			(at 1.82499 0 180)
			(size 1.0668 2.5146)
			(layers "F.Cu" "F.Mask" "F.Paste")
			(net "SW_P3V3_HPDB_FLT")
		)
	)
	(footprint ""
		(layer "F.Cu")
		(at 450.342 -37.211 -90)
		(property "Reference" "R12"
			(at 0 0 270)
			(layer "F.SilkS")
			(hide yes)
			(effects
				(font
					(size 1.27 1.27)
				)
			)
		)
		(property "Value" ""
			(at 0 0 270)
			(layer "F.Fab")
			(effects
				(font
					(size 1.27 1.27)
				)
			)
		)
		(duplicate_pad_numbers_are_jumpers no)
		(fp_line
			(start -0.7874 0.4064)
			(end -0.7874 -0.4064)
			(stroke
				(width 0.1524)
				(type default)
			)
			(layer "F.SilkS")
		)
		(fp_line
			(start 0.7874 0.4064)
			(end -0.7874 0.4064)
			(stroke
				(width 0.1524)
				(type default)
			)
			(layer "F.SilkS")
		)
		(fp_line
			(start -0.7874 -0.4064)
			(end 0.7874 -0.4064)
			(stroke
				(width 0.1524)
				(type default)
			)
			(layer "F.SilkS")
		)
		(fp_line
			(start 0.7874 -0.4064)
			(end 0.7874 0.4064)
			(stroke
				(width 0.1524)
				(type default)
			)
			(layer "F.SilkS")
		)
		(fp_line
			(start -0.67945 0.3048)
			(end -0.67945 -0.305054)
			(stroke
				(width 0.1)
				(type default)
			)
			(layer "F.Fab")
		)
		(fp_line
			(start -0.12065 0.3048)
			(end -0.67945 0.3048)
			(stroke
				(width 0.1)
				(type default)
			)
			(layer "F.Fab")
		)
		(fp_line
			(start 0.120396 0.3048)
			(end 0.120396 0.2794)
			(stroke
				(width 0.1)
				(type default)
			)
			(layer "F.Fab")
		)
		(fp_line
			(start 0.67945 0.3048)
			(end 0.120396 0.3048)
			(stroke
				(width 0.1)
				(type default)
			)
			(layer "F.Fab")
		)
		(fp_line
			(start -0.12065 0.2794)
			(end -0.12065 0.3048)
			(stroke
				(width 0.1)
				(type default)
			)
			(layer "F.Fab")
		)
		(fp_line
			(start 0.120396 0.2794)
			(end -0.12065 0.2794)
			(stroke
				(width 0.1)
				(type default)
			)
			(layer "F.Fab")
		)
		(fp_line
			(start -0.12065 -0.2794)
			(end 0.12065 -0.2794)
			(stroke
				(width 0.1)
				(type default)
			)
			(layer "F.Fab")
		)
		(fp_line
			(start 0.12065 -0.2794)
			(end 0.12065 -0.3048)
			(stroke
				(width 0.1)
				(type default)
			)
			(layer "F.Fab")
		)
		(fp_line
			(start 0.12065 -0.3048)
			(end 0.67945 -0.3048)
			(stroke
				(width 0.1)
				(type default)
			)
			(layer "F.Fab")
		)
		(fp_line
			(start 0.67945 -0.3048)
			(end 0.67945 0.3048)
			(stroke
				(width 0.1)
				(type default)
			)
			(layer "F.Fab")
		)
		(fp_line
			(start -0.67945 -0.305054)
			(end -0.12065 -0.305054)
			(stroke
				(width 0.1)
				(type default)
			)
			(layer "F.Fab")
		)
		(fp_line
			(start -0.12065 -0.305054)
			(end -0.12065 -0.2794)
			(stroke
				(width 0.1)
				(type default)
			)
			(layer "F.Fab")
		)
		(pad "1" smd circle
			(at -0.40005 0 270)
			(size 0 0)
			(layers "F.Cu" "F.Mask" "F.Paste")
			(net "SMB_P52V_PDB_SDA_R")
		)
		(pad "2" smd circle
			(at 0.40005 0 270)
			(size 0 0)
			(layers "F.Cu" "F.Mask" "F.Paste")
			(net "SMB_P52V_PDB_SDA")
		)
	)
	(footprint ""
		(layer "F.Cu")
		(at 377.000008 -156.830014 180)
		(property "Reference" "J2"
			(at 7.684008 -7.631684 0)
			(unlocked yes)
			(layer "F.SilkS")
			(effects
				(font
					(size 0.7874 0.5842)
					(thickness 0.1524)
				)
				(justify left)
			)
		)
		(property "Value" ""
			(at 0 0 180)
			(layer "F.Fab")
			(effects
				(font
					(size 1.27 1.27)
				)
			)
		)
		(duplicate_pad_numbers_are_jumpers no)
		(fp_line
			(start 18.925032 28.450032)
			(end -4.92506 28.450032)
			(stroke
				(width 0.1524)
				(type default)
			)
			(layer "F.SilkS")
		)
		(fp_line
			(start 18.925032 -6.849872)
			(end 18.925032 28.450032)
			(stroke
				(width 0.1524)
				(type default)
			)
			(layer "F.SilkS")
		)
		(fp_line
			(start 15.925038 25.450038)
			(end 15.925038 -3.849878)
			(stroke
				(width 0.1524)
				(type default)
			)
			(layer "F.SilkS")
		)
		(fp_line
			(start 15.925038 14.99997)
			(end -1.925066 14.99997)
			(stroke
				(width 0.1524)
				(type default)
			)
			(layer "F.SilkS")
		)
		(fp_line
			(start 15.925038 -3.849878)
			(end -1.925066 -3.849878)
			(stroke
				(width 0.1524)
				(type default)
			)
			(layer "F.SilkS")
		)
		(fp_line
			(start -1.925066 25.450038)
			(end 15.925038 25.450038)
			(stroke
				(width 0.1524)
				(type default)
			)
			(layer "F.SilkS")
		)
		(fp_line
			(start -1.925066 -3.849878)
			(end -1.925066 25.450038)
			(stroke
				(width 0.1524)
				(type default)
			)
			(layer "F.SilkS")
		)
		(fp_line
			(start -4.92506 28.450032)
			(end -4.92506 -6.849872)
			(stroke
				(width 0.1524)
				(type default)
			)
			(layer "F.SilkS")
		)
		(fp_line
			(start -4.92506 -6.849872)
			(end 18.925032 -6.849872)
			(stroke
				(width 0.1524)
				(type default)
			)
			(layer "F.SilkS")
		)
		(fp_poly
			(pts
				(xy 0.840994 -2.447036) (xy -0.683006 -2.447036) (xy 0.078994 -0.923036)
			)
			(stroke
				(width 0)
				(type default)
			)
			(fill yes)
			(layer "F.SilkS")
		)
		(fp_line
			(start 18.925032 28.450032)
			(end -4.92506 28.450032)
			(stroke
				(width 0.1524)
				(type default)
			)
			(layer "B.SilkS")
		)
		(fp_line
			(start 18.925032 -6.849872)
			(end 18.925032 28.450032)
			(stroke
				(width 0.1524)
				(type default)
			)
			(layer "B.SilkS")
		)
		(fp_line
			(start -4.92506 28.450032)
			(end -4.92506 -6.849872)
			(stroke
				(width 0.1524)
				(type default)
			)
			(layer "B.SilkS")
		)
		(fp_line
			(start -4.92506 -6.849872)
			(end 18.925032 -6.849872)
			(stroke
				(width 0.1524)
				(type default)
			)
			(layer "B.SilkS")
		)
		(fp_line
			(start 18.925032 28.450032)
			(end -4.92506 28.450032)
			(stroke
				(width 0.1)
				(type default)
			)
			(layer "B.Fab")
		)
		(fp_line
			(start 18.925032 -6.849872)
			(end 18.925032 28.450032)
			(stroke
				(width 0.1)
				(type default)
			)
			(layer "B.Fab")
		)
		(fp_line
			(start -4.92506 28.450032)
			(end -4.92506 -6.849872)
			(stroke
				(width 0.1)
				(type default)
			)
			(layer "B.Fab")
		)
		(fp_line
			(start -4.92506 -6.849872)
			(end 18.925032 -6.849872)
			(stroke
				(width 0.1)
				(type default)
			)
			(layer "B.Fab")
		)
		(fp_line
			(start 15.925038 25.450038)
			(end 15.925038 -3.849878)
			(stroke
				(width 0.1)
				(type default)
			)
			(layer "F.Fab")
		)
		(fp_line
			(start 15.925038 -3.849878)
			(end -1.925066 -3.849878)
			(stroke
				(width 0.1)
				(type default)
			)
			(layer "F.Fab")
		)
		(fp_line
			(start -1.925066 25.450038)
			(end 15.925038 25.450038)
			(stroke
				(width 0.1)
				(type default)
			)
			(layer "F.Fab")
		)
		(fp_line
			(start -1.925066 -3.849878)
			(end -1.925066 25.450038)
			(stroke
				(width 0.1)
				(type default)
			)
			(layer "F.Fab")
		)
		(fp_poly
			(pts
				(xy -3.795014 -0.762) (xy -3.795014 0.762) (xy -2.271014 0)
			)
			(stroke
				(width 0)
				(type default)
			)
			(fill yes)
			(layer "F.Fab")
		)
		(fp_text user "D4"
			(at 15.625572 12.001246 180)
			(unlocked yes)
			(layer "F.SilkS")
			(effects
				(font
					(size 0.7874 0.5842)
					(thickness 0.1524)
				)
			)
		)
		(fp_text user "D5"
			(at 15.625572 10.00125 180)
			(unlocked yes)
			(layer "F.SilkS")
			(effects
				(font
					(size 0.7874 0.5842)
					(thickness 0.1524)
				)
			)
		)
		(fp_text user "D6"
			(at 15.625572 8.001254 180)
			(unlocked yes)
			(layer "F.SilkS")
			(effects
				(font
					(size 0.7874 0.5842)
					(thickness 0.1524)
				)
			)
		)
		(fp_text user "C4"
			(at 15.625572 4.001262 180)
			(unlocked yes)
			(layer "F.SilkS")
			(effects
				(font
					(size 0.7874 0.5842)
					(thickness 0.1524)
				)
			)
		)
		(fp_text user "C5"
			(at 15.625572 2.001266 180)
			(unlocked yes)
			(layer "F.SilkS")
			(effects
				(font
					(size 0.7874 0.5842)
					(thickness 0.1524)
				)
			)
		)
		(fp_text user "C6"
			(at 15.625572 0.00127 180)
			(unlocked yes)
			(layer "F.SilkS")
			(effects
				(font
					(size 0.7874 0.5842)
					(thickness 0.1524)
				)
			)
		)
		(fp_text user "PRESS-FIT"
			(at 12.383008 -5.636514 0)
			(unlocked yes)
			(layer "F.SilkS")
			(effects
				(font
					(size 1.27 0.9652)
					(thickness 0.1524)
				)
				(justify left)
			)
		)
		(fp_text user "F3"
			(at -2.8956 11.950446 180)
			(unlocked yes)
			(layer "F.SilkS")
			(effects
				(font
					(size 0.7874 0.5842)
					(thickness 0.1524)
				)
			)
		)
		(fp_text user "F2"
			(at -2.8956 9.95045 180)
			(unlocked yes)
			(layer "F.SilkS")
			(effects
				(font
					(size 0.7874 0.5842)
					(thickness 0.1524)
				)
			)
		)
		(fp_text user "F1"
			(at -2.8956 7.950454 180)
			(unlocked yes)
			(layer "F.SilkS")
			(effects
				(font
					(size 0.7874 0.5842)
					(thickness 0.1524)
				)
			)
		)
		(fp_text user "A3"
			(at -2.8956 3.950462 180)
			(unlocked yes)
			(layer "F.SilkS")
			(effects
				(font
					(size 0.7874 0.5842)
					(thickness 0.1524)
				)
			)
		)
		(fp_text user "A2"
			(at -2.8956 1.950466 180)
			(unlocked yes)
			(layer "F.SilkS")
			(effects
				(font
					(size 0.7874 0.5842)
					(thickness 0.1524)
				)
			)
		)
		(fp_text user "D4"
			(at 15.588996 11.947906 0)
			(unlocked yes)
			(layer "B.SilkS")
			(effects
				(font
					(size 0.7874 0.5842)
					(thickness 0.1524)
				)
				(justify mirror)
			)
		)
		(fp_text user "D5"
			(at 15.588996 9.94791 0)
			(unlocked yes)
			(layer "B.SilkS")
			(effects
				(font
					(size 0.7874 0.5842)
					(thickness 0.1524)
				)
				(justify mirror)
			)
		)
		(fp_text user "D6"
			(at 15.588996 7.947914 0)
			(unlocked yes)
			(layer "B.SilkS")
			(effects
				(font
					(size 0.7874 0.5842)
					(thickness 0.1524)
				)
				(justify mirror)
			)
		)
		(fp_text user "C4"
			(at 15.588996 3.947922 0)
			(unlocked yes)
			(layer "B.SilkS")
			(effects
				(font
					(size 0.7874 0.5842)
					(thickness 0.1524)
				)
				(justify mirror)
			)
		)
		(fp_text user "C5"
			(at 15.588996 1.947926 0)
			(unlocked yes)
			(layer "B.SilkS")
			(effects
				(font
					(size 0.7874 0.5842)
					(thickness 0.1524)
				)
				(justify mirror)
			)
		)
		(fp_text user "C6"
			(at 15.588996 -0.05207 0)
			(unlocked yes)
			(layer "B.SilkS")
			(effects
				(font
					(size 0.7874 0.5842)
					(thickness 0.1524)
				)
				(justify mirror)
			)
		)
		(fp_text user "PRESS-FIT"
			(at 1.689608 -3.318764 0)
			(unlocked yes)
			(layer "B.SilkS")
			(effects
				(font
					(size 1.905 1.4224)
					(thickness 0.1524)
				)
				(justify left mirror)
			)
		)
		(fp_text user "F3"
			(at -2.219452 11.973306 0)
			(unlocked yes)
			(layer "B.SilkS")
			(effects
				(font
					(size 0.7874 0.5842)
					(thickness 0.1524)
				)
				(justify mirror)
			)
		)
		(fp_text user "F2"
			(at -2.219452 9.97331 0)
			(unlocked yes)
			(layer "B.SilkS")
			(effects
				(font
					(size 0.7874 0.5842)
					(thickness 0.1524)
				)
				(justify mirror)
			)
		)
		(fp_text user "F1"
			(at -2.219452 7.973314 0)
			(unlocked yes)
			(layer "B.SilkS")
			(effects
				(font
					(size 0.7874 0.5842)
					(thickness 0.1524)
				)
				(justify mirror)
			)
		)
		(fp_text user "A3"
			(at -2.219452 3.973322 0)
			(unlocked yes)
			(layer "B.SilkS")
			(effects
				(font
					(size 0.7874 0.5842)
					(thickness 0.1524)
				)
				(justify mirror)
			)
		)
		(fp_text user "A2"
			(at -2.219452 1.973326 0)
			(unlocked yes)
			(layer "B.SilkS")
			(effects
				(font
					(size 0.7874 0.5842)
					(thickness 0.1524)
				)
				(justify mirror)
			)
		)
		(fp_text user "A1"
			(at -2.244852 -0.007874 0)
			(unlocked yes)
			(layer "B.SilkS")
			(effects
				(font
					(size 0.7874 0.5842)
					(thickness 0.1524)
				)
				(justify mirror)
			)
		)
		(fp_text user "D4"
			(at 15.461996 12.001246 180)
			(unlocked yes)
			(layer "B.Fab")
			(effects
				(font
					(size 0.7874 0.5842)
					(thickness 0.1524)
				)
				(justify mirror)
			)
		)
		(fp_text user "D5"
			(at 15.461996 10.00125 180)
			(unlocked yes)
			(layer "B.Fab")
			(effects
				(font
					(size 0.7874 0.5842)
					(thickness 0.1524)
				)
				(justify mirror)
			)
		)
		(fp_text user "D6"
			(at 15.461996 8.001254 180)
			(unlocked yes)
			(layer "B.Fab")
			(effects
				(font
					(size 0.7874 0.5842)
					(thickness 0.1524)
				)
				(justify mirror)
			)
		)
		(fp_text user "C4"
			(at 15.461996 4.001262 180)
			(unlocked yes)
			(layer "B.Fab")
			(effects
				(font
					(size 0.7874 0.5842)
					(thickness 0.1524)
				)
				(justify mirror)
			)
		)
		(fp_text user "C5"
			(at 15.461996 2.001266 180)
			(unlocked yes)
			(layer "B.Fab")
			(effects
				(font
					(size 0.7874 0.5842)
					(thickness 0.1524)
				)
				(justify mirror)
			)
		)
		(fp_text user "C6"
			(at 15.461996 0.00127 180)
			(unlocked yes)
			(layer "B.Fab")
			(effects
				(font
					(size 0.7874 0.5842)
					(thickness 0.1524)
				)
				(justify mirror)
			)
		)
		(fp_text user "PRESS-FIT"
			(at 15.452598 -5.22097 180)
			(unlocked yes)
			(layer "B.Fab")
			(effects
				(font
					(size 1.905 1.4224)
					(thickness 0.1524)
				)
				(justify left mirror)
			)
		)
		(fp_text user "F3"
			(at -1.457452 12.026646 180)
			(unlocked yes)
			(layer "B.Fab")
			(effects
				(font
					(size 0.7874 0.5842)
					(thickness 0.1524)
				)
				(justify mirror)
			)
		)
		(fp_text user "F2"
			(at -1.457452 10.02665 180)
			(unlocked yes)
			(layer "B.Fab")
			(effects
				(font
					(size 0.7874 0.5842)
					(thickness 0.1524)
				)
				(justify mirror)
			)
		)
		(fp_text user "F1"
			(at -1.457452 8.026654 180)
			(unlocked yes)
			(layer "B.Fab")
			(effects
				(font
					(size 0.7874 0.5842)
					(thickness 0.1524)
				)
				(justify mirror)
			)
		)
		(fp_text user "A3"
			(at -1.457452 4.026662 180)
			(unlocked yes)
			(layer "B.Fab")
			(effects
				(font
					(size 0.7874 0.5842)
					(thickness 0.1524)
				)
				(justify mirror)
			)
		)
		(fp_text user "A2"
			(at -1.457452 2.026666 180)
			(unlocked yes)
			(layer "B.Fab")
			(effects
				(font
					(size 0.7874 0.5842)
					(thickness 0.1524)
				)
				(justify mirror)
			)
		)
		(fp_text user "A1"
			(at -1.482852 0.045466 180)
			(unlocked yes)
			(layer "B.Fab")
			(effects
				(font
					(size 0.7874 0.5842)
					(thickness 0.1524)
				)
				(justify mirror)
			)
		)
		(fp_text user "D4"
			(at 16.895572 12.001246 180)
			(unlocked yes)
			(layer "F.Fab")
			(effects
				(font
					(size 0.7874 0.5842)
					(thickness 0.1524)
				)
			)
		)
		(fp_text user "D5"
			(at 16.895572 10.00125 180)
			(unlocked yes)
			(layer "F.Fab")
			(effects
				(font
					(size 0.7874 0.5842)
					(thickness 0.1524)
				)
			)
		)
		(fp_text user "D6"
			(at 16.895572 8.001254 180)
			(unlocked yes)
			(layer "F.Fab")
			(effects
				(font
					(size 0.7874 0.5842)
					(thickness 0.1524)
				)
			)
		)
		(fp_text user "C4"
			(at 16.895572 4.001262 180)
			(unlocked yes)
			(layer "F.Fab")
			(effects
				(font
					(size 0.7874 0.5842)
					(thickness 0.1524)
				)
			)
		)
		(fp_text user "C5"
			(at 16.895572 2.001266 180)
			(unlocked yes)
			(layer "F.Fab")
			(effects
				(font
					(size 0.7874 0.5842)
					(thickness 0.1524)
				)
			)
		)
		(fp_text user "C6"
			(at 16.895572 0.00127 180)
			(unlocked yes)
			(layer "F.Fab")
			(effects
				(font
					(size 0.7874 0.5842)
					(thickness 0.1524)
				)
			)
		)
		(fp_text user "PRESS-FIT"
			(at -1.229614 -5.22097 180)
			(unlocked yes)
			(layer "F.Fab")
			(effects
				(font
					(size 1.905 1.4224)
					(thickness 0.1524)
				)
				(justify left)
			)
		)
		(fp_text user "F3"
			(at -2.8956 11.950446 180)
			(unlocked yes)
			(layer "F.Fab")
			(effects
				(font
					(size 0.7874 0.5842)
					(thickness 0.1524)
				)
			)
		)
		(fp_text user "F2"
			(at -2.8956 9.95045 180)
			(unlocked yes)
			(layer "F.Fab")
			(effects
				(font
					(size 0.7874 0.5842)
					(thickness 0.1524)
				)
			)
		)
		(fp_text user "F1"
			(at -2.8956 7.950454 180)
			(unlocked yes)
			(layer "F.Fab")
			(effects
				(font
					(size 0.7874 0.5842)
					(thickness 0.1524)
				)
			)
		)
		(fp_text user "A3"
			(at -2.8956 3.950462 180)
			(unlocked yes)
			(layer "F.Fab")
			(effects
				(font
					(size 0.7874 0.5842)
					(thickness 0.1524)
				)
			)
		)
		(fp_text user "A2"
			(at -2.8956 1.950466 180)
			(unlocked yes)
			(layer "F.Fab")
			(effects
				(font
					(size 0.7874 0.5842)
					(thickness 0.1524)
				)
			)
		)
		(pad "" np_thru_hole circle
			(at 3.999992 2.800096 180)
			(size 2.159 2.159)
			(drill 2.159)
			(layers "*.Cu" "*.Mask")
			(clearance 0.381)
			(thermal_gap 0.381)
		)
		(pad "" np_thru_hole circle
			(at 9.99998 10.80008 180)
			(size 2.159 2.159)
			(drill 2.159)
			(layers "*.Cu" "*.Mask")
			(clearance 0.381)
			(thermal_gap 0.381)
		)
		(pad "A1" thru_hole rect
			(at 0 0 180)
			(size 1.156208 1.156208)
			(drill 0.749808)
			(layers "*.Cu" "*.Mask")
			(remove_unused_layers no)
			(net "P52V_HS1")
			(clearance 0.0508)
			(thermal_gap 0.0508)
			(padstack
				(mode front_inner_back)
				(layer "Inner"
					(shape circle)
					(size 1.156208 1.156208)
					(clearance 0.0508)
				)
				(layer "B.Cu"
					(shape rect)
					(size 1.156208 1.156208)
					(clearance 0.0508)
				)
			)
		)
		(pad "A2" thru_hole circle
			(at 0 1.999996 180)
			(size 1.156208 1.156208)
			(drill 0.749808)
			(layers "*.Cu" "*.Mask")
			(remove_unused_layers no)
			(net "P52V_HS1")
			(clearance 0.0508)
			(thermal_gap 0.0508)
		)
		(pad "A3" thru_hole circle
			(at 0 3.999992 180)
			(size 1.156208 1.156208)
			(drill 0.749808)
			(layers "*.Cu" "*.Mask")
			(remove_unused_layers no)
			(net "P52V_HS1")
			(clearance 0.0508)
			(thermal_gap 0.0508)
		)
		(pad "A4" thru_hole circle
			(at 1.999996 3.999992 180)
			(size 1.156208 1.156208)
			(drill 0.749808)
			(layers "*.Cu" "*.Mask")
			(remove_unused_layers no)
			(net "P52V_HS1")
			(clearance 0.0508)
			(thermal_gap 0.0508)
		)
		(pad "A5" thru_hole circle
			(at 1.999996 1.999996 180)
			(size 1.156208 1.156208)
			(drill 0.749808)
			(layers "*.Cu" "*.Mask")
			(remove_unused_layers no)
			(net "P52V_HS1")
			(clearance 0.0508)
			(thermal_gap 0.0508)
		)
		(pad "A6" thru_hole circle
			(at 1.999996 0 180)
			(size 1.156208 1.156208)
			(drill 0.749808)
			(layers "*.Cu" "*.Mask")
			(remove_unused_layers no)
			(net "P52V_HS1")
			(clearance 0.0508)
			(thermal_gap 0.0508)
		)
		(pad "B1" thru_hole circle
			(at 5.999988 0 180)
			(size 1.156208 1.156208)
			(drill 0.749808)
			(layers "*.Cu" "*.Mask")
			(remove_unused_layers no)
			(net "P52V_HS1")
			(clearance 0.0508)
			(thermal_gap 0.0508)
		)
		(pad "B2" thru_hole circle
			(at 5.999988 1.999996 180)
			(size 1.156208 1.156208)
			(drill 0.749808)
			(layers "*.Cu" "*.Mask")
			(remove_unused_layers no)
			(net "P52V_HS1")
			(clearance 0.0508)
			(thermal_gap 0.0508)
		)
		(pad "B3" thru_hole circle
			(at 5.999988 3.999992 180)
			(size 1.156208 1.156208)
			(drill 0.749808)
			(layers "*.Cu" "*.Mask")
			(remove_unused_layers no)
			(net "P52V_HS1")
			(clearance 0.0508)
			(thermal_gap 0.0508)
		)
		(pad "B4" thru_hole circle
			(at 7.999984 3.999992 180)
			(size 1.156208 1.156208)
			(drill 0.749808)
			(layers "*.Cu" "*.Mask")
			(remove_unused_layers no)
			(net "P52V_HS1")
			(clearance 0.0508)
			(thermal_gap 0.0508)
		)
		(pad "B5" thru_hole circle
			(at 7.999984 1.999996 180)
			(size 1.156208 1.156208)
			(drill 0.749808)
			(layers "*.Cu" "*.Mask")
			(remove_unused_layers no)
			(net "P52V_HS1")
			(clearance 0.0508)
			(thermal_gap 0.0508)
		)
		(pad "B6" thru_hole circle
			(at 7.999984 0 180)
			(size 1.156208 1.156208)
			(drill 0.749808)
			(layers "*.Cu" "*.Mask")
			(remove_unused_layers no)
			(net "P52V_HS1")
			(clearance 0.0508)
			(thermal_gap 0.0508)
		)
		(pad "C1" thru_hole circle
			(at 11.999976 0 180)
			(size 1.156208 1.156208)
			(drill 0.749808)
			(layers "*.Cu" "*.Mask")
			(remove_unused_layers no)
			(net "P52V_HS1")
			(clearance 0.0508)
			(thermal_gap 0.0508)
		)
		(pad "C2" thru_hole circle
			(at 11.999976 1.999996 180)
			(size 1.156208 1.156208)
			(drill 0.749808)
			(layers "*.Cu" "*.Mask")
			(remove_unused_layers no)
			(net "P52V_HS1")
			(clearance 0.0508)
			(thermal_gap 0.0508)
		)
		(pad "C3" thru_hole circle
			(at 11.999976 3.999992 180)
			(size 1.156208 1.156208)
			(drill 0.749808)
			(layers "*.Cu" "*.Mask")
			(remove_unused_layers no)
			(net "P52V_HS1")
			(clearance 0.0508)
			(thermal_gap 0.0508)
		)
		(pad "C4" thru_hole circle
			(at 13.999972 3.999992 180)
			(size 1.156208 1.156208)
			(drill 0.749808)
			(layers "*.Cu" "*.Mask")
			(remove_unused_layers no)
			(net "P52V_HS1")
			(clearance 0.0508)
			(thermal_gap 0.0508)
		)
		(pad "C5" thru_hole circle
			(at 13.999972 1.999996 180)
			(size 1.156208 1.156208)
			(drill 0.749808)
			(layers "*.Cu" "*.Mask")
			(remove_unused_layers no)
			(net "P52V_HS1")
			(clearance 0.0508)
			(thermal_gap 0.0508)
		)
		(pad "C6" thru_hole circle
			(at 13.999972 0 180)
			(size 1.156208 1.156208)
			(drill 0.749808)
			(layers "*.Cu" "*.Mask")
			(remove_unused_layers no)
			(net "P52V_HS1")
			(clearance 0.0508)
			(thermal_gap 0.0508)
		)
		(pad "D1" thru_hole circle
			(at 11.999976 7.999984 180)
			(size 1.156208 1.156208)
			(drill 0.749808)
			(layers "*.Cu" "*.Mask")
			(remove_unused_layers no)
			(net "GND")
			(clearance 0.0508)
			(thermal_gap 0.0508)
		)
		(pad "D2" thru_hole circle
			(at 11.999976 9.99998 180)
			(size 1.156208 1.156208)
			(drill 0.749808)
			(layers "*.Cu" "*.Mask")
			(remove_unused_layers no)
			(net "GND")
			(clearance 0.0508)
			(thermal_gap 0.0508)
		)
		(pad "D3" thru_hole circle
			(at 11.999976 11.999976 180)
			(size 1.156208 1.156208)
			(drill 0.749808)
			(layers "*.Cu" "*.Mask")
			(remove_unused_layers no)
			(net "GND")
			(clearance 0.0508)
			(thermal_gap 0.0508)
		)
		(pad "D4" thru_hole circle
			(at 13.999972 11.999976 180)
			(size 1.156208 1.156208)
			(drill 0.749808)
			(layers "*.Cu" "*.Mask")
			(remove_unused_layers no)
			(net "GND")
			(clearance 0.0508)
			(thermal_gap 0.0508)
		)
		(pad "D5" thru_hole circle
			(at 13.999972 9.99998 180)
			(size 1.156208 1.156208)
			(drill 0.749808)
			(layers "*.Cu" "*.Mask")
			(remove_unused_layers no)
			(net "GND")
			(clearance 0.0508)
			(thermal_gap 0.0508)
		)
		(pad "D6" thru_hole circle
			(at 13.999972 7.999984 180)
			(size 1.156208 1.156208)
			(drill 0.749808)
			(layers "*.Cu" "*.Mask")
			(remove_unused_layers no)
			(net "GND")
			(clearance 0.0508)
			(thermal_gap 0.0508)
		)
		(pad "E1" thru_hole circle
			(at 5.999988 7.999984 180)
			(size 1.156208 1.156208)
			(drill 0.749808)
			(layers "*.Cu" "*.Mask")
			(remove_unused_layers no)
			(net "GND")
			(clearance 0.0508)
			(thermal_gap 0.0508)
		)
		(pad "E2" thru_hole circle
			(at 5.999988 9.99998 180)
			(size 1.156208 1.156208)
			(drill 0.749808)
			(layers "*.Cu" "*.Mask")
			(remove_unused_layers no)
			(net "GND")
			(clearance 0.0508)
			(thermal_gap 0.0508)
		)
		(pad "E3" thru_hole circle
			(at 5.999988 11.999976 180)
			(size 1.156208 1.156208)
			(drill 0.749808)
			(layers "*.Cu" "*.Mask")
			(remove_unused_layers no)
			(net "GND")
			(clearance 0.0508)
			(thermal_gap 0.0508)
		)
		(pad "E4" thru_hole circle
			(at 7.999984 11.999976 180)
			(size 1.156208 1.156208)
			(drill 0.749808)
			(layers "*.Cu" "*.Mask")
			(remove_unused_layers no)
			(net "GND")
			(clearance 0.0508)
			(thermal_gap 0.0508)
		)
		(pad "E5" thru_hole circle
			(at 7.999984 9.99998 180)
			(size 1.156208 1.156208)
			(drill 0.749808)
			(layers "*.Cu" "*.Mask")
			(remove_unused_layers no)
			(net "GND")
			(clearance 0.0508)
			(thermal_gap 0.0508)
		)
		(pad "E6" thru_hole circle
			(at 7.999984 7.999984 180)
			(size 1.156208 1.156208)
			(drill 0.749808)
			(layers "*.Cu" "*.Mask")
			(remove_unused_layers no)
			(net "GND")
			(clearance 0.0508)
			(thermal_gap 0.0508)
		)
		(pad "F1" thru_hole circle
			(at 0 7.999984 180)
			(size 1.156208 1.156208)
			(drill 0.749808)
			(layers "*.Cu" "*.Mask")
			(remove_unused_layers no)
			(net "GND")
			(clearance 0.0508)
			(thermal_gap 0.0508)
		)
		(pad "F2" thru_hole circle
			(at 0 9.99998 180)
			(size 1.156208 1.156208)
			(drill 0.749808)
			(layers "*.Cu" "*.Mask")
			(remove_unused_layers no)
			(net "GND")
			(clearance 0.0508)
			(thermal_gap 0.0508)
		)
		(pad "F3" thru_hole circle
			(at 0 11.999976 180)
			(size 1.156208 1.156208)
			(drill 0.749808)
			(layers "*.Cu" "*.Mask")
			(remove_unused_layers no)
			(net "GND")
			(clearance 0.0508)
			(thermal_gap 0.0508)
		)
		(pad "F4" thru_hole circle
			(at 1.999996 11.999976 180)
			(size 1.156208 1.156208)
			(drill 0.749808)
			(layers "*.Cu" "*.Mask")
			(remove_unused_layers no)
			(net "GND")
			(clearance 0.0508)
			(thermal_gap 0.0508)
		)
		(pad "F5" thru_hole circle
			(at 1.999996 9.99998 180)
			(size 1.156208 1.156208)
			(drill 0.749808)
			(layers "*.Cu" "*.Mask")
			(remove_unused_layers no)
			(net "GND")
			(clearance 0.0508)
			(thermal_gap 0.0508)
		)
		(pad "F6" thru_hole circle
			(at 1.999996 7.999984 180)
			(size 1.156208 1.156208)
			(drill 0.749808)
			(layers "*.Cu" "*.Mask")
			(remove_unused_layers no)
			(net "GND")
			(clearance 0.0508)
			(thermal_gap 0.0508)
		)
		(zone
			(layers "F.Cu" "B.Cu" "In1.Cu" "In2.Cu" "In3.Cu" "In4.Cu" "In5.Cu" "In6.Cu"
				"In7.Cu" "In8.Cu"
			)
			(hatch none 0.5)
			(connect_pads
				(clearance 0)
			)
			(min_thickness 0.25)
			(keepout
				(tracks not_allowed)
				(vias allowed)
				(pads allowed)
				(copperpour not_allowed)
				(footprints allowed)
			)
			(placement
				(enabled no)
				(sheetname "")
			)
			(fill
				(thermal_gap 0.5)
				(thermal_bridge_width 0.5)
				(island_removal_mode 0)
			)
			(polygon
				(pts
					(arc
						(start 368.485928 -167.630094)
						(mid 365.514128 -167.630094)
						(end 368.485928 -167.630094)
					)
				)
			)
		)
		(zone
			(layers "F.Cu" "B.Cu" "In1.Cu" "In2.Cu" "In3.Cu" "In4.Cu" "In5.Cu" "In6.Cu"
				"In7.Cu" "In8.Cu"
			)
			(hatch none 0.5)
			(connect_pads
				(clearance 0)
			)
			(min_thickness 0.25)
			(keepout
				(tracks not_allowed)
				(vias allowed)
				(pads allowed)
				(copperpour not_allowed)
				(footprints allowed)
			)
			(placement
				(enabled no)
				(sheetname "")
			)
			(fill
				(thermal_gap 0.5)
				(thermal_bridge_width 0.5)
				(island_removal_mode 0)
			)
			(polygon
				(pts
					(arc
						(start 374.485916 -159.63011)
						(mid 371.514116 -159.63011)
						(end 374.485916 -159.63011)
					)
				)
			)
		)
		(zone
			(layer "B.Cu")
			(hatch none 0.5)
			(connect_pads
				(clearance 0)
			)
			(min_thickness 0.25)
			(keepout
				(tracks allowed)
				(vias not_allowed)
				(pads allowed)
				(copperpour not_allowed)
				(footprints allowed)
			)
			(placement
				(enabled no)
				(sheetname "")
			)
			(fill
				(thermal_gap 0.5)
				(thermal_bridge_width 0.5)
				(island_removal_mode 0)
			)
			(polygon
				(pts
					(xy 365.635032 -169.465498) (xy 362.358432 -169.465498) (xy 362.358432 -164.194998) (xy 365.635032 -164.194998)
				)
			)
		)
		(zone
			(layer "B.Cu")
			(hatch none 0.5)
			(connect_pads
				(clearance 0)
			)
			(min_thickness 0.25)
			(keepout
				(tracks allowed)
				(vias not_allowed)
				(pads allowed)
				(copperpour not_allowed)
				(footprints allowed)
			)
			(placement
				(enabled no)
				(sheetname "")
			)
			(fill
				(thermal_gap 0.5)
				(thermal_bridge_width 0.5)
				(island_removal_mode 0)
			)
			(polygon
				(pts
					(xy 365.635032 -161.465514) (xy 362.358432 -161.465514) (xy 362.358432 -156.195014) (xy 365.635032 -156.195014)
				)
			)
		)
		(zone
			(layer "B.Cu")
			(hatch none 0.5)
			(connect_pads
				(clearance 0)
			)
			(min_thickness 0.25)
			(keepout
				(tracks allowed)
				(vias not_allowed)
				(pads allowed)
				(copperpour not_allowed)
				(footprints allowed)
			)
			(placement
				(enabled no)
				(sheetname "")
			)
			(fill
				(thermal_gap 0.5)
				(thermal_bridge_width 0.5)
				(island_removal_mode 0)
			)
			(polygon
				(pts
					(xy 371.63502 -169.465498) (xy 368.35842 -169.465498) (xy 368.35842 -164.194998) (xy 371.63502 -164.194998)
				)
			)
		)
		(zone
			(layer "B.Cu")
			(hatch none 0.5)
			(connect_pads
				(clearance 0)
			)
			(min_thickness 0.25)
			(keepout
				(tracks allowed)
				(vias not_allowed)
				(pads allowed)
				(copperpour not_allowed)
				(footprints allowed)
			)
			(placement
				(enabled no)
				(sheetname "")
			)
			(fill
				(thermal_gap 0.5)
				(thermal_bridge_width 0.5)
				(island_removal_mode 0)
			)
			(polygon
				(pts
					(xy 371.63502 -161.465514) (xy 368.35842 -161.465514) (xy 368.35842 -156.195014) (xy 371.63502 -156.195014)
				)
			)
		)
		(zone
			(layer "B.Cu")
			(hatch none 0.5)
			(connect_pads
				(clearance 0)
			)
			(min_thickness 0.25)
			(keepout
				(tracks allowed)
				(vias not_allowed)
				(pads allowed)
				(copperpour not_allowed)
				(footprints allowed)
			)
			(placement
				(enabled no)
				(sheetname "")
			)
			(fill
				(thermal_gap 0.5)
				(thermal_bridge_width 0.5)
				(island_removal_mode 0)
			)
			(polygon
				(pts
					(xy 377.635008 -169.465498) (xy 374.358408 -169.465498) (xy 374.358408 -164.194998) (xy 377.635008 -164.194998)
				)
			)
		)
		(zone
			(layer "B.Cu")
			(hatch none 0.5)
			(connect_pads
				(clearance 0)
			)
			(min_thickness 0.25)
			(keepout
				(tracks allowed)
				(vias not_allowed)
				(pads allowed)
				(copperpour not_allowed)
				(footprints allowed)
			)
			(placement
				(enabled no)
				(sheetname "")
			)
			(fill
				(thermal_gap 0.5)
				(thermal_bridge_width 0.5)
				(island_removal_mode 0)
			)
			(polygon
				(pts
					(xy 377.635008 -161.465514) (xy 374.358408 -161.465514) (xy 374.358408 -156.195014) (xy 377.635008 -156.195014)
				)
			)
		)
	)
	(footprint ""
		(layer "F.Cu")
		(at 58.8264 -20.574)
		(property "Reference" "H25"
			(at -1.1684 -3.40233 0)
			(unlocked yes)
			(layer "F.SilkS")
			(effects
				(font
					(size 0.7874 0.5842)
					(thickness 0.1524)
				)
				(justify left)
			)
		)
		(property "Value" ""
			(at 0 0 0)
			(layer "F.Fab")
			(effects
				(font
					(size 1.27 1.27)
				)
			)
		)
		(duplicate_pad_numbers_are_jumpers no)
		(fp_circle
			(center 0 0)
			(end 2.4003 0)
			(stroke
				(width 0.1524)
				(type default)
			)
			(fill no)
			(layer "F.SilkS")
		)
		(fp_circle
			(center 0 0)
			(end 6.5913 0)
			(stroke
				(width 0.1524)
				(type default)
			)
			(fill no)
			(layer "B.SilkS")
		)
		(fp_circle
			(center 0 0)
			(end 6.5913 0)
			(stroke
				(width 0.1)
				(type default)
			)
			(fill no)
			(layer "B.Fab")
		)
		(fp_circle
			(center 0 0)
			(end 2.4003 0)
			(stroke
				(width 0.1)
				(type default)
			)
			(fill no)
			(layer "F.Fab")
		)
		(pad "" np_thru_hole circle
			(at 0 0)
			(size 3.175 3.175)
			(drill 3.175)
			(layers "*.Cu" "*.Mask")
			(clearance 0.381)
			(thermal_gap 0.381)
		)
		(zone
			(layers "F.Cu" "B.Cu" "In1.Cu" "In2.Cu" "In3.Cu" "In4.Cu" "In5.Cu" "In6.Cu"
				"In7.Cu" "In8.Cu"
			)
			(hatch none 0.5)
			(connect_pads
				(clearance 0)
			)
			(min_thickness 0.25)
			(keepout
				(tracks not_allowed)
				(vias allowed)
				(pads allowed)
				(copperpour not_allowed)
				(footprints allowed)
			)
			(placement
				(enabled no)
				(sheetname "")
			)
			(fill
				(thermal_gap 0.5)
				(thermal_bridge_width 0.5)
				(island_removal_mode 0)
			)
			(polygon
				(pts
					(arc
						(start 60.9219 -20.574)
						(mid 56.7309 -20.574)
						(end 60.9219 -20.574)
					)
				)
			)
		)
	)
	(footprint ""
		(layer "F.Cu")
		(at 34.874962 -168.82999)
		(property "Reference" "JP2"
			(at 3.606038 21.91766 0)
			(unlocked yes)
			(layer "F.SilkS")
			(effects
				(font
					(size 0.7874 0.5842)
					(thickness 0.1524)
				)
			)
		)
		(property "Value" ""
			(at 0 0 0)
			(layer "F.Fab")
			(effects
				(font
					(size 1.27 1.27)
				)
			)
		)
		(duplicate_pad_numbers_are_jumpers no)
		(fp_line
			(start -6.374892 -18.699988)
			(end 13.124942 -18.699988)
			(stroke
				(width 0.1524)
				(type default)
			)
			(layer "F.SilkS")
		)
		(fp_line
			(start -6.374892 20.999958)
			(end -6.374892 -18.699988)
			(stroke
				(width 0.1524)
				(type default)
			)
			(layer "F.SilkS")
		)
		(fp_line
			(start -3.374898 -15.699994)
			(end 10.124948 -15.699994)
			(stroke
				(width 0.1524)
				(type default)
			)
			(layer "F.SilkS")
		)
		(fp_line
			(start -3.374898 -6.500114)
			(end 10.124948 -6.500114)
			(stroke
				(width 0.1524)
				(type default)
			)
			(layer "F.SilkS")
		)
		(fp_line
			(start -3.374898 17.999964)
			(end -3.374898 -15.699994)
			(stroke
				(width 0.1524)
				(type default)
			)
			(layer "F.SilkS")
		)
		(fp_line
			(start 10.124948 -15.699994)
			(end 10.124948 17.999964)
			(stroke
				(width 0.1524)
				(type default)
			)
			(layer "F.SilkS")
		)
		(fp_line
			(start 10.124948 17.999964)
			(end -3.374898 17.999964)
			(stroke
				(width 0.1524)
				(type default)
			)
			(layer "F.SilkS")
		)
		(fp_line
			(start 13.124942 -18.699988)
			(end 13.124942 20.999958)
			(stroke
				(width 0.1524)
				(type default)
			)
			(layer "F.SilkS")
		)
		(fp_line
			(start 13.124942 20.999958)
			(end -6.374892 20.999958)
			(stroke
				(width 0.1524)
				(type default)
			)
			(layer "F.SilkS")
		)
		(fp_poly
			(pts
				(xy -2.048256 -0.381) (xy -2.048256 0.635) (xy -1.032256 0.127)
			)
			(stroke
				(width 0)
				(type default)
			)
			(fill yes)
			(layer "F.SilkS")
		)
		(fp_line
			(start -6.374892 -18.699988)
			(end 13.124942 -18.699988)
			(stroke
				(width 0.1524)
				(type default)
			)
			(layer "B.SilkS")
		)
		(fp_line
			(start -6.374892 20.999958)
			(end -6.374892 -18.699988)
			(stroke
				(width 0.1524)
				(type default)
			)
			(layer "B.SilkS")
		)
		(fp_line
			(start 13.124942 -18.699988)
			(end 13.124942 20.999958)
			(stroke
				(width 0.1524)
				(type default)
			)
			(layer "B.SilkS")
		)
		(fp_line
			(start 13.124942 20.999958)
			(end -6.374892 20.999958)
			(stroke
				(width 0.1524)
				(type default)
			)
			(layer "B.SilkS")
		)
		(fp_line
			(start -6.374892 -18.699988)
			(end 13.124942 -18.699988)
			(stroke
				(width 0.1)
				(type default)
			)
			(layer "B.Fab")
		)
		(fp_line
			(start -6.374892 20.999958)
			(end -6.374892 -18.699988)
			(stroke
				(width 0.1)
				(type default)
			)
			(layer "B.Fab")
		)
		(fp_line
			(start 13.124942 -18.699988)
			(end 13.124942 20.999958)
			(stroke
				(width 0.1)
				(type default)
			)
			(layer "B.Fab")
		)
		(fp_line
			(start 13.124942 20.999958)
			(end -6.374892 20.999958)
			(stroke
				(width 0.1)
				(type default)
			)
			(layer "B.Fab")
		)
		(fp_line
			(start -3.374898 -15.699994)
			(end 10.124948 -15.699994)
			(stroke
				(width 0.1)
				(type default)
			)
			(layer "F.Fab")
		)
		(fp_line
			(start -3.374898 17.999964)
			(end -3.374898 -15.699994)
			(stroke
				(width 0.1)
				(type default)
			)
			(layer "F.Fab")
		)
		(fp_line
			(start 10.124948 -15.699994)
			(end 10.124948 17.999964)
			(stroke
				(width 0.1)
				(type default)
			)
			(layer "F.Fab")
		)
		(fp_line
			(start 10.124948 17.999964)
			(end -3.374898 17.999964)
			(stroke
				(width 0.1)
				(type default)
			)
			(layer "F.Fab")
		)
		(fp_poly
			(pts
				(xy -4.842256 -0.508) (xy -4.842256 0.508) (xy -3.826256 0)
			)
			(stroke
				(width 0)
				(type default)
			)
			(fill yes)
			(layer "F.Fab")
		)
		(fp_text user "PRESS-FIT"
			(at -4.8768 19.94535 0)
			(unlocked yes)
			(layer "F.SilkS")
			(effects
				(font
					(size 1.905 1.4224)
					(thickness 0.1524)
				)
				(justify left)
			)
		)
		(fp_text user "PRESS-FIT"
			(at -2.369312 16.42999 270)
			(unlocked yes)
			(layer "B.SilkS")
			(effects
				(font
					(size 1.905 1.4224)
					(thickness 0.1524)
				)
				(justify left mirror)
			)
		)
		(fp_text user "PRESS-FIT"
			(at 11.811 19.94535 0)
			(unlocked yes)
			(layer "B.Fab")
			(effects
				(font
					(size 1.905 1.4224)
					(thickness 0.1524)
				)
				(justify left mirror)
			)
		)
		(fp_text user "PRESS-FIT"
			(at -4.8768 19.94535 0)
			(unlocked yes)
			(layer "F.Fab")
			(effects
				(font
					(size 1.905 1.4224)
					(thickness 0.1524)
				)
				(justify left)
			)
		)
		(pad "P1_1" thru_hole rect
			(at 0 0)
			(size 1.156208 1.156208)
			(drill 0.749808)
			(layers "*.Cu" "*.Mask")
			(remove_unused_layers no)
			(net "P52V_HS2")
			(clearance 0.0508)
			(thermal_gap 0.0508)
			(padstack
				(mode front_inner_back)
				(layer "Inner"
					(shape circle)
					(size 1.156208 1.156208)
					(clearance 0.0508)
				)
				(layer "B.Cu"
					(shape rect)
					(size 1.156208 1.156208)
					(clearance 0.0508)
				)
			)
		)
		(pad "P1_2" thru_hole circle
			(at 0 1.999996)
			(size 1.156208 1.156208)
			(drill 0.749808)
			(layers "*.Cu" "*.Mask")
			(remove_unused_layers no)
			(net "P52V_HS2")
			(clearance 0.0508)
			(thermal_gap 0.0508)
		)
		(pad "P1_3" thru_hole circle
			(at 0 3.999992)
			(size 1.156208 1.156208)
			(drill 0.749808)
			(layers "*.Cu" "*.Mask")
			(remove_unused_layers no)
			(net "P52V_HS2")
			(clearance 0.0508)
			(thermal_gap 0.0508)
		)
		(pad "P1_4" thru_hole circle
			(at 0 5.999988)
			(size 1.156208 1.156208)
			(drill 0.749808)
			(layers "*.Cu" "*.Mask")
			(remove_unused_layers no)
			(net "P52V_HS2")
			(clearance 0.0508)
			(thermal_gap 0.0508)
		)
		(pad "P1_5" thru_hole circle
			(at 0 7.999984)
			(size 1.156208 1.156208)
			(drill 0.749808)
			(layers "*.Cu" "*.Mask")
			(remove_unused_layers no)
			(net "P52V_HS2")
			(clearance 0.0508)
			(thermal_gap 0.0508)
		)
		(pad "P1_6" thru_hole circle
			(at 0 9.99998)
			(size 1.156208 1.156208)
			(drill 0.749808)
			(layers "*.Cu" "*.Mask")
			(remove_unused_layers no)
			(net "P52V_HS2")
			(clearance 0.0508)
			(thermal_gap 0.0508)
		)
		(pad "P1_7" thru_hole circle
			(at 0 11.999976)
			(size 1.156208 1.156208)
			(drill 0.749808)
			(layers "*.Cu" "*.Mask")
			(remove_unused_layers no)
			(net "P52V_HS2")
			(clearance 0.0508)
			(thermal_gap 0.0508)
		)
		(pad "P1_8" thru_hole circle
			(at 0 13.999972)
			(size 1.156208 1.156208)
			(drill 0.749808)
			(layers "*.Cu" "*.Mask")
			(remove_unused_layers no)
			(net "P52V_HS2")
			(clearance 0.0508)
			(thermal_gap 0.0508)
		)
		(pad "P1_9" thru_hole circle
			(at 0 15.999968)
			(size 1.156208 1.156208)
			(drill 0.749808)
			(layers "*.Cu" "*.Mask")
			(remove_unused_layers no)
			(net "P52V_HS2")
			(clearance 0.0508)
			(thermal_gap 0.0508)
		)
		(pad "P1_10" thru_hole circle
			(at 1.999996 0)
			(size 1.156208 1.156208)
			(drill 0.749808)
			(layers "*.Cu" "*.Mask")
			(remove_unused_layers no)
			(net "P52V_HS2")
			(clearance 0.0508)
			(thermal_gap 0.0508)
		)
		(pad "P1_11" thru_hole circle
			(at 1.999996 1.999996)
			(size 1.156208 1.156208)
			(drill 0.749808)
			(layers "*.Cu" "*.Mask")
			(remove_unused_layers no)
			(net "P52V_HS2")
			(clearance 0.0508)
			(thermal_gap 0.0508)
		)
		(pad "P1_12" thru_hole circle
			(at 1.999996 3.999992)
			(size 1.156208 1.156208)
			(drill 0.749808)
			(layers "*.Cu" "*.Mask")
			(remove_unused_layers no)
			(net "P52V_HS2")
			(clearance 0.0508)
			(thermal_gap 0.0508)
		)
		(pad "P1_13" thru_hole circle
			(at 1.999996 5.999988)
			(size 1.156208 1.156208)
			(drill 0.749808)
			(layers "*.Cu" "*.Mask")
			(remove_unused_layers no)
			(net "P52V_HS2")
			(clearance 0.0508)
			(thermal_gap 0.0508)
		)
		(pad "P1_14" thru_hole circle
			(at 1.999996 7.999984)
			(size 1.156208 1.156208)
			(drill 0.749808)
			(layers "*.Cu" "*.Mask")
			(remove_unused_layers no)
			(net "P52V_HS2")
			(clearance 0.0508)
			(thermal_gap 0.0508)
		)
		(pad "P1_15" thru_hole circle
			(at 1.999996 9.99998)
			(size 1.156208 1.156208)
			(drill 0.749808)
			(layers "*.Cu" "*.Mask")
			(remove_unused_layers no)
			(net "P52V_HS2")
			(clearance 0.0508)
			(thermal_gap 0.0508)
		)
		(pad "P1_16" thru_hole circle
			(at 1.999996 11.999976)
			(size 1.156208 1.156208)
			(drill 0.749808)
			(layers "*.Cu" "*.Mask")
			(remove_unused_layers no)
			(net "P52V_HS2")
			(clearance 0.0508)
			(thermal_gap 0.0508)
		)
		(pad "P1_17" thru_hole circle
			(at 1.999996 13.999972)
			(size 1.156208 1.156208)
			(drill 0.749808)
			(layers "*.Cu" "*.Mask")
			(remove_unused_layers no)
			(net "P52V_HS2")
			(clearance 0.0508)
			(thermal_gap 0.0508)
		)
		(pad "P1_18" thru_hole circle
			(at 1.999996 15.999968)
			(size 1.156208 1.156208)
			(drill 0.749808)
			(layers "*.Cu" "*.Mask")
			(remove_unused_layers no)
			(net "P52V_HS2")
			(clearance 0.0508)
			(thermal_gap 0.0508)
		)
		(pad "P2_1" thru_hole circle
			(at 4.750054 0)
			(size 1.156208 1.156208)
			(drill 0.749808)
			(layers "*.Cu" "*.Mask")
			(remove_unused_layers no)
			(net "GND")
			(clearance 0.0508)
			(thermal_gap 0.0508)
		)
		(pad "P2_2" thru_hole circle
			(at 4.750054 1.999996)
			(size 1.156208 1.156208)
			(drill 0.749808)
			(layers "*.Cu" "*.Mask")
			(remove_unused_layers no)
			(net "GND")
			(clearance 0.0508)
			(thermal_gap 0.0508)
		)
		(pad "P2_3" thru_hole circle
			(at 4.750054 3.999992)
			(size 1.156208 1.156208)
			(drill 0.749808)
			(layers "*.Cu" "*.Mask")
			(remove_unused_layers no)
			(net "GND")
			(clearance 0.0508)
			(thermal_gap 0.0508)
		)
		(pad "P2_4" thru_hole circle
			(at 4.750054 5.999988)
			(size 1.156208 1.156208)
			(drill 0.749808)
			(layers "*.Cu" "*.Mask")
			(remove_unused_layers no)
			(net "GND")
			(clearance 0.0508)
			(thermal_gap 0.0508)
		)
		(pad "P2_5" thru_hole circle
			(at 4.750054 7.999984)
			(size 1.156208 1.156208)
			(drill 0.749808)
			(layers "*.Cu" "*.Mask")
			(remove_unused_layers no)
			(net "GND")
			(clearance 0.0508)
			(thermal_gap 0.0508)
		)
		(pad "P2_6" thru_hole circle
			(at 4.750054 9.99998)
			(size 1.156208 1.156208)
			(drill 0.749808)
			(layers "*.Cu" "*.Mask")
			(remove_unused_layers no)
			(net "GND")
			(clearance 0.0508)
			(thermal_gap 0.0508)
		)
		(pad "P2_7" thru_hole circle
			(at 4.750054 11.999976)
			(size 1.156208 1.156208)
			(drill 0.749808)
			(layers "*.Cu" "*.Mask")
			(remove_unused_layers no)
			(net "GND")
			(clearance 0.0508)
			(thermal_gap 0.0508)
		)
		(pad "P2_8" thru_hole circle
			(at 4.750054 13.999972)
			(size 1.156208 1.156208)
			(drill 0.749808)
			(layers "*.Cu" "*.Mask")
			(remove_unused_layers no)
			(net "GND")
			(clearance 0.0508)
			(thermal_gap 0.0508)
		)
		(pad "P2_9" thru_hole circle
			(at 4.750054 15.999968)
			(size 1.156208 1.156208)
			(drill 0.749808)
			(layers "*.Cu" "*.Mask")
			(remove_unused_layers no)
			(net "GND")
			(clearance 0.0508)
			(thermal_gap 0.0508)
		)
		(pad "P2_10" thru_hole circle
			(at 6.75005 0)
			(size 1.156208 1.156208)
			(drill 0.749808)
			(layers "*.Cu" "*.Mask")
			(remove_unused_layers no)
			(net "GND")
			(clearance 0.0508)
			(thermal_gap 0.0508)
		)
		(pad "P2_11" thru_hole circle
			(at 6.75005 1.999996)
			(size 1.156208 1.156208)
			(drill 0.749808)
			(layers "*.Cu" "*.Mask")
			(remove_unused_layers no)
			(net "GND")
			(clearance 0.0508)
			(thermal_gap 0.0508)
		)
		(pad "P2_12" thru_hole circle
			(at 6.75005 3.999992)
			(size 1.156208 1.156208)
			(drill 0.749808)
			(layers "*.Cu" "*.Mask")
			(remove_unused_layers no)
			(net "GND")
			(clearance 0.0508)
			(thermal_gap 0.0508)
		)
		(pad "P2_13" thru_hole circle
			(at 6.75005 5.999988)
			(size 1.156208 1.156208)
			(drill 0.749808)
			(layers "*.Cu" "*.Mask")
			(remove_unused_layers no)
			(net "GND")
			(clearance 0.0508)
			(thermal_gap 0.0508)
		)
		(pad "P2_14" thru_hole circle
			(at 6.75005 7.999984)
			(size 1.156208 1.156208)
			(drill 0.749808)
			(layers "*.Cu" "*.Mask")
			(remove_unused_layers no)
			(net "GND")
			(clearance 0.0508)
			(thermal_gap 0.0508)
		)
		(pad "P2_15" thru_hole circle
			(at 6.75005 9.99998)
			(size 1.156208 1.156208)
			(drill 0.749808)
			(layers "*.Cu" "*.Mask")
			(remove_unused_layers no)
			(net "GND")
			(clearance 0.0508)
			(thermal_gap 0.0508)
		)
		(pad "P2_16" thru_hole circle
			(at 6.75005 11.999976)
			(size 1.156208 1.156208)
			(drill 0.749808)
			(layers "*.Cu" "*.Mask")
			(remove_unused_layers no)
			(net "GND")
			(clearance 0.0508)
			(thermal_gap 0.0508)
		)
		(pad "P2_17" thru_hole circle
			(at 6.75005 13.999972)
			(size 1.156208 1.156208)
			(drill 0.749808)
			(layers "*.Cu" "*.Mask")
			(remove_unused_layers no)
			(net "GND")
			(clearance 0.0508)
			(thermal_gap 0.0508)
		)
		(pad "P2_18" thru_hole circle
			(at 6.75005 15.999968)
			(size 1.156208 1.156208)
			(drill 0.749808)
			(layers "*.Cu" "*.Mask")
			(remove_unused_layers no)
			(net "GND")
			(clearance 0.0508)
			(thermal_gap 0.0508)
		)
		(zone
			(layer "B.Cu")
			(hatch none 0.5)
			(connect_pads
				(clearance 0)
			)
			(min_thickness 0.25)
			(keepout
				(tracks allowed)
				(vias not_allowed)
				(pads allowed)
				(copperpour not_allowed)
				(footprints allowed)
			)
			(placement
				(enabled no)
				(sheetname "")
			)
			(fill
				(thermal_gap 0.5)
				(thermal_bridge_width 0.5)
				(island_removal_mode 0)
			)
			(polygon
				(pts
					(xy 34.233358 -169.471594) (xy 34.233358 -152.188418) (xy 42.266616 -152.188418) (xy 42.266616 -169.471594)
				)
			)
		)
	)
	(footprint ""
		(layer "F.Cu")
		(at 436.245 -27.813 180)
		(property "Reference" "R328"
			(at 0 0 180)
			(layer "F.SilkS")
			(hide yes)
			(effects
				(font
					(size 1.27 1.27)
				)
			)
		)
		(property "Value" ""
			(at 0 0 180)
			(layer "F.Fab")
			(effects
				(font
					(size 1.27 1.27)
				)
			)
		)
		(duplicate_pad_numbers_are_jumpers no)
		(fp_line
			(start 0.7874 0.4064)
			(end -0.7874 0.4064)
			(stroke
				(width 0.1524)
				(type default)
			)
			(layer "F.SilkS")
		)
		(fp_line
			(start 0.7874 -0.4064)
			(end 0.7874 0.4064)
			(stroke
				(width 0.1524)
				(type default)
			)
			(layer "F.SilkS")
		)
		(fp_line
			(start -0.7874 0.4064)
			(end -0.7874 -0.4064)
			(stroke
				(width 0.1524)
				(type default)
			)
			(layer "F.SilkS")
		)
		(fp_line
			(start -0.7874 -0.4064)
			(end 0.7874 -0.4064)
			(stroke
				(width 0.1524)
				(type default)
			)
			(layer "F.SilkS")
		)
		(fp_line
			(start 0.67945 0.3048)
			(end 0.120396 0.3048)
			(stroke
				(width 0.1)
				(type default)
			)
			(layer "F.Fab")
		)
		(fp_line
			(start 0.67945 -0.3048)
			(end 0.67945 0.3048)
			(stroke
				(width 0.1)
				(type default)
			)
			(layer "F.Fab")
		)
		(fp_line
			(start 0.12065 -0.2794)
			(end 0.12065 -0.3048)
			(stroke
				(width 0.1)
				(type default)
			)
			(layer "F.Fab")
		)
		(fp_line
			(start 0.12065 -0.3048)
			(end 0.67945 -0.3048)
			(stroke
				(width 0.1)
				(type default)
			)
			(layer "F.Fab")
		)
		(fp_line
			(start 0.120396 0.3048)
			(end 0.120396 0.2794)
			(stroke
				(width 0.1)
				(type default)
			)
			(layer "F.Fab")
		)
		(fp_line
			(start 0.120396 0.2794)
			(end -0.12065 0.2794)
			(stroke
				(width 0.1)
				(type default)
			)
			(layer "F.Fab")
		)
		(fp_line
			(start -0.12065 0.3048)
			(end -0.67945 0.3048)
			(stroke
				(width 0.1)
				(type default)
			)
			(layer "F.Fab")
		)
		(fp_line
			(start -0.12065 0.2794)
			(end -0.12065 0.3048)
			(stroke
				(width 0.1)
				(type default)
			)
			(layer "F.Fab")
		)
		(fp_line
			(start -0.12065 -0.2794)
			(end 0.12065 -0.2794)
			(stroke
				(width 0.1)
				(type default)
			)
			(layer "F.Fab")
		)
		(fp_line
			(start -0.12065 -0.305054)
			(end -0.12065 -0.2794)
			(stroke
				(width 0.1)
				(type default)
			)
			(layer "F.Fab")
		)
		(fp_line
			(start -0.67945 0.3048)
			(end -0.67945 -0.305054)
			(stroke
				(width 0.1)
				(type default)
			)
			(layer "F.Fab")
		)
		(fp_line
			(start -0.67945 -0.305054)
			(end -0.12065 -0.305054)
			(stroke
				(width 0.1)
				(type default)
			)
			(layer "F.Fab")
		)
		(pad "1" smd circle
			(at -0.40005 0 180)
			(size 0 0)
			(layers "F.Cu" "F.Mask" "F.Paste")
			(net "SMB_PDB_FAN_0_SCL")
		)
		(pad "2" smd circle
			(at 0.40005 0 180)
			(size 0 0)
			(layers "F.Cu" "F.Mask" "F.Paste")
			(net "P3V3_AUX")
		)
	)
	(footprint ""
		(layer "F.Cu")
		(at 416.948874 -55.831232)
		(property "Reference" ""
			(at 0 0 0)
			(layer "F.SilkS")
			(hide yes)
			(effects
				(font
					(size 1.27 1.27)
				)
			)
		)
		(property "Value" ""
			(at 0 0 0)
			(layer "F.Fab")
			(effects
				(font
					(size 1.27 1.27)
				)
			)
		)
		(duplicate_pad_numbers_are_jumpers no)
		(pad "1" smd circle
			(at 0 0)
			(size 0.9906 0.9906)
			(layers "F.Cu" "F.Mask" "F.Paste")
			(net "Net_246")
		)
		(zone
			(layer "F.Cu")
			(hatch none 0.5)
			(connect_pads
				(clearance 0)
			)
			(min_thickness 0.25)
			(keepout
				(tracks not_allowed)
				(vias allowed)
				(pads allowed)
				(copperpour not_allowed)
				(footprints allowed)
			)
			(placement
				(enabled no)
				(sheetname "")
			)
			(fill
				(thermal_gap 0.5)
				(thermal_bridge_width 0.5)
				(island_removal_mode 0)
			)
			(polygon
				(pts
					(arc
						(start 418.574474 -55.831232)
						(mid 415.323274 -55.831232)
						(end 418.574474 -55.831232)
					)
				)
			)
		)
	)
	(footprint ""
		(layer "F.Cu")
		(at 437.134 -41.148 90)
		(property "Reference" "R6"
			(at 0 0 90)
			(layer "F.SilkS")
			(hide yes)
			(effects
				(font
					(size 1.27 1.27)
				)
			)
		)
		(property "Value" ""
			(at 0 0 90)
			(layer "F.Fab")
			(effects
				(font
					(size 1.27 1.27)
				)
			)
		)
		(duplicate_pad_numbers_are_jumpers no)
		(fp_line
			(start 0.7874 -0.4064)
			(end 0.7874 0.4064)
			(stroke
				(width 0.1524)
				(type default)
			)
			(layer "F.SilkS")
		)
		(fp_line
			(start -0.7874 -0.4064)
			(end 0.7874 -0.4064)
			(stroke
				(width 0.1524)
				(type default)
			)
			(layer "F.SilkS")
		)
		(fp_line
			(start 0.7874 0.4064)
			(end -0.7874 0.4064)
			(stroke
				(width 0.1524)
				(type default)
			)
			(layer "F.SilkS")
		)
		(fp_line
			(start -0.7874 0.4064)
			(end -0.7874 -0.4064)
			(stroke
				(width 0.1524)
				(type default)
			)
			(layer "F.SilkS")
		)
		(fp_line
			(start -0.12065 -0.305054)
			(end -0.12065 -0.2794)
			(stroke
				(width 0.1)
				(type default)
			)
			(layer "F.Fab")
		)
		(fp_line
			(start -0.67945 -0.305054)
			(end -0.12065 -0.305054)
			(stroke
				(width 0.1)
				(type default)
			)
			(layer "F.Fab")
		)
		(fp_line
			(start 0.67945 -0.3048)
			(end 0.67945 0.3048)
			(stroke
				(width 0.1)
				(type default)
			)
			(layer "F.Fab")
		)
		(fp_line
			(start 0.12065 -0.3048)
			(end 0.67945 -0.3048)
			(stroke
				(width 0.1)
				(type default)
			)
			(layer "F.Fab")
		)
		(fp_line
			(start 0.12065 -0.2794)
			(end 0.12065 -0.3048)
			(stroke
				(width 0.1)
				(type default)
			)
			(layer "F.Fab")
		)
		(fp_line
			(start -0.12065 -0.2794)
			(end 0.12065 -0.2794)
			(stroke
				(width 0.1)
				(type default)
			)
			(layer "F.Fab")
		)
		(fp_line
			(start 0.120396 0.2794)
			(end -0.12065 0.2794)
			(stroke
				(width 0.1)
				(type default)
			)
			(layer "F.Fab")
		)
		(fp_line
			(start -0.12065 0.2794)
			(end -0.12065 0.3048)
			(stroke
				(width 0.1)
				(type default)
			)
			(layer "F.Fab")
		)
		(fp_line
			(start 0.67945 0.3048)
			(end 0.120396 0.3048)
			(stroke
				(width 0.1)
				(type default)
			)
			(layer "F.Fab")
		)
		(fp_line
			(start 0.120396 0.3048)
			(end 0.120396 0.2794)
			(stroke
				(width 0.1)
				(type default)
			)
			(layer "F.Fab")
		)
		(fp_line
			(start -0.12065 0.3048)
			(end -0.67945 0.3048)
			(stroke
				(width 0.1)
				(type default)
			)
			(layer "F.Fab")
		)
		(fp_line
			(start -0.67945 0.3048)
			(end -0.67945 -0.305054)
			(stroke
				(width 0.1)
				(type default)
			)
			(layer "F.Fab")
		)
		(pad "1" smd circle
			(at -0.40005 0 90)
			(size 0 0)
			(layers "F.Cu" "F.Mask" "F.Paste")
			(net "SMB_PDB_SCL")
		)
		(pad "2" smd circle
			(at 0.40005 0 90)
			(size 0 0)
			(layers "F.Cu" "F.Mask" "F.Paste")
			(net "SMB_PDB_MISC_SCL_R")
		)
	)
	(footprint ""
		(layer "F.Cu")
		(at 220.0656 -97.0788)
		(property "Reference" "JP3"
			(at 1.0414 -1.95453 0)
			(unlocked yes)
			(layer "F.SilkS")
			(effects
				(font
					(size 0.7874 0.5842)
					(thickness 0.1524)
				)
				(justify left)
			)
		)
		(property "Value" ""
			(at 0 0 0)
			(layer "F.Fab")
			(effects
				(font
					(size 1.27 1.27)
				)
			)
		)
		(duplicate_pad_numbers_are_jumpers no)
		(fp_line
			(start -1.234948 -1.335024)
			(end 1.234948 -1.335024)
			(stroke
				(width 0.1524)
				(type default)
			)
			(layer "F.SilkS")
		)
		(fp_line
			(start -1.234948 6.415024)
			(end -1.234948 -1.335024)
			(stroke
				(width 0.1524)
				(type default)
			)
			(layer "F.SilkS")
		)
		(fp_line
			(start 1.234948 -1.335024)
			(end 1.234948 6.415024)
			(stroke
				(width 0.1524)
				(type default)
			)
			(layer "F.SilkS")
		)
		(fp_line
			(start 1.234948 6.415024)
			(end -1.234948 6.415024)
			(stroke
				(width 0.1524)
				(type default)
			)
			(layer "F.SilkS")
		)
		(fp_poly
			(pts
				(xy 0.508 -2.530348) (xy -0.508 -2.530348) (xy 0 -1.514348)
			)
			(stroke
				(width 0)
				(type default)
			)
			(fill yes)
			(layer "F.SilkS")
		)
		(fp_line
			(start -1.234948 -1.335024)
			(end 1.234948 -1.335024)
			(stroke
				(width 0.1)
				(type default)
			)
			(layer "F.Fab")
		)
		(fp_line
			(start -1.234948 6.415024)
			(end -1.234948 -1.335024)
			(stroke
				(width 0.1)
				(type default)
			)
			(layer "F.Fab")
		)
		(fp_line
			(start 1.234948 -1.335024)
			(end 1.234948 6.415024)
			(stroke
				(width 0.1)
				(type default)
			)
			(layer "F.Fab")
		)
		(fp_line
			(start 1.234948 6.415024)
			(end -1.234948 6.415024)
			(stroke
				(width 0.1)
				(type default)
			)
			(layer "F.Fab")
		)
		(fp_poly
			(pts
				(xy 0.508 -2.530348) (xy -0.508 -2.530348) (xy 0 -1.514348)
			)
			(stroke
				(width 0)
				(type default)
			)
			(fill yes)
			(layer "F.Fab")
		)
		(fp_text user "3"
			(at -0.3683 7.45617 0)
			(unlocked yes)
			(layer "F.SilkS")
			(effects
				(font
					(size 0.7874 0.5842)
					(thickness 0.1524)
				)
				(justify left)
			)
		)
		(fp_text user "1"
			(at -0.00127 -0.954024 270)
			(unlocked yes)
			(layer "B.SilkS")
			(effects
				(font
					(size 0.7874 0.5842)
					(thickness 0.1524)
				)
				(justify left mirror)
			)
		)
		(fp_text user "3"
			(at -0.00127 6.640576 270)
			(unlocked yes)
			(layer "B.SilkS")
			(effects
				(font
					(size 0.7874 0.5842)
					(thickness 0.1524)
				)
				(justify left mirror)
			)
		)
		(fp_text user "1"
			(at -0.00127 -0.954024 270)
			(unlocked yes)
			(layer "B.Fab")
			(effects
				(font
					(size 0.7874 0.5842)
					(thickness 0.1524)
				)
				(justify left mirror)
			)
		)
		(fp_text user "3"
			(at -0.00127 6.640576 270)
			(unlocked yes)
			(layer "B.Fab")
			(effects
				(font
					(size 0.7874 0.5842)
					(thickness 0.1524)
				)
				(justify left mirror)
			)
		)
		(fp_text user "3"
			(at -0.009652 6.5659 270)
			(unlocked yes)
			(layer "F.Fab")
			(effects
				(font
					(size 0.7874 0.5842)
					(thickness 0.1524)
				)
				(justify left)
			)
		)
		(pad "1" thru_hole rect
			(at 0 0 270)
			(size 1.6764 1.6764)
			(drill 1.1684)
			(layers "*.Cu" "*.Mask")
			(remove_unused_layers no)
			(net "SMB_P52V_PDB_DEBUG_SDA")
			(clearance 0)
			(padstack
				(mode front_inner_back)
				(layer "Inner"
					(shape circle)
					(size 1.6764 1.6764)
					(clearance 0)
				)
				(layer "B.Cu"
					(shape rect)
					(size 1.6764 1.6764)
					(clearance 0)
				)
			)
		)
		(pad "2" thru_hole circle
			(at 0 2.54 270)
			(size 1.6764 1.6764)
			(drill 1.1684)
			(layers "*.Cu" "*.Mask")
			(remove_unused_layers no)
			(net "GND")
			(clearance 0)
		)
		(pad "3" thru_hole circle
			(at 0 5.08 270)
			(size 1.6764 1.6764)
			(drill 1.1684)
			(layers "*.Cu" "*.Mask")
			(remove_unused_layers no)
			(net "SMB_P52V_PDB_DEBUG_SCL")
			(clearance 0)
		)
	)
	(footprint ""
		(layer "F.Cu")
		(at 416.24758 -32.75076 90)
		(property "Reference" "C99"
			(at 0 0 90)
			(layer "F.SilkS")
			(hide yes)
			(effects
				(font
					(size 1.27 1.27)
				)
			)
		)
		(property "Value" ""
			(at 0 0 90)
			(layer "F.Fab")
			(effects
				(font
					(size 1.27 1.27)
				)
			)
		)
		(duplicate_pad_numbers_are_jumpers no)
		(fp_line
			(start 0.7874 -0.4064)
			(end 0.7874 0.4064)
			(stroke
				(width 0.1524)
				(type default)
			)
			(layer "F.SilkS")
		)
		(fp_line
			(start -0.7874 -0.4064)
			(end 0.7874 -0.4064)
			(stroke
				(width 0.1524)
				(type default)
			)
			(layer "F.SilkS")
		)
		(fp_line
			(start 0.7874 0.4064)
			(end -0.7874 0.4064)
			(stroke
				(width 0.1524)
				(type default)
			)
			(layer "F.SilkS")
		)
		(fp_line
			(start -0.7874 0.4064)
			(end -0.7874 -0.4064)
			(stroke
				(width 0.1524)
				(type default)
			)
			(layer "F.SilkS")
		)
		(fp_line
			(start -0.12065 -0.305054)
			(end -0.12065 -0.2794)
			(stroke
				(width 0.1)
				(type default)
			)
			(layer "F.Fab")
		)
		(fp_line
			(start -0.67945 -0.305054)
			(end -0.12065 -0.305054)
			(stroke
				(width 0.1)
				(type default)
			)
			(layer "F.Fab")
		)
		(fp_line
			(start 0.67945 -0.3048)
			(end 0.67945 0.3048)
			(stroke
				(width 0.1)
				(type default)
			)
			(layer "F.Fab")
		)
		(fp_line
			(start 0.12065 -0.3048)
			(end 0.67945 -0.3048)
			(stroke
				(width 0.1)
				(type default)
			)
			(layer "F.Fab")
		)
		(fp_line
			(start 0.12065 -0.2794)
			(end 0.12065 -0.3048)
			(stroke
				(width 0.1)
				(type default)
			)
			(layer "F.Fab")
		)
		(fp_line
			(start -0.12065 -0.2794)
			(end 0.12065 -0.2794)
			(stroke
				(width 0.1)
				(type default)
			)
			(layer "F.Fab")
		)
		(fp_line
			(start 0.120396 0.2794)
			(end -0.12065 0.2794)
			(stroke
				(width 0.1)
				(type default)
			)
			(layer "F.Fab")
		)
		(fp_line
			(start -0.12065 0.2794)
			(end -0.12065 0.3048)
			(stroke
				(width 0.1)
				(type default)
			)
			(layer "F.Fab")
		)
		(fp_line
			(start 0.67945 0.3048)
			(end 0.120396 0.3048)
			(stroke
				(width 0.1)
				(type default)
			)
			(layer "F.Fab")
		)
		(fp_line
			(start 0.120396 0.3048)
			(end 0.120396 0.2794)
			(stroke
				(width 0.1)
				(type default)
			)
			(layer "F.Fab")
		)
		(fp_line
			(start -0.12065 0.3048)
			(end -0.67945 0.3048)
			(stroke
				(width 0.1)
				(type default)
			)
			(layer "F.Fab")
		)
		(fp_line
			(start -0.67945 0.3048)
			(end -0.67945 -0.305054)
			(stroke
				(width 0.1)
				(type default)
			)
			(layer "F.Fab")
		)
		(pad "1" smd circle
			(at -0.40005 0 90)
			(size 0 0)
			(layers "F.Cu" "F.Mask" "F.Paste")
			(net "P12V_LED_SS")
		)
		(pad "2" smd circle
			(at 0.40005 0 90)
			(size 0 0)
			(layers "F.Cu" "F.Mask" "F.Paste")
			(net "GND")
		)
	)
	(footprint ""
		(layer "F.Cu")
		(at 388.3914 -19.939)
		(property "Reference" "H27"
			(at -0.889 3.20167 0)
			(unlocked yes)
			(layer "F.SilkS")
			(effects
				(font
					(size 0.7874 0.5842)
					(thickness 0.1524)
				)
				(justify left)
			)
		)
		(property "Value" ""
			(at 0 0 0)
			(layer "F.Fab")
			(effects
				(font
					(size 1.27 1.27)
				)
			)
		)
		(duplicate_pad_numbers_are_jumpers no)
		(fp_circle
			(center 0 0)
			(end 2.4003 0)
			(stroke
				(width 0.1524)
				(type default)
			)
			(fill no)
			(layer "F.SilkS")
		)
		(fp_circle
			(center 0 0)
			(end 6.5913 0)
			(stroke
				(width 0.1524)
				(type default)
			)
			(fill no)
			(layer "B.SilkS")
		)
		(fp_circle
			(center 0 0)
			(end 6.5913 0)
			(stroke
				(width 0.1)
				(type default)
			)
			(fill no)
			(layer "B.Fab")
		)
		(fp_circle
			(center 0 0)
			(end 2.4003 0)
			(stroke
				(width 0.1)
				(type default)
			)
			(fill no)
			(layer "F.Fab")
		)
		(pad "" np_thru_hole circle
			(at 0 0)
			(size 3.175 3.175)
			(drill 3.175)
			(layers "*.Cu" "*.Mask")
			(clearance 0.381)
			(thermal_gap 0.381)
		)
		(zone
			(layers "F.Cu" "B.Cu" "In1.Cu" "In2.Cu" "In3.Cu" "In4.Cu" "In5.Cu" "In6.Cu"
				"In7.Cu" "In8.Cu"
			)
			(hatch none 0.5)
			(connect_pads
				(clearance 0)
			)
			(min_thickness 0.25)
			(keepout
				(tracks not_allowed)
				(vias allowed)
				(pads allowed)
				(copperpour not_allowed)
				(footprints allowed)
			)
			(placement
				(enabled no)
				(sheetname "")
			)
			(fill
				(thermal_gap 0.5)
				(thermal_bridge_width 0.5)
				(island_removal_mode 0)
			)
			(polygon
				(pts
					(arc
						(start 390.4869 -19.939)
						(mid 386.2959 -19.939)
						(end 390.4869 -19.939)
					)
				)
			)
		)
	)
	(footprint ""
		(layer "F.Cu")
		(at 433.451 -34.163 180)
		(property "Reference" "R25"
			(at 0 0 180)
			(layer "F.SilkS")
			(hide yes)
			(effects
				(font
					(size 1.27 1.27)
				)
			)
		)
		(property "Value" ""
			(at 0 0 180)
			(layer "F.Fab")
			(effects
				(font
					(size 1.27 1.27)
				)
			)
		)
		(duplicate_pad_numbers_are_jumpers no)
		(fp_line
			(start 0.7874 0.4064)
			(end -0.7874 0.4064)
			(stroke
				(width 0.1524)
				(type default)
			)
			(layer "F.SilkS")
		)
		(fp_line
			(start 0.7874 -0.4064)
			(end 0.7874 0.4064)
			(stroke
				(width 0.1524)
				(type default)
			)
			(layer "F.SilkS")
		)
		(fp_line
			(start -0.7874 0.4064)
			(end -0.7874 -0.4064)
			(stroke
				(width 0.1524)
				(type default)
			)
			(layer "F.SilkS")
		)
		(fp_line
			(start -0.7874 -0.4064)
			(end 0.7874 -0.4064)
			(stroke
				(width 0.1524)
				(type default)
			)
			(layer "F.SilkS")
		)
		(fp_line
			(start 0.67945 0.3048)
			(end 0.120396 0.3048)
			(stroke
				(width 0.1)
				(type default)
			)
			(layer "F.Fab")
		)
		(fp_line
			(start 0.67945 -0.3048)
			(end 0.67945 0.3048)
			(stroke
				(width 0.1)
				(type default)
			)
			(layer "F.Fab")
		)
		(fp_line
			(start 0.12065 -0.2794)
			(end 0.12065 -0.3048)
			(stroke
				(width 0.1)
				(type default)
			)
			(layer "F.Fab")
		)
		(fp_line
			(start 0.12065 -0.3048)
			(end 0.67945 -0.3048)
			(stroke
				(width 0.1)
				(type default)
			)
			(layer "F.Fab")
		)
		(fp_line
			(start 0.120396 0.3048)
			(end 0.120396 0.2794)
			(stroke
				(width 0.1)
				(type default)
			)
			(layer "F.Fab")
		)
		(fp_line
			(start 0.120396 0.2794)
			(end -0.12065 0.2794)
			(stroke
				(width 0.1)
				(type default)
			)
			(layer "F.Fab")
		)
		(fp_line
			(start -0.12065 0.3048)
			(end -0.67945 0.3048)
			(stroke
				(width 0.1)
				(type default)
			)
			(layer "F.Fab")
		)
		(fp_line
			(start -0.12065 0.2794)
			(end -0.12065 0.3048)
			(stroke
				(width 0.1)
				(type default)
			)
			(layer "F.Fab")
		)
		(fp_line
			(start -0.12065 -0.2794)
			(end 0.12065 -0.2794)
			(stroke
				(width 0.1)
				(type default)
			)
			(layer "F.Fab")
		)
		(fp_line
			(start -0.12065 -0.305054)
			(end -0.12065 -0.2794)
			(stroke
				(width 0.1)
				(type default)
			)
			(layer "F.Fab")
		)
		(fp_line
			(start -0.67945 0.3048)
			(end -0.67945 -0.305054)
			(stroke
				(width 0.1)
				(type default)
			)
			(layer "F.Fab")
		)
		(fp_line
			(start -0.67945 -0.305054)
			(end -0.12065 -0.305054)
			(stroke
				(width 0.1)
				(type default)
			)
			(layer "F.Fab")
		)
		(pad "1" smd circle
			(at -0.40005 0 180)
			(size 0 0)
			(layers "F.Cu" "F.Mask" "F.Paste")
			(net "PD_9543_FAN_A0")
		)
		(pad "2" smd circle
			(at 0.40005 0 180)
			(size 0 0)
			(layers "F.Cu" "F.Mask" "F.Paste")
			(net "GND")
		)
	)
	(footprint ""
		(layer "F.Cu")
		(at 278.6634 -75.184)
		(property "Reference" "PR31"
			(at 0 0 0)
			(layer "F.SilkS")
			(hide yes)
			(effects
				(font
					(size 1.27 1.27)
				)
			)
		)
		(property "Value" ""
			(at 0 0 0)
			(layer "F.Fab")
			(effects
				(font
					(size 1.27 1.27)
				)
			)
		)
		(duplicate_pad_numbers_are_jumpers no)
		(fp_line
			(start -0.7874 -0.4064)
			(end 0.7874 -0.4064)
			(stroke
				(width 0.1524)
				(type default)
			)
			(layer "F.SilkS")
		)
		(fp_line
			(start -0.7874 0.4064)
			(end -0.7874 -0.4064)
			(stroke
				(width 0.1524)
				(type default)
			)
			(layer "F.SilkS")
		)
		(fp_line
			(start 0.7874 -0.4064)
			(end 0.7874 0.4064)
			(stroke
				(width 0.1524)
				(type default)
			)
			(layer "F.SilkS")
		)
		(fp_line
			(start 0.7874 0.4064)
			(end -0.7874 0.4064)
			(stroke
				(width 0.1524)
				(type default)
			)
			(layer "F.SilkS")
		)
		(fp_line
			(start -0.67945 -0.305054)
			(end -0.12065 -0.305054)
			(stroke
				(width 0.1)
				(type default)
			)
			(layer "F.Fab")
		)
		(fp_line
			(start -0.67945 0.3048)
			(end -0.67945 -0.305054)
			(stroke
				(width 0.1)
				(type default)
			)
			(layer "F.Fab")
		)
		(fp_line
			(start -0.12065 -0.305054)
			(end -0.12065 -0.2794)
			(stroke
				(width 0.1)
				(type default)
			)
			(layer "F.Fab")
		)
		(fp_line
			(start -0.12065 -0.2794)
			(end 0.12065 -0.2794)
			(stroke
				(width 0.1)
				(type default)
			)
			(layer "F.Fab")
		)
		(fp_line
			(start -0.12065 0.2794)
			(end -0.12065 0.3048)
			(stroke
				(width 0.1)
				(type default)
			)
			(layer "F.Fab")
		)
		(fp_line
			(start -0.12065 0.3048)
			(end -0.67945 0.3048)
			(stroke
				(width 0.1)
				(type default)
			)
			(layer "F.Fab")
		)
		(fp_line
			(start 0.120396 0.2794)
			(end -0.12065 0.2794)
			(stroke
				(width 0.1)
				(type default)
			)
			(layer "F.Fab")
		)
		(fp_line
			(start 0.120396 0.3048)
			(end 0.120396 0.2794)
			(stroke
				(width 0.1)
				(type default)
			)
			(layer "F.Fab")
		)
		(fp_line
			(start 0.12065 -0.3048)
			(end 0.67945 -0.3048)
			(stroke
				(width 0.1)
				(type default)
			)
			(layer "F.Fab")
		)
		(fp_line
			(start 0.12065 -0.2794)
			(end 0.12065 -0.3048)
			(stroke
				(width 0.1)
				(type default)
			)
			(layer "F.Fab")
		)
		(fp_line
			(start 0.67945 -0.3048)
			(end 0.67945 0.3048)
			(stroke
				(width 0.1)
				(type default)
			)
			(layer "F.Fab")
		)
		(fp_line
			(start 0.67945 0.3048)
			(end 0.120396 0.3048)
			(stroke
				(width 0.1)
				(type default)
			)
			(layer "F.Fab")
		)
		(pad "1" smd circle
			(at -0.40005 0)
			(size 0 0)
			(layers "F.Cu" "F.Mask" "F.Paste")
			(net "P52V_HS1_EFAULT_R")
		)
		(pad "2" smd circle
			(at 0.40005 0)
			(size 0 0)
			(layers "F.Cu" "F.Mask" "F.Paste")
			(net "P52V_HS1_EFAULT")
		)
	)
	(footprint ""
		(layer "F.Cu")
		(at 438.3278 -23.749 180)
		(property "Reference" "R65"
			(at 0 0 180)
			(layer "F.SilkS")
			(hide yes)
			(effects
				(font
					(size 1.27 1.27)
				)
			)
		)
		(property "Value" ""
			(at 0 0 180)
			(layer "F.Fab")
			(effects
				(font
					(size 1.27 1.27)
				)
			)
		)
		(duplicate_pad_numbers_are_jumpers no)
		(fp_line
			(start 0.7874 0.4064)
			(end -0.7874 0.4064)
			(stroke
				(width 0.1524)
				(type default)
			)
			(layer "F.SilkS")
		)
		(fp_line
			(start 0.7874 -0.4064)
			(end 0.7874 0.4064)
			(stroke
				(width 0.1524)
				(type default)
			)
			(layer "F.SilkS")
		)
		(fp_line
			(start -0.7874 0.4064)
			(end -0.7874 -0.4064)
			(stroke
				(width 0.1524)
				(type default)
			)
			(layer "F.SilkS")
		)
		(fp_line
			(start -0.7874 -0.4064)
			(end 0.7874 -0.4064)
			(stroke
				(width 0.1524)
				(type default)
			)
			(layer "F.SilkS")
		)
		(fp_line
			(start 0.67945 0.3048)
			(end 0.120396 0.3048)
			(stroke
				(width 0.1)
				(type default)
			)
			(layer "F.Fab")
		)
		(fp_line
			(start 0.67945 -0.3048)
			(end 0.67945 0.3048)
			(stroke
				(width 0.1)
				(type default)
			)
			(layer "F.Fab")
		)
		(fp_line
			(start 0.12065 -0.2794)
			(end 0.12065 -0.3048)
			(stroke
				(width 0.1)
				(type default)
			)
			(layer "F.Fab")
		)
		(fp_line
			(start 0.12065 -0.3048)
			(end 0.67945 -0.3048)
			(stroke
				(width 0.1)
				(type default)
			)
			(layer "F.Fab")
		)
		(fp_line
			(start 0.120396 0.3048)
			(end 0.120396 0.2794)
			(stroke
				(width 0.1)
				(type default)
			)
			(layer "F.Fab")
		)
		(fp_line
			(start 0.120396 0.2794)
			(end -0.12065 0.2794)
			(stroke
				(width 0.1)
				(type default)
			)
			(layer "F.Fab")
		)
		(fp_line
			(start -0.12065 0.3048)
			(end -0.67945 0.3048)
			(stroke
				(width 0.1)
				(type default)
			)
			(layer "F.Fab")
		)
		(fp_line
			(start -0.12065 0.2794)
			(end -0.12065 0.3048)
			(stroke
				(width 0.1)
				(type default)
			)
			(layer "F.Fab")
		)
		(fp_line
			(start -0.12065 -0.2794)
			(end 0.12065 -0.2794)
			(stroke
				(width 0.1)
				(type default)
			)
			(layer "F.Fab")
		)
		(fp_line
			(start -0.12065 -0.305054)
			(end -0.12065 -0.2794)
			(stroke
				(width 0.1)
				(type default)
			)
			(layer "F.Fab")
		)
		(fp_line
			(start -0.67945 0.3048)
			(end -0.67945 -0.305054)
			(stroke
				(width 0.1)
				(type default)
			)
			(layer "F.Fab")
		)
		(fp_line
			(start -0.67945 -0.305054)
			(end -0.12065 -0.305054)
			(stroke
				(width 0.1)
				(type default)
			)
			(layer "F.Fab")
		)
		(pad "1" smd circle
			(at -0.40005 0 180)
			(size 0 0)
			(layers "F.Cu" "F.Mask" "F.Paste")
			(net "GND")
		)
		(pad "2" smd circle
			(at 0.40005 0 180)
			(size 0 0)
			(layers "F.Cu" "F.Mask" "F.Paste")
			(net "FRU_ADDR1")
		)
	)
	(footprint ""
		(layer "F.Cu")
		(at 160.274 -80.645 -90)
		(property "Reference" "R5906"
			(at 0 0 270)
			(layer "F.SilkS")
			(hide yes)
			(effects
				(font
					(size 1.27 1.27)
				)
			)
		)
		(property "Value" ""
			(at 0 0 270)
			(layer "F.Fab")
			(effects
				(font
					(size 1.27 1.27)
				)
			)
		)
		(duplicate_pad_numbers_are_jumpers no)
		(fp_line
			(start -1.651 0.8382)
			(end -1.651 -0.8382)
			(stroke
				(width 0.1524)
				(type default)
			)
			(layer "F.SilkS")
		)
		(fp_line
			(start 1.651 0.8382)
			(end -1.651 0.8382)
			(stroke
				(width 0.1524)
				(type default)
			)
			(layer "F.SilkS")
		)
		(fp_line
			(start -1.651 -0.8382)
			(end 1.651 -0.8382)
			(stroke
				(width 0.1524)
				(type default)
			)
			(layer "F.SilkS")
		)
		(fp_line
			(start 1.651 -0.8382)
			(end 1.651 0.8382)
			(stroke
				(width 0.1524)
				(type default)
			)
			(layer "F.SilkS")
		)
		(fp_line
			(start -1.559814 0.7366)
			(end -1.524 0.7366)
			(stroke
				(width 0.1)
				(type default)
			)
			(layer "F.Fab")
		)
		(fp_line
			(start -1.524 0.7366)
			(end 1.524 0.7366)
			(stroke
				(width 0.1)
				(type default)
			)
			(layer "F.Fab")
		)
		(fp_line
			(start 1.524 0.7366)
			(end 1.560576 0.7366)
			(stroke
				(width 0.1)
				(type default)
			)
			(layer "F.Fab")
		)
		(fp_line
			(start 1.560576 0.7366)
			(end 1.560576 -0.7366)
			(stroke
				(width 0.1)
				(type default)
			)
			(layer "F.Fab")
		)
		(fp_line
			(start -1.559814 -0.7366)
			(end -1.559814 0.7366)
			(stroke
				(width 0.1)
				(type default)
			)
			(layer "F.Fab")
		)
		(fp_line
			(start -1.524 -0.7366)
			(end -1.559814 -0.7366)
			(stroke
				(width 0.1)
				(type default)
			)
			(layer "F.Fab")
		)
		(fp_line
			(start 1.524 -0.7366)
			(end -1.524 -0.7366)
			(stroke
				(width 0.1)
				(type default)
			)
			(layer "F.Fab")
		)
		(fp_line
			(start 1.560576 -0.7366)
			(end 1.524 -0.7366)
			(stroke
				(width 0.1)
				(type default)
			)
			(layer "F.Fab")
		)
		(pad "1" smd rect
			(at -0.94996 0 90)
			(size 1.1176 1.3716)
			(layers "F.Cu" "F.Mask" "F.Paste")
			(net "P52V_2_BUSBAR")
		)
		(pad "2" smd rect
			(at 0.94996 0 90)
			(size 1.1176 1.3716)
			(layers "F.Cu" "F.Mask" "F.Paste")
			(net "FM_HS2_EN_BUSBAR")
		)
	)
	(footprint ""
		(layer "F.Cu")
		(at 33.85439 -36.957 180)
		(property "Reference" "R43"
			(at 0 0 180)
			(layer "F.SilkS")
			(hide yes)
			(effects
				(font
					(size 1.27 1.27)
				)
			)
		)
		(property "Value" ""
			(at 0 0 180)
			(layer "F.Fab")
			(effects
				(font
					(size 1.27 1.27)
				)
			)
		)
		(duplicate_pad_numbers_are_jumpers no)
		(fp_line
			(start 2.234946 0.9271)
			(end -2.234946 0.9271)
			(stroke
				(width 0.1524)
				(type default)
			)
			(layer "F.SilkS")
		)
		(fp_line
			(start 2.234946 -0.9271)
			(end 2.234946 0.9271)
			(stroke
				(width 0.1524)
				(type default)
			)
			(layer "F.SilkS")
		)
		(fp_line
			(start -2.234946 0.9271)
			(end -2.234946 -0.9271)
			(stroke
				(width 0.1524)
				(type default)
			)
			(layer "F.SilkS")
		)
		(fp_line
			(start -2.234946 -0.9271)
			(end 2.234946 -0.9271)
			(stroke
				(width 0.1524)
				(type default)
			)
			(layer "F.SilkS")
		)
		(fp_line
			(start 1.575054 0.824992)
			(end 1.575054 -0.824992)
			(stroke
				(width 0.1)
				(type default)
			)
			(layer "F.Fab")
		)
		(fp_line
			(start 1.575054 -0.824992)
			(end -1.575054 -0.824992)
			(stroke
				(width 0.1)
				(type default)
			)
			(layer "F.Fab")
		)
		(fp_line
			(start -1.575054 0.824992)
			(end 1.575054 0.824992)
			(stroke
				(width 0.1)
				(type default)
			)
			(layer "F.Fab")
		)
		(fp_line
			(start -1.575054 -0.824992)
			(end -1.575054 0.824992)
			(stroke
				(width 0.1)
				(type default)
			)
			(layer "F.Fab")
		)
		(pad "1" smd rect
			(at -1.599946 0 180)
			(size 1.016 1.6002)
			(layers "F.Cu" "F.Mask" "F.Paste")
			(net "LED_D2_R2")
		)
		(pad "2" smd rect
			(at 1.599946 0 180)
			(size 1.016 1.6002)
			(layers "F.Cu" "F.Mask" "F.Paste")
			(net "LED_D2_R3")
		)
	)
	(footprint ""
		(layer "F.Cu")
		(at 449.834 -50.927)
		(property "Reference" "R5914"
			(at 0 0 0)
			(layer "F.SilkS")
			(hide yes)
			(effects
				(font
					(size 1.27 1.27)
				)
			)
		)
		(property "Value" ""
			(at 0 0 0)
			(layer "F.Fab")
			(effects
				(font
					(size 1.27 1.27)
				)
			)
		)
		(duplicate_pad_numbers_are_jumpers no)
		(fp_line
			(start -0.7874 -0.4064)
			(end 0.7874 -0.4064)
			(stroke
				(width 0.1524)
				(type default)
			)
			(layer "F.SilkS")
		)
		(fp_line
			(start -0.7874 0.4064)
			(end -0.7874 -0.4064)
			(stroke
				(width 0.1524)
				(type default)
			)
			(layer "F.SilkS")
		)
		(fp_line
			(start 0.7874 -0.4064)
			(end 0.7874 0.4064)
			(stroke
				(width 0.1524)
				(type default)
			)
			(layer "F.SilkS")
		)
		(fp_line
			(start 0.7874 0.4064)
			(end -0.7874 0.4064)
			(stroke
				(width 0.1524)
				(type default)
			)
			(layer "F.SilkS")
		)
		(fp_line
			(start -0.67945 -0.305054)
			(end -0.12065 -0.305054)
			(stroke
				(width 0.1)
				(type default)
			)
			(layer "F.Fab")
		)
		(fp_line
			(start -0.67945 0.3048)
			(end -0.67945 -0.305054)
			(stroke
				(width 0.1)
				(type default)
			)
			(layer "F.Fab")
		)
		(fp_line
			(start -0.12065 -0.305054)
			(end -0.12065 -0.2794)
			(stroke
				(width 0.1)
				(type default)
			)
			(layer "F.Fab")
		)
		(fp_line
			(start -0.12065 -0.2794)
			(end 0.12065 -0.2794)
			(stroke
				(width 0.1)
				(type default)
			)
			(layer "F.Fab")
		)
		(fp_line
			(start -0.12065 0.2794)
			(end -0.12065 0.3048)
			(stroke
				(width 0.1)
				(type default)
			)
			(layer "F.Fab")
		)
		(fp_line
			(start -0.12065 0.3048)
			(end -0.67945 0.3048)
			(stroke
				(width 0.1)
				(type default)
			)
			(layer "F.Fab")
		)
		(fp_line
			(start 0.120396 0.2794)
			(end -0.12065 0.2794)
			(stroke
				(width 0.1)
				(type default)
			)
			(layer "F.Fab")
		)
		(fp_line
			(start 0.120396 0.3048)
			(end 0.120396 0.2794)
			(stroke
				(width 0.1)
				(type default)
			)
			(layer "F.Fab")
		)
		(fp_line
			(start 0.12065 -0.3048)
			(end 0.67945 -0.3048)
			(stroke
				(width 0.1)
				(type default)
			)
			(layer "F.Fab")
		)
		(fp_line
			(start 0.12065 -0.2794)
			(end 0.12065 -0.3048)
			(stroke
				(width 0.1)
				(type default)
			)
			(layer "F.Fab")
		)
		(fp_line
			(start 0.67945 -0.3048)
			(end 0.67945 0.3048)
			(stroke
				(width 0.1)
				(type default)
			)
			(layer "F.Fab")
		)
		(fp_line
			(start 0.67945 0.3048)
			(end 0.120396 0.3048)
			(stroke
				(width 0.1)
				(type default)
			)
			(layer "F.Fab")
		)
		(pad "1" smd circle
			(at -0.40005 0)
			(size 0 0)
			(layers "F.Cu" "F.Mask" "F.Paste")
			(net "P3V3_AUX")
		)
		(pad "2" smd circle
			(at 0.40005 0)
			(size 0 0)
			(layers "F.Cu" "F.Mask" "F.Paste")
			(net "PWRGD_P3V3_HPDB_R")
		)
	)
	(footprint ""
		(layer "F.Cu")
		(at 61.92139 -139.7)
		(property "Reference" "PC35"
			(at -8.93699 -4.41833 0)
			(unlocked yes)
			(layer "F.SilkS")
			(effects
				(font
					(size 0.7874 0.5842)
					(thickness 0.1524)
				)
				(justify left)
			)
		)
		(property "Value" ""
			(at 0 0 0)
			(layer "F.Fab")
			(effects
				(font
					(size 1.27 1.27)
				)
			)
		)
		(duplicate_pad_numbers_are_jumpers no)
		(fp_line
			(start -9.253728 3.750056)
			(end 9.249918 3.750056)
			(stroke
				(width 0.1524)
				(type default)
			)
			(layer "F.SilkS")
		)
		(fp_line
			(start 0 3.750056)
			(end -9.253728 3.750056)
			(stroke
				(width 0.1524)
				(type default)
			)
			(layer "F.SilkS")
		)
		(fp_circle
			(center 0 3.750056)
			(end 9.249918 3.750056)
			(stroke
				(width 0.1524)
				(type default)
			)
			(fill no)
			(layer "F.SilkS")
		)
		(fp_poly
			(pts
				(arc
					(start 9.249918 3.750056)
					(mid 0 12.999974)
					(end -9.249918 3.750056)
				)
			)
			(stroke
				(width 0)
				(type default)
			)
			(fill yes)
			(layer "F.SilkS")
		)
		(fp_circle
			(center 0 3.750056)
			(end 9.249918 3.750056)
			(stroke
				(width 0.1)
				(type default)
			)
			(fill no)
			(layer "F.Fab")
		)
		(pad "1" thru_hole rect
			(at 0 0)
			(size 1.778 1.778)
			(drill 1.27)
			(layers "*.Cu" "*.Mask")
			(remove_unused_layers no)
			(net "P52V_HS2")
			(clearance 0)
			(padstack
				(mode front_inner_back)
				(layer "Inner"
					(shape circle)
					(size 1.778 1.778)
					(clearance 0)
				)
				(layer "B.Cu"
					(shape rect)
					(size 1.778 1.778)
					(clearance 0)
				)
			)
		)
		(pad "2" thru_hole circle
			(at 0 7.500112)
			(size 1.778 1.778)
			(drill 1.27)
			(layers "*.Cu" "*.Mask")
			(remove_unused_layers no)
			(net "GND")
			(clearance 0)
		)
	)
	(footprint ""
		(layer "F.Cu")
		(at 61.92139 -78.74)
		(property "Reference" "PC45"
			(at -8.42899 -5.30733 0)
			(unlocked yes)
			(layer "F.SilkS")
			(effects
				(font
					(size 0.7874 0.5842)
					(thickness 0.1524)
				)
				(justify left)
			)
		)
		(property "Value" ""
			(at 0 0 0)
			(layer "F.Fab")
			(effects
				(font
					(size 1.27 1.27)
				)
			)
		)
		(duplicate_pad_numbers_are_jumpers no)
		(fp_line
			(start -9.253728 3.750056)
			(end 9.249918 3.750056)
			(stroke
				(width 0.1524)
				(type default)
			)
			(layer "F.SilkS")
		)
		(fp_line
			(start 0 3.750056)
			(end -9.253728 3.750056)
			(stroke
				(width 0.1524)
				(type default)
			)
			(layer "F.SilkS")
		)
		(fp_circle
			(center 0 3.750056)
			(end 9.249918 3.750056)
			(stroke
				(width 0.1524)
				(type default)
			)
			(fill no)
			(layer "F.SilkS")
		)
		(fp_poly
			(pts
				(arc
					(start 9.249918 3.750056)
					(mid 0 12.999974)
					(end -9.249918 3.750056)
				)
			)
			(stroke
				(width 0)
				(type default)
			)
			(fill yes)
			(layer "F.SilkS")
		)
		(fp_circle
			(center 0 3.750056)
			(end 9.249918 3.750056)
			(stroke
				(width 0.1)
				(type default)
			)
			(fill no)
			(layer "F.Fab")
		)
		(pad "1" thru_hole rect
			(at 0 0)
			(size 1.778 1.778)
			(drill 1.27)
			(layers "*.Cu" "*.Mask")
			(remove_unused_layers no)
			(net "P52V_HS2")
			(clearance 0)
			(padstack
				(mode front_inner_back)
				(layer "Inner"
					(shape circle)
					(size 1.778 1.778)
					(clearance 0)
				)
				(layer "B.Cu"
					(shape rect)
					(size 1.778 1.778)
					(clearance 0)
				)
			)
		)
		(pad "2" thru_hole circle
			(at 0 7.500112)
			(size 1.778 1.778)
			(drill 1.27)
			(layers "*.Cu" "*.Mask")
			(remove_unused_layers no)
			(net "GND")
			(clearance 0)
		)
	)
	(footprint ""
		(layer "F.Cu")
		(at 99.2632 -14.097 180)
		(property "Reference" "R162"
			(at 0 0 180)
			(layer "F.SilkS")
			(hide yes)
			(effects
				(font
					(size 1.27 1.27)
				)
			)
		)
		(property "Value" ""
			(at 0 0 180)
			(layer "F.Fab")
			(effects
				(font
					(size 1.27 1.27)
				)
			)
		)
		(duplicate_pad_numbers_are_jumpers no)
		(fp_line
			(start 1.651 0.8382)
			(end -1.651 0.8382)
			(stroke
				(width 0.1524)
				(type default)
			)
			(layer "F.SilkS")
		)
		(fp_line
			(start 1.651 -0.8382)
			(end 1.651 0.8382)
			(stroke
				(width 0.1524)
				(type default)
			)
			(layer "F.SilkS")
		)
		(fp_line
			(start -1.651 0.8382)
			(end -1.651 -0.8382)
			(stroke
				(width 0.1524)
				(type default)
			)
			(layer "F.SilkS")
		)
		(fp_line
			(start -1.651 -0.8382)
			(end 1.651 -0.8382)
			(stroke
				(width 0.1524)
				(type default)
			)
			(layer "F.SilkS")
		)
		(fp_line
			(start 1.560576 0.7366)
			(end 1.560576 -0.7366)
			(stroke
				(width 0.1)
				(type default)
			)
			(layer "F.Fab")
		)
		(fp_line
			(start 1.560576 -0.7366)
			(end 1.524 -0.7366)
			(stroke
				(width 0.1)
				(type default)
			)
			(layer "F.Fab")
		)
		(fp_line
			(start 1.524 0.7366)
			(end 1.560576 0.7366)
			(stroke
				(width 0.1)
				(type default)
			)
			(layer "F.Fab")
		)
		(fp_line
			(start 1.524 -0.7366)
			(end -1.524 -0.7366)
			(stroke
				(width 0.1)
				(type default)
			)
			(layer "F.Fab")
		)
		(fp_line
			(start -1.524 0.7366)
			(end 1.524 0.7366)
			(stroke
				(width 0.1)
				(type default)
			)
			(layer "F.Fab")
		)
		(fp_line
			(start -1.524 -0.7366)
			(end -1.559814 -0.7366)
			(stroke
				(width 0.1)
				(type default)
			)
			(layer "F.Fab")
		)
		(fp_line
			(start -1.559814 0.7366)
			(end -1.524 0.7366)
			(stroke
				(width 0.1)
				(type default)
			)
			(layer "F.Fab")
		)
		(fp_line
			(start -1.559814 -0.7366)
			(end -1.559814 0.7366)
			(stroke
				(width 0.1)
				(type default)
			)
			(layer "F.Fab")
		)
		(pad "1" smd rect
			(at -0.94996 0)
			(size 1.1176 1.3716)
			(layers "F.Cu" "F.Mask" "F.Paste")
			(net "P52V_HS2")
		)
		(pad "2" smd rect
			(at 0.94996 0)
			(size 1.1176 1.3716)
			(layers "F.Cu" "F.Mask" "F.Paste")
			(net "PWRGD_P52V_HS2_4287_PG_R_N")
		)
	)
	(footprint ""
		(layer "F.Cu")
		(at 450.4436 -90.5002 180)
		(property "Reference" "PR110"
			(at 0 0 180)
			(layer "F.SilkS")
			(hide yes)
			(effects
				(font
					(size 1.27 1.27)
				)
			)
		)
		(property "Value" ""
			(at 0 0 180)
			(layer "F.Fab")
			(effects
				(font
					(size 1.27 1.27)
				)
			)
		)
		(duplicate_pad_numbers_are_jumpers no)
		(fp_line
			(start 0.7874 0.4064)
			(end -0.7874 0.4064)
			(stroke
				(width 0.1524)
				(type default)
			)
			(layer "F.SilkS")
		)
		(fp_line
			(start 0.7874 -0.4064)
			(end 0.7874 0.4064)
			(stroke
				(width 0.1524)
				(type default)
			)
			(layer "F.SilkS")
		)
		(fp_line
			(start -0.7874 0.4064)
			(end -0.7874 -0.4064)
			(stroke
				(width 0.1524)
				(type default)
			)
			(layer "F.SilkS")
		)
		(fp_line
			(start -0.7874 -0.4064)
			(end 0.7874 -0.4064)
			(stroke
				(width 0.1524)
				(type default)
			)
			(layer "F.SilkS")
		)
		(fp_line
			(start 0.67945 0.3048)
			(end 0.120396 0.3048)
			(stroke
				(width 0.1)
				(type default)
			)
			(layer "F.Fab")
		)
		(fp_line
			(start 0.67945 -0.3048)
			(end 0.67945 0.3048)
			(stroke
				(width 0.1)
				(type default)
			)
			(layer "F.Fab")
		)
		(fp_line
			(start 0.12065 -0.2794)
			(end 0.12065 -0.3048)
			(stroke
				(width 0.1)
				(type default)
			)
			(layer "F.Fab")
		)
		(fp_line
			(start 0.12065 -0.3048)
			(end 0.67945 -0.3048)
			(stroke
				(width 0.1)
				(type default)
			)
			(layer "F.Fab")
		)
		(fp_line
			(start 0.120396 0.3048)
			(end 0.120396 0.2794)
			(stroke
				(width 0.1)
				(type default)
			)
			(layer "F.Fab")
		)
		(fp_line
			(start 0.120396 0.2794)
			(end -0.12065 0.2794)
			(stroke
				(width 0.1)
				(type default)
			)
			(layer "F.Fab")
		)
		(fp_line
			(start -0.12065 0.3048)
			(end -0.67945 0.3048)
			(stroke
				(width 0.1)
				(type default)
			)
			(layer "F.Fab")
		)
		(fp_line
			(start -0.12065 0.2794)
			(end -0.12065 0.3048)
			(stroke
				(width 0.1)
				(type default)
			)
			(layer "F.Fab")
		)
		(fp_line
			(start -0.12065 -0.2794)
			(end 0.12065 -0.2794)
			(stroke
				(width 0.1)
				(type default)
			)
			(layer "F.Fab")
		)
		(fp_line
			(start -0.12065 -0.305054)
			(end -0.12065 -0.2794)
			(stroke
				(width 0.1)
				(type default)
			)
			(layer "F.Fab")
		)
		(fp_line
			(start -0.67945 0.3048)
			(end -0.67945 -0.305054)
			(stroke
				(width 0.1)
				(type default)
			)
			(layer "F.Fab")
		)
		(fp_line
			(start -0.67945 -0.305054)
			(end -0.12065 -0.305054)
			(stroke
				(width 0.1)
				(type default)
			)
			(layer "F.Fab")
		)
		(pad "1" smd circle
			(at -0.40005 0 180)
			(size 0 0)
			(layers "F.Cu" "F.Mask" "F.Paste")
			(net "P3V3_AUX")
		)
		(pad "2" smd circle
			(at 0.40005 0 180)
			(size 0 0)
			(layers "F.Cu" "F.Mask" "F.Paste")
			(net "P3V3_HPDB_PG_R")
		)
	)
	(footprint ""
		(layer "F.Cu")
		(at 334.631284 -50.3428 -90)
		(property "Reference" "PR476"
			(at 0 0 270)
			(layer "F.SilkS")
			(hide yes)
			(effects
				(font
					(size 1.27 1.27)
				)
			)
		)
		(property "Value" ""
			(at 0 0 270)
			(layer "F.Fab")
			(effects
				(font
					(size 1.27 1.27)
				)
			)
		)
		(duplicate_pad_numbers_are_jumpers no)
		(fp_line
			(start -1.2954 0.5842)
			(end -1.2954 -0.5842)
			(stroke
				(width 0.1524)
				(type default)
			)
			(layer "F.SilkS")
		)
		(fp_line
			(start 1.2954 0.5842)
			(end -1.2954 0.5842)
			(stroke
				(width 0.1524)
				(type default)
			)
			(layer "F.SilkS")
		)
		(fp_line
			(start -1.2954 -0.5842)
			(end 1.2954 -0.5842)
			(stroke
				(width 0.1524)
				(type default)
			)
			(layer "F.SilkS")
		)
		(fp_line
			(start 1.2954 -0.5842)
			(end 1.2954 0.5842)
			(stroke
				(width 0.1524)
				(type default)
			)
			(layer "F.SilkS")
		)
		(fp_line
			(start -0.8636 0.4572)
			(end -0.8636 0.4318)
			(stroke
				(width 0.1)
				(type default)
			)
			(layer "F.Fab")
		)
		(fp_line
			(start 0.8636 0.4572)
			(end -0.8636 0.4572)
			(stroke
				(width 0.1)
				(type default)
			)
			(layer "F.Fab")
		)
		(fp_line
			(start -0.8636 0.4318)
			(end -0.8636 0.4064)
			(stroke
				(width 0.1)
				(type default)
			)
			(layer "F.Fab")
		)
		(fp_line
			(start -1.1938 0.4064)
			(end -1.1938 -0.406654)
			(stroke
				(width 0.1)
				(type default)
			)
			(layer "F.Fab")
		)
		(fp_line
			(start -0.8636 0.4064)
			(end -1.1938 0.4064)
			(stroke
				(width 0.1)
				(type default)
			)
			(layer "F.Fab")
		)
		(fp_line
			(start 0.8636 0.4064)
			(end 0.8636 0.4572)
			(stroke
				(width 0.1)
				(type default)
			)
			(layer "F.Fab")
		)
		(fp_line
			(start 1.1938 0.4064)
			(end 0.8636 0.4064)
			(stroke
				(width 0.1)
				(type default)
			)
			(layer "F.Fab")
		)
		(fp_line
			(start -1.1938 -0.406654)
			(end -0.8636 -0.406654)
			(stroke
				(width 0.1)
				(type default)
			)
			(layer "F.Fab")
		)
		(fp_line
			(start -0.8636 -0.406654)
			(end -0.8636 -0.4572)
			(stroke
				(width 0.1)
				(type default)
			)
			(layer "F.Fab")
		)
		(fp_line
			(start 0.8636 -0.406654)
			(end 1.1938 -0.406654)
			(stroke
				(width 0.1)
				(type default)
			)
			(layer "F.Fab")
		)
		(fp_line
			(start 1.1938 -0.406654)
			(end 1.1938 0.4064)
			(stroke
				(width 0.1)
				(type default)
			)
			(layer "F.Fab")
		)
		(fp_line
			(start -0.8636 -0.4572)
			(end 0.8636 -0.4572)
			(stroke
				(width 0.1)
				(type default)
			)
			(layer "F.Fab")
		)
		(fp_line
			(start 0.8636 -0.4572)
			(end 0.8636 -0.406654)
			(stroke
				(width 0.1)
				(type default)
			)
			(layer "F.Fab")
		)
		(pad "1" smd rect
			(at -0.7366 0 180)
			(size 0.7112 0.8128)
			(layers "F.Cu" "F.Mask" "F.Paste")
			(net "P52V_HS1_GATE1_R")
		)
		(pad "2" smd rect
			(at 0.7366 0 180)
			(size 0.7112 0.8128)
			(layers "F.Cu" "F.Mask" "F.Paste")
			(net "P52V_HS1_GATE3")
		)
	)
	(footprint ""
		(layer "F.Cu")
		(at 340.000336 -87.499952 180)
		(property "Reference" "H10"
			(at 0.910336 -5.484622 0)
			(unlocked yes)
			(layer "F.SilkS")
			(effects
				(font
					(size 0.7874 0.5842)
					(thickness 0.1524)
				)
				(justify left)
			)
		)
		(property "Value" ""
			(at 0 0 180)
			(layer "F.Fab")
			(effects
				(font
					(size 1.27 1.27)
				)
			)
		)
		(duplicate_pad_numbers_are_jumpers no)
		(pad "1" thru_hole oval
			(at 0 0 180)
			(size 9.017 14.0208)
			(drill 3.0226
				(offset 0 2.499868)
			)
			(layers "*.Cu" "*.Mask")
			(remove_unused_layers no)
			(net "GND")
			(clearance -1.500378)
			(padstack
				(mode front_inner_back)
				(layer "Inner"
					(shape circle)
					(size 0 0)
					(clearance 0)
				)
				(layer "B.Cu"
					(shape oval)
					(size 9.017 14.0208)
					(offset 0 2.499868)
					(clearance -1.500378)
				)
			)
		)
	)
	(footprint ""
		(layer "F.Cu")
		(at 419.93058 -32.75076 -90)
		(property "Reference" "R5917"
			(at 0 0 270)
			(layer "F.SilkS")
			(hide yes)
			(effects
				(font
					(size 1.27 1.27)
				)
			)
		)
		(property "Value" ""
			(at 0 0 270)
			(layer "F.Fab")
			(effects
				(font
					(size 1.27 1.27)
				)
			)
		)
		(duplicate_pad_numbers_are_jumpers no)
		(fp_line
			(start -0.7874 0.4064)
			(end -0.7874 -0.4064)
			(stroke
				(width 0.1524)
				(type default)
			)
			(layer "F.SilkS")
		)
		(fp_line
			(start 0.7874 0.4064)
			(end -0.7874 0.4064)
			(stroke
				(width 0.1524)
				(type default)
			)
			(layer "F.SilkS")
		)
		(fp_line
			(start -0.7874 -0.4064)
			(end 0.7874 -0.4064)
			(stroke
				(width 0.1524)
				(type default)
			)
			(layer "F.SilkS")
		)
		(fp_line
			(start 0.7874 -0.4064)
			(end 0.7874 0.4064)
			(stroke
				(width 0.1524)
				(type default)
			)
			(layer "F.SilkS")
		)
		(fp_line
			(start -0.67945 0.3048)
			(end -0.67945 -0.305054)
			(stroke
				(width 0.1)
				(type default)
			)
			(layer "F.Fab")
		)
		(fp_line
			(start -0.12065 0.3048)
			(end -0.67945 0.3048)
			(stroke
				(width 0.1)
				(type default)
			)
			(layer "F.Fab")
		)
		(fp_line
			(start 0.120396 0.3048)
			(end 0.120396 0.2794)
			(stroke
				(width 0.1)
				(type default)
			)
			(layer "F.Fab")
		)
		(fp_line
			(start 0.67945 0.3048)
			(end 0.120396 0.3048)
			(stroke
				(width 0.1)
				(type default)
			)
			(layer "F.Fab")
		)
		(fp_line
			(start -0.12065 0.2794)
			(end -0.12065 0.3048)
			(stroke
				(width 0.1)
				(type default)
			)
			(layer "F.Fab")
		)
		(fp_line
			(start 0.120396 0.2794)
			(end -0.12065 0.2794)
			(stroke
				(width 0.1)
				(type default)
			)
			(layer "F.Fab")
		)
		(fp_line
			(start -0.12065 -0.2794)
			(end 0.12065 -0.2794)
			(stroke
				(width 0.1)
				(type default)
			)
			(layer "F.Fab")
		)
		(fp_line
			(start 0.12065 -0.2794)
			(end 0.12065 -0.3048)
			(stroke
				(width 0.1)
				(type default)
			)
			(layer "F.Fab")
		)
		(fp_line
			(start 0.12065 -0.3048)
			(end 0.67945 -0.3048)
			(stroke
				(width 0.1)
				(type default)
			)
			(layer "F.Fab")
		)
		(fp_line
			(start 0.67945 -0.3048)
			(end 0.67945 0.3048)
			(stroke
				(width 0.1)
				(type default)
			)
			(layer "F.Fab")
		)
		(fp_line
			(start -0.67945 -0.305054)
			(end -0.12065 -0.305054)
			(stroke
				(width 0.1)
				(type default)
			)
			(layer "F.Fab")
		)
		(fp_line
			(start -0.12065 -0.305054)
			(end -0.12065 -0.2794)
			(stroke
				(width 0.1)
				(type default)
			)
			(layer "F.Fab")
		)
		(pad "1" smd circle
			(at -0.40005 0 270)
			(size 0 0)
			(layers "F.Cu" "F.Mask" "F.Paste")
			(net "P12V_LED_EN_BUF")
		)
		(pad "2" smd circle
			(at 0.40005 0 270)
			(size 0 0)
			(layers "F.Cu" "F.Mask" "F.Paste")
			(net "P12V_LED_EN_R")
		)
	)
	(footprint ""
		(layer "F.Cu")
		(at 449.199 -41.148 -90)
		(property "Reference" "R2"
			(at 0 0 270)
			(layer "F.SilkS")
			(hide yes)
			(effects
				(font
					(size 1.27 1.27)
				)
			)
		)
		(property "Value" ""
			(at 0 0 270)
			(layer "F.Fab")
			(effects
				(font
					(size 1.27 1.27)
				)
			)
		)
		(duplicate_pad_numbers_are_jumpers no)
		(fp_line
			(start -0.7874 0.4064)
			(end -0.7874 -0.4064)
			(stroke
				(width 0.1524)
				(type default)
			)
			(layer "F.SilkS")
		)
		(fp_line
			(start 0.7874 0.4064)
			(end -0.7874 0.4064)
			(stroke
				(width 0.1524)
				(type default)
			)
			(layer "F.SilkS")
		)
		(fp_line
			(start -0.7874 -0.4064)
			(end 0.7874 -0.4064)
			(stroke
				(width 0.1524)
				(type default)
			)
			(layer "F.SilkS")
		)
		(fp_line
			(start 0.7874 -0.4064)
			(end 0.7874 0.4064)
			(stroke
				(width 0.1524)
				(type default)
			)
			(layer "F.SilkS")
		)
		(fp_line
			(start -0.67945 0.3048)
			(end -0.67945 -0.305054)
			(stroke
				(width 0.1)
				(type default)
			)
			(layer "F.Fab")
		)
		(fp_line
			(start -0.12065 0.3048)
			(end -0.67945 0.3048)
			(stroke
				(width 0.1)
				(type default)
			)
			(layer "F.Fab")
		)
		(fp_line
			(start 0.120396 0.3048)
			(end 0.120396 0.2794)
			(stroke
				(width 0.1)
				(type default)
			)
			(layer "F.Fab")
		)
		(fp_line
			(start 0.67945 0.3048)
			(end 0.120396 0.3048)
			(stroke
				(width 0.1)
				(type default)
			)
			(layer "F.Fab")
		)
		(fp_line
			(start -0.12065 0.2794)
			(end -0.12065 0.3048)
			(stroke
				(width 0.1)
				(type default)
			)
			(layer "F.Fab")
		)
		(fp_line
			(start 0.120396 0.2794)
			(end -0.12065 0.2794)
			(stroke
				(width 0.1)
				(type default)
			)
			(layer "F.Fab")
		)
		(fp_line
			(start -0.12065 -0.2794)
			(end 0.12065 -0.2794)
			(stroke
				(width 0.1)
				(type default)
			)
			(layer "F.Fab")
		)
		(fp_line
			(start 0.12065 -0.2794)
			(end 0.12065 -0.3048)
			(stroke
				(width 0.1)
				(type default)
			)
			(layer "F.Fab")
		)
		(fp_line
			(start 0.12065 -0.3048)
			(end 0.67945 -0.3048)
			(stroke
				(width 0.1)
				(type default)
			)
			(layer "F.Fab")
		)
		(fp_line
			(start 0.67945 -0.3048)
			(end 0.67945 0.3048)
			(stroke
				(width 0.1)
				(type default)
			)
			(layer "F.Fab")
		)
		(fp_line
			(start -0.67945 -0.305054)
			(end -0.12065 -0.305054)
			(stroke
				(width 0.1)
				(type default)
			)
			(layer "F.Fab")
		)
		(fp_line
			(start -0.12065 -0.305054)
			(end -0.12065 -0.2794)
			(stroke
				(width 0.1)
				(type default)
			)
			(layer "F.Fab")
		)
		(pad "1" smd circle
			(at -0.40005 0 270)
			(size 0 0)
			(layers "F.Cu" "F.Mask" "F.Paste")
			(net "SMB_PDB_MISC_SDA_R")
		)
		(pad "2" smd circle
			(at 0.40005 0 270)
			(size 0 0)
			(layers "F.Cu" "F.Mask" "F.Paste")
			(net "P3V3_AUX")
		)
	)
	(footprint ""
		(layer "F.Cu")
		(at 42.36339 -78.74)
		(property "Reference" "PC44"
			(at 6.30301 -5.18033 0)
			(unlocked yes)
			(layer "F.SilkS")
			(effects
				(font
					(size 0.7874 0.5842)
					(thickness 0.1524)
				)
				(justify left)
			)
		)
		(property "Value" ""
			(at 0 0 0)
			(layer "F.Fab")
			(effects
				(font
					(size 1.27 1.27)
				)
			)
		)
		(duplicate_pad_numbers_are_jumpers no)
		(fp_line
			(start -9.253728 3.750056)
			(end 9.249918 3.750056)
			(stroke
				(width 0.1524)
				(type default)
			)
			(layer "F.SilkS")
		)
		(fp_line
			(start 0 3.750056)
			(end -9.253728 3.750056)
			(stroke
				(width 0.1524)
				(type default)
			)
			(layer "F.SilkS")
		)
		(fp_circle
			(center 0 3.750056)
			(end 9.249918 3.750056)
			(stroke
				(width 0.1524)
				(type default)
			)
			(fill no)
			(layer "F.SilkS")
		)
		(fp_poly
			(pts
				(arc
					(start 9.249918 3.750056)
					(mid 0 12.999974)
					(end -9.249918 3.750056)
				)
			)
			(stroke
				(width 0)
				(type default)
			)
			(fill yes)
			(layer "F.SilkS")
		)
		(fp_circle
			(center 0 3.750056)
			(end 9.249918 3.750056)
			(stroke
				(width 0.1)
				(type default)
			)
			(fill no)
			(layer "F.Fab")
		)
		(pad "1" thru_hole rect
			(at 0 0)
			(size 1.778 1.778)
			(drill 1.27)
			(layers "*.Cu" "*.Mask")
			(remove_unused_layers no)
			(net "P52V_HS2")
			(clearance 0)
			(padstack
				(mode front_inner_back)
				(layer "Inner"
					(shape circle)
					(size 1.778 1.778)
					(clearance 0)
				)
				(layer "B.Cu"
					(shape rect)
					(size 1.778 1.778)
					(clearance 0)
				)
			)
		)
		(pad "2" thru_hole circle
			(at 0 7.500112)
			(size 1.778 1.778)
			(drill 1.27)
			(layers "*.Cu" "*.Mask")
			(remove_unused_layers no)
			(net "GND")
			(clearance 0)
		)
	)
	(footprint ""
		(layer "F.Cu")
		(at 430.276 -44.577 180)
		(property "Reference" "R96"
			(at 0 0 180)
			(layer "F.SilkS")
			(hide yes)
			(effects
				(font
					(size 1.27 1.27)
				)
			)
		)
		(property "Value" ""
			(at 0 0 180)
			(layer "F.Fab")
			(effects
				(font
					(size 1.27 1.27)
				)
			)
		)
		(duplicate_pad_numbers_are_jumpers no)
		(fp_line
			(start 0.7874 0.4064)
			(end -0.7874 0.4064)
			(stroke
				(width 0.1524)
				(type default)
			)
			(layer "F.SilkS")
		)
		(fp_line
			(start 0.7874 -0.4064)
			(end 0.7874 0.4064)
			(stroke
				(width 0.1524)
				(type default)
			)
			(layer "F.SilkS")
		)
		(fp_line
			(start -0.7874 0.4064)
			(end -0.7874 -0.4064)
			(stroke
				(width 0.1524)
				(type default)
			)
			(layer "F.SilkS")
		)
		(fp_line
			(start -0.7874 -0.4064)
			(end 0.7874 -0.4064)
			(stroke
				(width 0.1524)
				(type default)
			)
			(layer "F.SilkS")
		)
		(fp_line
			(start 0.67945 0.3048)
			(end 0.120396 0.3048)
			(stroke
				(width 0.1)
				(type default)
			)
			(layer "F.Fab")
		)
		(fp_line
			(start 0.67945 -0.3048)
			(end 0.67945 0.3048)
			(stroke
				(width 0.1)
				(type default)
			)
			(layer "F.Fab")
		)
		(fp_line
			(start 0.12065 -0.2794)
			(end 0.12065 -0.3048)
			(stroke
				(width 0.1)
				(type default)
			)
			(layer "F.Fab")
		)
		(fp_line
			(start 0.12065 -0.3048)
			(end 0.67945 -0.3048)
			(stroke
				(width 0.1)
				(type default)
			)
			(layer "F.Fab")
		)
		(fp_line
			(start 0.120396 0.3048)
			(end 0.120396 0.2794)
			(stroke
				(width 0.1)
				(type default)
			)
			(layer "F.Fab")
		)
		(fp_line
			(start 0.120396 0.2794)
			(end -0.12065 0.2794)
			(stroke
				(width 0.1)
				(type default)
			)
			(layer "F.Fab")
		)
		(fp_line
			(start -0.12065 0.3048)
			(end -0.67945 0.3048)
			(stroke
				(width 0.1)
				(type default)
			)
			(layer "F.Fab")
		)
		(fp_line
			(start -0.12065 0.2794)
			(end -0.12065 0.3048)
			(stroke
				(width 0.1)
				(type default)
			)
			(layer "F.Fab")
		)
		(fp_line
			(start -0.12065 -0.2794)
			(end 0.12065 -0.2794)
			(stroke
				(width 0.1)
				(type default)
			)
			(layer "F.Fab")
		)
		(fp_line
			(start -0.12065 -0.305054)
			(end -0.12065 -0.2794)
			(stroke
				(width 0.1)
				(type default)
			)
			(layer "F.Fab")
		)
		(fp_line
			(start -0.67945 0.3048)
			(end -0.67945 -0.305054)
			(stroke
				(width 0.1)
				(type default)
			)
			(layer "F.Fab")
		)
		(fp_line
			(start -0.67945 -0.305054)
			(end -0.12065 -0.305054)
			(stroke
				(width 0.1)
				(type default)
			)
			(layer "F.Fab")
		)
		(pad "1" smd circle
			(at -0.40005 0 180)
			(size 0 0)
			(layers "F.Cu" "F.Mask" "F.Paste")
			(net "P3V3_AUX")
		)
		(pad "2" smd circle
			(at 0.40005 0 180)
			(size 0 0)
			(layers "F.Cu" "F.Mask" "F.Paste")
			(net "SKU_ID_2")
		)
	)
	(footprint ""
		(layer "F.Cu")
		(at 447.5734 -62.23 -90)
		(property "Reference" "PC50"
			(at 0 0 270)
			(layer "F.SilkS")
			(hide yes)
			(effects
				(font
					(size 1.27 1.27)
				)
			)
		)
		(property "Value" ""
			(at 0 0 270)
			(layer "F.Fab")
			(effects
				(font
					(size 1.27 1.27)
				)
			)
		)
		(duplicate_pad_numbers_are_jumpers no)
		(fp_line
			(start -1.524 0.762)
			(end -1.524 -0.762)
			(stroke
				(width 0.1524)
				(type default)
			)
			(layer "F.SilkS")
		)
		(fp_line
			(start 1.524 0.762)
			(end -1.524 0.762)
			(stroke
				(width 0.1524)
				(type default)
			)
			(layer "F.SilkS")
		)
		(fp_line
			(start -1.524 -0.762)
			(end 1.524 -0.762)
			(stroke
				(width 0.1524)
				(type default)
			)
			(layer "F.SilkS")
		)
		(fp_line
			(start 1.524 -0.762)
			(end 1.524 0.762)
			(stroke
				(width 0.1524)
				(type default)
			)
			(layer "F.SilkS")
		)
		(fp_line
			(start -1.1049 0.724916)
			(end 1.1049 0.724916)
			(stroke
				(width 0.1)
				(type default)
			)
			(layer "F.Fab")
		)
		(fp_line
			(start 1.1049 0.724916)
			(end 1.1049 -0.724916)
			(stroke
				(width 0.1)
				(type default)
			)
			(layer "F.Fab")
		)
		(fp_line
			(start -1.1049 -0.724916)
			(end -1.1049 0.724916)
			(stroke
				(width 0.1)
				(type default)
			)
			(layer "F.Fab")
		)
		(fp_line
			(start 1.1049 -0.724916)
			(end -1.1049 -0.724916)
			(stroke
				(width 0.1)
				(type default)
			)
			(layer "F.Fab")
		)
		(pad "1" smd rect
			(at -0.889 0 90)
			(size 1.016 1.27)
			(layers "F.Cu" "F.Mask" "F.Paste")
			(net "P3V3_AUX")
		)
		(pad "2" smd rect
			(at 0.889 0 90)
			(size 1.016 1.27)
			(layers "F.Cu" "F.Mask" "F.Paste")
			(net "GND")
		)
	)
	(footprint ""
		(layer "F.Cu")
		(at 124.483876 -29.5402)
		(property "Reference" "PQ42"
			(at 8.913114 -3.609848 0)
			(unlocked yes)
			(layer "F.SilkS")
			(effects
				(font
					(size 0.7874 0.5842)
					(thickness 0.1524)
				)
				(justify left)
			)
		)
		(property "Value" ""
			(at 0 0 0)
			(layer "F.Fab")
			(effects
				(font
					(size 1.27 1.27)
				)
			)
		)
		(duplicate_pad_numbers_are_jumpers no)
		(fp_line
			(start -7.649972 -4.99999)
			(end -7.649972 -3.3274)
			(stroke
				(width 0.1524)
				(type default)
			)
			(layer "F.SilkS")
		)
		(fp_line
			(start -7.649972 -1.7526)
			(end -7.649972 1.7526)
			(stroke
				(width 0.1524)
				(type default)
			)
			(layer "F.SilkS")
		)
		(fp_line
			(start -7.649972 3.3274)
			(end -7.649972 4.99999)
			(stroke
				(width 0.1524)
				(type default)
			)
			(layer "F.SilkS")
		)
		(fp_line
			(start -7.649972 4.99999)
			(end 5.115814 4.99999)
			(stroke
				(width 0.1524)
				(type default)
			)
			(layer "F.SilkS")
		)
		(fp_line
			(start 5.115814 -4.99999)
			(end -7.649972 -4.99999)
			(stroke
				(width 0.1524)
				(type default)
			)
			(layer "F.SilkS")
		)
		(fp_line
			(start 7.630414 4.99999)
			(end 7.649972 4.99999)
			(stroke
				(width 0.1524)
				(type default)
			)
			(layer "F.SilkS")
		)
		(fp_line
			(start 7.649972 -4.99999)
			(end 7.630414 -4.99999)
			(stroke
				(width 0.1524)
				(type default)
			)
			(layer "F.SilkS")
		)
		(fp_line
			(start 7.649972 4.99999)
			(end 7.649972 -4.99999)
			(stroke
				(width 0.1524)
				(type default)
			)
			(layer "F.SilkS")
		)
		(fp_line
			(start -7.649972 -4.99999)
			(end -7.649972 4.99999)
			(stroke
				(width 0.1)
				(type default)
			)
			(layer "F.Fab")
		)
		(fp_line
			(start -7.649972 4.99999)
			(end 7.649972 4.99999)
			(stroke
				(width 0.1)
				(type default)
			)
			(layer "F.Fab")
		)
		(fp_line
			(start 7.649972 -4.99999)
			(end -7.649972 -4.99999)
			(stroke
				(width 0.1)
				(type default)
			)
			(layer "F.Fab")
		)
		(fp_line
			(start 7.649972 4.99999)
			(end 7.649972 -4.99999)
			(stroke
				(width 0.1)
				(type default)
			)
			(layer "F.Fab")
		)
		(pad "D" smd circle
			(at 2.15011 0)
			(size 0 0)
			(layers "F.Cu" "F.Mask" "F.Paste")
			(net "P52V_HS2_DRAIN_2")
		)
		(pad "G" smd rect
			(at -7.050024 -2.54 270)
			(size 1.3208 3.0988)
			(layers "F.Cu" "F.Mask" "F.Paste")
			(net "P52V_HS2_GATE5")
		)
		(pad "S" smd rect
			(at -7.050024 2.54 270)
			(size 1.3208 3.0988)
			(layers "F.Cu" "F.Mask" "F.Paste")
			(net "P52V_HS2")
		)
		(zone
			(layer "F.Cu")
			(hatch none 0.5)
			(connect_pads
				(clearance 0)
			)
			(min_thickness 0.25)
			(keepout
				(tracks not_allowed)
				(vias allowed)
				(pads allowed)
				(copperpour not_allowed)
				(footprints allowed)
			)
			(placement
				(enabled no)
				(sheetname "")
			)
			(fill
				(thermal_gap 0.5)
				(thermal_bridge_width 0.5)
				(island_removal_mode 0)
			)
			(polygon
				(pts
					(xy 129.665476 -34.5186) (xy 116.838476 -34.5186) (xy 116.838476 -32.7914) (xy 119.048276 -32.7914)
					(xy 119.048276 -31.369) (xy 116.838476 -31.369) (xy 116.838476 -27.7114) (xy 119.048276 -27.7114)
					(xy 119.048276 -26.289) (xy 116.838476 -26.289) (xy 116.838476 -24.5618) (xy 129.665476 -24.5618)
					(xy 129.665476 -25.7302) (xy 123.467876 -25.7302) (xy 123.467876 -33.3502) (xy 129.665476 -33.3502)
				)
			)
		)
	)
	(footprint ""
		(layer "F.Cu")
		(at 390.017 -28.575)
		(property "Reference" "PQ17"
			(at -4.03733 3.048 90)
			(unlocked yes)
			(layer "F.SilkS")
			(effects
				(font
					(size 0.7874 0.5842)
					(thickness 0.1524)
				)
				(justify left)
			)
		)
		(property "Value" ""
			(at 0 0 0)
			(layer "F.Fab")
			(effects
				(font
					(size 1.27 1.27)
				)
			)
		)
		(duplicate_pad_numbers_are_jumpers no)
		(fp_line
			(start -1.905 -1.651)
			(end 1.905 -1.651)
			(stroke
				(width 0.1524)
				(type default)
			)
			(layer "F.SilkS")
		)
		(fp_line
			(start -1.905 1.651)
			(end -1.905 -1.651)
			(stroke
				(width 0.1524)
				(type default)
			)
			(layer "F.SilkS")
		)
		(fp_line
			(start 1.905 -1.651)
			(end 1.905 1.651)
			(stroke
				(width 0.1524)
				(type default)
			)
			(layer "F.SilkS")
		)
		(fp_line
			(start 1.905 1.651)
			(end -1.905 1.651)
			(stroke
				(width 0.1524)
				(type default)
			)
			(layer "F.SilkS")
		)
		(fp_line
			(start -1.249934 -1.169924)
			(end -0.649986 -1.169924)
			(stroke
				(width 0.1)
				(type default)
			)
			(layer "F.Fab")
		)
		(fp_line
			(start -1.249934 -0.729996)
			(end -1.249934 -1.169924)
			(stroke
				(width 0.1)
				(type default)
			)
			(layer "F.Fab")
		)
		(fp_line
			(start -1.249934 0.729996)
			(end -0.6985 0.729996)
			(stroke
				(width 0.1)
				(type default)
			)
			(layer "F.Fab")
		)
		(fp_line
			(start -1.249934 1.169924)
			(end -1.249934 0.729996)
			(stroke
				(width 0.1)
				(type default)
			)
			(layer "F.Fab")
		)
		(fp_line
			(start -0.6985 -0.729996)
			(end -1.249934 -0.729996)
			(stroke
				(width 0.1)
				(type default)
			)
			(layer "F.Fab")
		)
		(fp_line
			(start -0.6985 0.729996)
			(end -0.6985 -0.729996)
			(stroke
				(width 0.1)
				(type default)
			)
			(layer "F.Fab")
		)
		(fp_line
			(start -0.649986 -1.524)
			(end 0.6985 -1.524)
			(stroke
				(width 0.1)
				(type default)
			)
			(layer "F.Fab")
		)
		(fp_line
			(start -0.649986 -1.169924)
			(end -0.649986 -1.524)
			(stroke
				(width 0.1)
				(type default)
			)
			(layer "F.Fab")
		)
		(fp_line
			(start -0.649986 1.169924)
			(end -1.249934 1.169924)
			(stroke
				(width 0.1)
				(type default)
			)
			(layer "F.Fab")
		)
		(fp_line
			(start -0.649986 1.524)
			(end -0.649986 1.169924)
			(stroke
				(width 0.1)
				(type default)
			)
			(layer "F.Fab")
		)
		(fp_line
			(start 0.6985 -1.524)
			(end 0.6985 -0.219964)
			(stroke
				(width 0.1)
				(type default)
			)
			(layer "F.Fab")
		)
		(fp_line
			(start 0.6985 -0.219964)
			(end 1.249934 -0.219964)
			(stroke
				(width 0.1)
				(type default)
			)
			(layer "F.Fab")
		)
		(fp_line
			(start 0.6985 0.219964)
			(end 0.6985 1.524)
			(stroke
				(width 0.1)
				(type default)
			)
			(layer "F.Fab")
		)
		(fp_line
			(start 0.6985 1.524)
			(end -0.649986 1.524)
			(stroke
				(width 0.1)
				(type default)
			)
			(layer "F.Fab")
		)
		(fp_line
			(start 1.249934 -0.219964)
			(end 1.249934 0.219964)
			(stroke
				(width 0.1)
				(type default)
			)
			(layer "F.Fab")
		)
		(fp_line
			(start 1.249934 0.219964)
			(end 0.6985 0.219964)
			(stroke
				(width 0.1)
				(type default)
			)
			(layer "F.Fab")
		)
		(pad "B" smd rect
			(at -1.1176 -1.016 270)
			(size 1.016 1.27)
			(layers "F.Cu" "F.Mask" "F.Paste")
			(net "P52V_HS1_EN_DISCHARGE_VBE")
		)
		(pad "C" smd rect
			(at 1.1176 0 270)
			(size 1.016 1.27)
			(layers "F.Cu" "F.Mask" "F.Paste")
			(net "P52V_HS1_EN_DISCHARGE_N")
		)
		(pad "E" smd rect
			(at -1.1176 1.016 270)
			(size 1.016 1.27)
			(layers "F.Cu" "F.Mask" "F.Paste")
			(net "GND")
		)
	)
	(footprint ""
		(layer "F.Cu")
		(at 164.973 -65.786 90)
		(property "Reference" "PC615"
			(at 0 0 90)
			(layer "F.SilkS")
			(hide yes)
			(effects
				(font
					(size 1.27 1.27)
				)
			)
		)
		(property "Value" ""
			(at 0 0 90)
			(layer "F.Fab")
			(effects
				(font
					(size 1.27 1.27)
				)
			)
		)
		(duplicate_pad_numbers_are_jumpers no)
		(fp_line
			(start 0.7874 -0.4064)
			(end 0.7874 0.4064)
			(stroke
				(width 0.1524)
				(type default)
			)
			(layer "F.SilkS")
		)
		(fp_line
			(start -0.7874 -0.4064)
			(end 0.7874 -0.4064)
			(stroke
				(width 0.1524)
				(type default)
			)
			(layer "F.SilkS")
		)
		(fp_line
			(start 0.7874 0.4064)
			(end -0.7874 0.4064)
			(stroke
				(width 0.1524)
				(type default)
			)
			(layer "F.SilkS")
		)
		(fp_line
			(start -0.7874 0.4064)
			(end -0.7874 -0.4064)
			(stroke
				(width 0.1524)
				(type default)
			)
			(layer "F.SilkS")
		)
		(fp_line
			(start -0.12065 -0.305054)
			(end -0.12065 -0.2794)
			(stroke
				(width 0.1)
				(type default)
			)
			(layer "F.Fab")
		)
		(fp_line
			(start -0.67945 -0.305054)
			(end -0.12065 -0.305054)
			(stroke
				(width 0.1)
				(type default)
			)
			(layer "F.Fab")
		)
		(fp_line
			(start 0.67945 -0.3048)
			(end 0.67945 0.3048)
			(stroke
				(width 0.1)
				(type default)
			)
			(layer "F.Fab")
		)
		(fp_line
			(start 0.12065 -0.3048)
			(end 0.67945 -0.3048)
			(stroke
				(width 0.1)
				(type default)
			)
			(layer "F.Fab")
		)
		(fp_line
			(start 0.12065 -0.2794)
			(end 0.12065 -0.3048)
			(stroke
				(width 0.1)
				(type default)
			)
			(layer "F.Fab")
		)
		(fp_line
			(start -0.12065 -0.2794)
			(end 0.12065 -0.2794)
			(stroke
				(width 0.1)
				(type default)
			)
			(layer "F.Fab")
		)
		(fp_line
			(start 0.120396 0.2794)
			(end -0.12065 0.2794)
			(stroke
				(width 0.1)
				(type default)
			)
			(layer "F.Fab")
		)
		(fp_line
			(start -0.12065 0.2794)
			(end -0.12065 0.3048)
			(stroke
				(width 0.1)
				(type default)
			)
			(layer "F.Fab")
		)
		(fp_line
			(start 0.67945 0.3048)
			(end 0.120396 0.3048)
			(stroke
				(width 0.1)
				(type default)
			)
			(layer "F.Fab")
		)
		(fp_line
			(start 0.120396 0.3048)
			(end 0.120396 0.2794)
			(stroke
				(width 0.1)
				(type default)
			)
			(layer "F.Fab")
		)
		(fp_line
			(start -0.12065 0.3048)
			(end -0.67945 0.3048)
			(stroke
				(width 0.1)
				(type default)
			)
			(layer "F.Fab")
		)
		(fp_line
			(start -0.67945 0.3048)
			(end -0.67945 -0.305054)
			(stroke
				(width 0.1)
				(type default)
			)
			(layer "F.Fab")
		)
		(pad "1" smd circle
			(at -0.40005 0 90)
			(size 0 0)
			(layers "F.Cu" "F.Mask" "F.Paste")
			(net "P52V_HS2_EFAULT")
		)
		(pad "2" smd circle
			(at 0.40005 0 90)
			(size 0 0)
			(layers "F.Cu" "F.Mask" "F.Paste")
			(net "GND1_FIELD_SIGNAL")
		)
	)
	(footprint ""
		(layer "F.Cu")
		(at 433.451 -32.893 180)
		(property "Reference" "R24"
			(at 0 0 180)
			(layer "F.SilkS")
			(hide yes)
			(effects
				(font
					(size 1.27 1.27)
				)
			)
		)
		(property "Value" ""
			(at 0 0 180)
			(layer "F.Fab")
			(effects
				(font
					(size 1.27 1.27)
				)
			)
		)
		(duplicate_pad_numbers_are_jumpers no)
		(fp_line
			(start 0.7874 0.4064)
			(end -0.7874 0.4064)
			(stroke
				(width 0.1524)
				(type default)
			)
			(layer "F.SilkS")
		)
		(fp_line
			(start 0.7874 -0.4064)
			(end 0.7874 0.4064)
			(stroke
				(width 0.1524)
				(type default)
			)
			(layer "F.SilkS")
		)
		(fp_line
			(start -0.7874 0.4064)
			(end -0.7874 -0.4064)
			(stroke
				(width 0.1524)
				(type default)
			)
			(layer "F.SilkS")
		)
		(fp_line
			(start -0.7874 -0.4064)
			(end 0.7874 -0.4064)
			(stroke
				(width 0.1524)
				(type default)
			)
			(layer "F.SilkS")
		)
		(fp_line
			(start 0.67945 0.3048)
			(end 0.120396 0.3048)
			(stroke
				(width 0.1)
				(type default)
			)
			(layer "F.Fab")
		)
		(fp_line
			(start 0.67945 -0.3048)
			(end 0.67945 0.3048)
			(stroke
				(width 0.1)
				(type default)
			)
			(layer "F.Fab")
		)
		(fp_line
			(start 0.12065 -0.2794)
			(end 0.12065 -0.3048)
			(stroke
				(width 0.1)
				(type default)
			)
			(layer "F.Fab")
		)
		(fp_line
			(start 0.12065 -0.3048)
			(end 0.67945 -0.3048)
			(stroke
				(width 0.1)
				(type default)
			)
			(layer "F.Fab")
		)
		(fp_line
			(start 0.120396 0.3048)
			(end 0.120396 0.2794)
			(stroke
				(width 0.1)
				(type default)
			)
			(layer "F.Fab")
		)
		(fp_line
			(start 0.120396 0.2794)
			(end -0.12065 0.2794)
			(stroke
				(width 0.1)
				(type default)
			)
			(layer "F.Fab")
		)
		(fp_line
			(start -0.12065 0.3048)
			(end -0.67945 0.3048)
			(stroke
				(width 0.1)
				(type default)
			)
			(layer "F.Fab")
		)
		(fp_line
			(start -0.12065 0.2794)
			(end -0.12065 0.3048)
			(stroke
				(width 0.1)
				(type default)
			)
			(layer "F.Fab")
		)
		(fp_line
			(start -0.12065 -0.2794)
			(end 0.12065 -0.2794)
			(stroke
				(width 0.1)
				(type default)
			)
			(layer "F.Fab")
		)
		(fp_line
			(start -0.12065 -0.305054)
			(end -0.12065 -0.2794)
			(stroke
				(width 0.1)
				(type default)
			)
			(layer "F.Fab")
		)
		(fp_line
			(start -0.67945 0.3048)
			(end -0.67945 -0.305054)
			(stroke
				(width 0.1)
				(type default)
			)
			(layer "F.Fab")
		)
		(fp_line
			(start -0.67945 -0.305054)
			(end -0.12065 -0.305054)
			(stroke
				(width 0.1)
				(type default)
			)
			(layer "F.Fab")
		)
		(pad "1" smd circle
			(at -0.40005 0 180)
			(size 0 0)
			(layers "F.Cu" "F.Mask" "F.Paste")
			(net "PD_9543_FAN_A1")
		)
		(pad "2" smd circle
			(at 0.40005 0 180)
			(size 0 0)
			(layers "F.Cu" "F.Mask" "F.Paste")
			(net "GND")
		)
	)
	(footprint ""
		(layer "F.Cu")
		(at 360.000296 -142.499842 180)
		(property "Reference" "H11"
			(at 0.844296 -6.509512 0)
			(unlocked yes)
			(layer "F.SilkS")
			(effects
				(font
					(size 0.7874 0.5842)
					(thickness 0.1524)
				)
				(justify left)
			)
		)
		(property "Value" ""
			(at 0 0 180)
			(layer "F.Fab")
			(effects
				(font
					(size 1.27 1.27)
				)
			)
		)
		(duplicate_pad_numbers_are_jumpers no)
		(pad "1" thru_hole oval
			(at 0 0 180)
			(size 9.017 14.0208)
			(drill 3.0226
				(offset 0 2.499868)
			)
			(layers "*.Cu" "*.Mask")
			(remove_unused_layers no)
			(net "GND")
			(clearance -1.500378)
			(padstack
				(mode front_inner_back)
				(layer "Inner"
					(shape circle)
					(size 0 0)
					(clearance 0)
				)
				(layer "B.Cu"
					(shape oval)
					(size 9.017 14.0208)
					(offset 0 2.499868)
					(clearance -1.500378)
				)
			)
		)
	)
	(footprint ""
		(layer "F.Cu")
		(at 411.72384 -27.852878 90)
		(property "Reference" "R5921"
			(at 0 0 90)
			(layer "F.SilkS")
			(hide yes)
			(effects
				(font
					(size 1.27 1.27)
				)
			)
		)
		(property "Value" ""
			(at 0 0 90)
			(layer "F.Fab")
			(effects
				(font
					(size 1.27 1.27)
				)
			)
		)
		(duplicate_pad_numbers_are_jumpers no)
		(fp_line
			(start 0.7874 -0.4064)
			(end 0.7874 0.4064)
			(stroke
				(width 0.1524)
				(type default)
			)
			(layer "F.SilkS")
		)
		(fp_line
			(start -0.7874 -0.4064)
			(end 0.7874 -0.4064)
			(stroke
				(width 0.1524)
				(type default)
			)
			(layer "F.SilkS")
		)
		(fp_line
			(start 0.7874 0.4064)
			(end -0.7874 0.4064)
			(stroke
				(width 0.1524)
				(type default)
			)
			(layer "F.SilkS")
		)
		(fp_line
			(start -0.7874 0.4064)
			(end -0.7874 -0.4064)
			(stroke
				(width 0.1524)
				(type default)
			)
			(layer "F.SilkS")
		)
		(fp_line
			(start -0.12065 -0.305054)
			(end -0.12065 -0.2794)
			(stroke
				(width 0.1)
				(type default)
			)
			(layer "F.Fab")
		)
		(fp_line
			(start -0.67945 -0.305054)
			(end -0.12065 -0.305054)
			(stroke
				(width 0.1)
				(type default)
			)
			(layer "F.Fab")
		)
		(fp_line
			(start 0.67945 -0.3048)
			(end 0.67945 0.3048)
			(stroke
				(width 0.1)
				(type default)
			)
			(layer "F.Fab")
		)
		(fp_line
			(start 0.12065 -0.3048)
			(end 0.67945 -0.3048)
			(stroke
				(width 0.1)
				(type default)
			)
			(layer "F.Fab")
		)
		(fp_line
			(start 0.12065 -0.2794)
			(end 0.12065 -0.3048)
			(stroke
				(width 0.1)
				(type default)
			)
			(layer "F.Fab")
		)
		(fp_line
			(start -0.12065 -0.2794)
			(end 0.12065 -0.2794)
			(stroke
				(width 0.1)
				(type default)
			)
			(layer "F.Fab")
		)
		(fp_line
			(start 0.120396 0.2794)
			(end -0.12065 0.2794)
			(stroke
				(width 0.1)
				(type default)
			)
			(layer "F.Fab")
		)
		(fp_line
			(start -0.12065 0.2794)
			(end -0.12065 0.3048)
			(stroke
				(width 0.1)
				(type default)
			)
			(layer "F.Fab")
		)
		(fp_line
			(start 0.67945 0.3048)
			(end 0.120396 0.3048)
			(stroke
				(width 0.1)
				(type default)
			)
			(layer "F.Fab")
		)
		(fp_line
			(start 0.120396 0.3048)
			(end 0.120396 0.2794)
			(stroke
				(width 0.1)
				(type default)
			)
			(layer "F.Fab")
		)
		(fp_line
			(start -0.12065 0.3048)
			(end -0.67945 0.3048)
			(stroke
				(width 0.1)
				(type default)
			)
			(layer "F.Fab")
		)
		(fp_line
			(start -0.67945 0.3048)
			(end -0.67945 -0.305054)
			(stroke
				(width 0.1)
				(type default)
			)
			(layer "F.Fab")
		)
		(pad "1" smd rect
			(at -0.40005 0 270)
			(size 0.4572 0.508)
			(layers "F.Cu" "F.Mask" "F.Paste")
			(net "P12V_FAN_LED")
		)
		(pad "2" smd rect
			(at 0.40005 0 270)
			(size 0.4572 0.508)
			(layers "F.Cu" "F.Mask" "F.Paste")
			(net "P12V_LED_FB")
		)
	)
	(footprint ""
		(layer "F.Cu")
		(at 414.9344 -36.068)
		(property "Reference" "R423"
			(at 0 0 0)
			(layer "F.SilkS")
			(hide yes)
			(effects
				(font
					(size 1.27 1.27)
				)
			)
		)
		(property "Value" ""
			(at 0 0 0)
			(layer "F.Fab")
			(effects
				(font
					(size 1.27 1.27)
				)
			)
		)
		(duplicate_pad_numbers_are_jumpers no)
		(fp_line
			(start -0.7874 -0.4064)
			(end 0.7874 -0.4064)
			(stroke
				(width 0.1524)
				(type default)
			)
			(layer "F.SilkS")
		)
		(fp_line
			(start -0.7874 0.4064)
			(end -0.7874 -0.4064)
			(stroke
				(width 0.1524)
				(type default)
			)
			(layer "F.SilkS")
		)
		(fp_line
			(start 0.7874 -0.4064)
			(end 0.7874 0.4064)
			(stroke
				(width 0.1524)
				(type default)
			)
			(layer "F.SilkS")
		)
		(fp_line
			(start 0.7874 0.4064)
			(end -0.7874 0.4064)
			(stroke
				(width 0.1524)
				(type default)
			)
			(layer "F.SilkS")
		)
		(fp_line
			(start -0.67945 -0.305054)
			(end -0.12065 -0.305054)
			(stroke
				(width 0.1)
				(type default)
			)
			(layer "F.Fab")
		)
		(fp_line
			(start -0.67945 0.3048)
			(end -0.67945 -0.305054)
			(stroke
				(width 0.1)
				(type default)
			)
			(layer "F.Fab")
		)
		(fp_line
			(start -0.12065 -0.305054)
			(end -0.12065 -0.2794)
			(stroke
				(width 0.1)
				(type default)
			)
			(layer "F.Fab")
		)
		(fp_line
			(start -0.12065 -0.2794)
			(end 0.12065 -0.2794)
			(stroke
				(width 0.1)
				(type default)
			)
			(layer "F.Fab")
		)
		(fp_line
			(start -0.12065 0.2794)
			(end -0.12065 0.3048)
			(stroke
				(width 0.1)
				(type default)
			)
			(layer "F.Fab")
		)
		(fp_line
			(start -0.12065 0.3048)
			(end -0.67945 0.3048)
			(stroke
				(width 0.1)
				(type default)
			)
			(layer "F.Fab")
		)
		(fp_line
			(start 0.120396 0.2794)
			(end -0.12065 0.2794)
			(stroke
				(width 0.1)
				(type default)
			)
			(layer "F.Fab")
		)
		(fp_line
			(start 0.120396 0.3048)
			(end 0.120396 0.2794)
			(stroke
				(width 0.1)
				(type default)
			)
			(layer "F.Fab")
		)
		(fp_line
			(start 0.12065 -0.3048)
			(end 0.67945 -0.3048)
			(stroke
				(width 0.1)
				(type default)
			)
			(layer "F.Fab")
		)
		(fp_line
			(start 0.12065 -0.2794)
			(end 0.12065 -0.3048)
			(stroke
				(width 0.1)
				(type default)
			)
			(layer "F.Fab")
		)
		(fp_line
			(start 0.67945 -0.3048)
			(end 0.67945 0.3048)
			(stroke
				(width 0.1)
				(type default)
			)
			(layer "F.Fab")
		)
		(fp_line
			(start 0.67945 0.3048)
			(end 0.120396 0.3048)
			(stroke
				(width 0.1)
				(type default)
			)
			(layer "F.Fab")
		)
		(pad "1" smd circle
			(at -0.40005 0)
			(size 0 0)
			(layers "F.Cu" "F.Mask" "F.Paste")
			(net "PWRGD_P52V_HS2_4287_PG")
		)
		(pad "2" smd circle
			(at 0.40005 0)
			(size 0 0)
			(layers "F.Cu" "F.Mask" "F.Paste")
			(net "PWRGD_P52V_HS2_PG")
		)
	)
	(footprint ""
		(layer "F.Cu")
		(at 143.003778 -63.373 180)
		(property "Reference" "PR6976"
			(at 0.458978 -4.48437 0)
			(unlocked yes)
			(layer "F.SilkS")
			(effects
				(font
					(size 0.7874 0.5842)
					(thickness 0.1524)
				)
				(justify left)
			)
		)
		(property "Value" ""
			(at 0 0 180)
			(layer "F.Fab")
			(effects
				(font
					(size 1.27 1.27)
				)
			)
		)
		(duplicate_pad_numbers_are_jumpers no)
		(fp_line
			(start 3.9878 3.5814)
			(end -3.9878 3.5814)
			(stroke
				(width 0.1524)
				(type default)
			)
			(layer "F.SilkS")
		)
		(fp_line
			(start 3.9878 -3.5814)
			(end 3.9878 3.5814)
			(stroke
				(width 0.1524)
				(type default)
			)
			(layer "F.SilkS")
		)
		(fp_line
			(start -3.9878 3.5814)
			(end -3.9878 -3.5814)
			(stroke
				(width 0.1524)
				(type default)
			)
			(layer "F.SilkS")
		)
		(fp_line
			(start -3.9878 -3.5814)
			(end 3.9878 -3.5814)
			(stroke
				(width 0.1524)
				(type default)
			)
			(layer "F.SilkS")
		)
		(fp_line
			(start 3.5306 3.353054)
			(end -3.5306 3.353054)
			(stroke
				(width 0.1)
				(type default)
			)
			(layer "F.Fab")
		)
		(fp_line
			(start 3.5306 -3.353054)
			(end 3.5306 3.353054)
			(stroke
				(width 0.1)
				(type default)
			)
			(layer "F.Fab")
		)
		(fp_line
			(start -3.5306 3.353054)
			(end -3.5306 -3.353054)
			(stroke
				(width 0.1)
				(type default)
			)
			(layer "F.Fab")
		)
		(fp_line
			(start -3.5306 -3.353054)
			(end 3.5306 -3.353054)
			(stroke
				(width 0.1)
				(type default)
			)
			(layer "F.Fab")
		)
		(pad "1A" smd rect
			(at -2.249932 0)
			(size 3.2004 6.858)
			(layers "F.Cu" "F.Mask" "F.Paste")
			(net "P52V_2")
		)
		(pad "1B" smd rect
			(at -0.776732 0 180)
			(size 0.254 0.508)
			(layers "F.Cu" "F.Mask" "F.Paste")
			(net "P52V_HS2_SENSE_P_R1")
		)
		(pad "2A" smd rect
			(at 2.249932 0)
			(size 3.2004 6.858)
			(layers "F.Cu" "F.Mask" "F.Paste")
			(net "P52V_HS2_DRAIN_1")
		)
		(pad "2B" smd rect
			(at 0.776732 0 180)
			(size 0.254 0.508)
			(layers "F.Cu" "F.Mask" "F.Paste")
			(net "P52V_HS2_SENSE_N_R1")
		)
	)
	(footprint ""
		(layer "F.Cu")
		(at 265.9634 -49.149 -90)
		(property "Reference" "U22"
			(at -1.905 1.11633 90)
			(unlocked yes)
			(layer "F.SilkS")
			(effects
				(font
					(size 0.7874 0.5842)
					(thickness 0.1524)
				)
				(justify left)
			)
		)
		(property "Value" ""
			(at 0 0 270)
			(layer "F.Fab")
			(effects
				(font
					(size 1.27 1.27)
				)
			)
		)
		(duplicate_pad_numbers_are_jumpers no)
		(fp_line
			(start -1.603248 1.500124)
			(end -1.603248 -1.500124)
			(stroke
				(width 0.1524)
				(type default)
			)
			(layer "F.SilkS")
		)
		(fp_line
			(start 1.603248 1.500124)
			(end -1.603248 1.500124)
			(stroke
				(width 0.1524)
				(type default)
			)
			(layer "F.SilkS")
		)
		(fp_line
			(start -1.603248 -1.500124)
			(end 1.603248 -1.500124)
			(stroke
				(width 0.1524)
				(type default)
			)
			(layer "F.SilkS")
		)
		(fp_line
			(start 1.603248 -1.500124)
			(end 1.603248 1.500124)
			(stroke
				(width 0.1524)
				(type default)
			)
			(layer "F.SilkS")
		)
		(fp_line
			(start -0.700024 1.500124)
			(end 0.700024 1.500124)
			(stroke
				(width 0.1)
				(type default)
			)
			(layer "F.Fab")
		)
		(fp_line
			(start 0.700024 1.500124)
			(end 0.700024 0.219964)
			(stroke
				(width 0.1)
				(type default)
			)
			(layer "F.Fab")
		)
		(fp_line
			(start -1.249934 1.169924)
			(end -0.700024 1.169924)
			(stroke
				(width 0.1)
				(type default)
			)
			(layer "F.Fab")
		)
		(fp_line
			(start -0.700024 1.169924)
			(end -0.700024 1.500124)
			(stroke
				(width 0.1)
				(type default)
			)
			(layer "F.Fab")
		)
		(fp_line
			(start -1.249934 0.729996)
			(end -1.249934 1.169924)
			(stroke
				(width 0.1)
				(type default)
			)
			(layer "F.Fab")
		)
		(fp_line
			(start -0.6985 0.729996)
			(end -1.249934 0.729996)
			(stroke
				(width 0.1)
				(type default)
			)
			(layer "F.Fab")
		)
		(fp_line
			(start 0.700024 0.219964)
			(end 1.249934 0.219964)
			(stroke
				(width 0.1)
				(type default)
			)
			(layer "F.Fab")
		)
		(fp_line
			(start 1.249934 0.219964)
			(end 1.249934 -0.219964)
			(stroke
				(width 0.1)
				(type default)
			)
			(layer "F.Fab")
		)
		(fp_line
			(start 0.700024 -0.219964)
			(end 0.700024 -1.500124)
			(stroke
				(width 0.1)
				(type default)
			)
			(layer "F.Fab")
		)
		(fp_line
			(start 1.249934 -0.219964)
			(end 0.700024 -0.219964)
			(stroke
				(width 0.1)
				(type default)
			)
			(layer "F.Fab")
		)
		(fp_line
			(start -1.249934 -0.729996)
			(end -0.6985 -0.729996)
			(stroke
				(width 0.1)
				(type default)
			)
			(layer "F.Fab")
		)
		(fp_line
			(start -0.6985 -0.729996)
			(end -0.6985 0.729996)
			(stroke
				(width 0.1)
				(type default)
			)
			(layer "F.Fab")
		)
		(fp_line
			(start -1.249934 -1.169924)
			(end -1.249934 -0.729996)
			(stroke
				(width 0.1)
				(type default)
			)
			(layer "F.Fab")
		)
		(fp_line
			(start -0.700024 -1.169924)
			(end -1.249934 -1.169924)
			(stroke
				(width 0.1)
				(type default)
			)
			(layer "F.Fab")
		)
		(fp_line
			(start -0.700024 -1.500124)
			(end -0.700024 -1.169924)
			(stroke
				(width 0.1)
				(type default)
			)
			(layer "F.Fab")
		)
		(fp_line
			(start 0.700024 -1.500124)
			(end -0.700024 -1.500124)
			(stroke
				(width 0.1)
				(type default)
			)
			(layer "F.Fab")
		)
		(fp_rect
			(start -0.700024 1.500124)
			(end 0.700024 -1.500124)
			(stroke
				(width 0)
				(type default)
			)
			(fill no)
			(layer "F.Fab")
		)
		(pad "D" smd rect
			(at 0.999998 0 180)
			(size 0.8128 0.9144)
			(layers "F.Cu" "F.Mask" "F.Paste")
			(net "GPU_HSC1_BUF_EN_N")
		)
		(pad "G" smd rect
			(at -0.999998 -0.94996 180)
			(size 0.8128 0.9144)
			(layers "F.Cu" "F.Mask" "F.Paste")
			(net "GPU_HSC_BUF_EN")
		)
		(pad "S" smd rect
			(at -0.999998 0.94996 180)
			(size 0.8128 0.9144)
			(layers "F.Cu" "F.Mask" "F.Paste")
			(net "GND")
		)
	)
	(footprint ""
		(layer "F.Cu")
		(at 302.4124 -68.199 180)
		(property "Reference" "PR6963"
			(at 0 0 180)
			(layer "F.SilkS")
			(hide yes)
			(effects
				(font
					(size 1.27 1.27)
				)
			)
		)
		(property "Value" ""
			(at 0 0 180)
			(layer "F.Fab")
			(effects
				(font
					(size 1.27 1.27)
				)
			)
		)
		(duplicate_pad_numbers_are_jumpers no)
		(fp_line
			(start 1.2954 0.5842)
			(end -1.2954 0.5842)
			(stroke
				(width 0.1524)
				(type default)
			)
			(layer "F.SilkS")
		)
		(fp_line
			(start 1.2954 -0.5842)
			(end 1.2954 0.5842)
			(stroke
				(width 0.1524)
				(type default)
			)
			(layer "F.SilkS")
		)
		(fp_line
			(start -1.2954 0.5842)
			(end -1.2954 -0.5842)
			(stroke
				(width 0.1524)
				(type default)
			)
			(layer "F.SilkS")
		)
		(fp_line
			(start -1.2954 -0.5842)
			(end 1.2954 -0.5842)
			(stroke
				(width 0.1524)
				(type default)
			)
			(layer "F.SilkS")
		)
		(fp_line
			(start 1.1938 0.4064)
			(end 0.8636 0.4064)
			(stroke
				(width 0.1)
				(type default)
			)
			(layer "F.Fab")
		)
		(fp_line
			(start 1.1938 -0.406654)
			(end 1.1938 0.4064)
			(stroke
				(width 0.1)
				(type default)
			)
			(layer "F.Fab")
		)
		(fp_line
			(start 0.8636 0.4572)
			(end -0.8636 0.4572)
			(stroke
				(width 0.1)
				(type default)
			)
			(layer "F.Fab")
		)
		(fp_line
			(start 0.8636 0.4064)
			(end 0.8636 0.4572)
			(stroke
				(width 0.1)
				(type default)
			)
			(layer "F.Fab")
		)
		(fp_line
			(start 0.8636 -0.406654)
			(end 1.1938 -0.406654)
			(stroke
				(width 0.1)
				(type default)
			)
			(layer "F.Fab")
		)
		(fp_line
			(start 0.8636 -0.4572)
			(end 0.8636 -0.406654)
			(stroke
				(width 0.1)
				(type default)
			)
			(layer "F.Fab")
		)
		(fp_line
			(start -0.8636 0.4572)
			(end -0.8636 0.4318)
			(stroke
				(width 0.1)
				(type default)
			)
			(layer "F.Fab")
		)
		(fp_line
			(start -0.8636 0.4318)
			(end -0.8636 0.4064)
			(stroke
				(width 0.1)
				(type default)
			)
			(layer "F.Fab")
		)
		(fp_line
			(start -0.8636 0.4064)
			(end -1.1938 0.4064)
			(stroke
				(width 0.1)
				(type default)
			)
			(layer "F.Fab")
		)
		(fp_line
			(start -0.8636 -0.406654)
			(end -0.8636 -0.4572)
			(stroke
				(width 0.1)
				(type default)
			)
			(layer "F.Fab")
		)
		(fp_line
			(start -0.8636 -0.4572)
			(end 0.8636 -0.4572)
			(stroke
				(width 0.1)
				(type default)
			)
			(layer "F.Fab")
		)
		(fp_line
			(start -1.1938 0.4064)
			(end -1.1938 -0.406654)
			(stroke
				(width 0.1)
				(type default)
			)
			(layer "F.Fab")
		)
		(fp_line
			(start -1.1938 -0.406654)
			(end -0.8636 -0.406654)
			(stroke
				(width 0.1)
				(type default)
			)
			(layer "F.Fab")
		)
		(pad "1" smd rect
			(at -0.7366 0 90)
			(size 0.7112 0.8128)
			(layers "F.Cu" "F.Mask" "F.Paste")
			(net "P52V_HS_4287_ADC_P")
		)
		(pad "2" smd rect
			(at 0.7366 0 90)
			(size 0.7112 0.8128)
			(layers "F.Cu" "F.Mask" "F.Paste")
			(net "P52V_HS1_SENSE_P_R1")
		)
	)
	(footprint ""
		(layer "F.Cu")
		(at 238.810038 -51.049936 180)
		(property "Reference" "J6"
			(at 0.913638 -41.905936 0)
			(unlocked yes)
			(layer "F.SilkS")
			(effects
				(font
					(size 10.16 7.62)
					(thickness 1.778)
				)
			)
		)
		(property "Value" ""
			(at 0 0 180)
			(layer "F.Fab")
			(effects
				(font
					(size 1.27 1.27)
				)
			)
		)
		(duplicate_pad_numbers_are_jumpers no)
		(fp_line
			(start 14.109954 34.36493)
			(end -6.469888 34.36493)
			(stroke
				(width 0.1524)
				(type default)
			)
			(layer "F.SilkS")
		)
		(fp_line
			(start 14.109954 -34.36493)
			(end 14.109954 34.36493)
			(stroke
				(width 0.1524)
				(type default)
			)
			(layer "F.SilkS")
		)
		(fp_line
			(start 11.10996 31.364936)
			(end 4.241038 31.364936)
			(stroke
				(width 0.1524)
				(type default)
			)
			(layer "F.SilkS")
		)
		(fp_line
			(start 11.10996 -31.364936)
			(end 11.10996 31.364936)
			(stroke
				(width 0.1524)
				(type default)
			)
			(layer "F.SilkS")
		)
		(fp_line
			(start 4.291838 -31.364936)
			(end 11.10996 -31.364936)
			(stroke
				(width 0.1524)
				(type default)
			)
			(layer "F.SilkS")
		)
		(fp_line
			(start -3.469894 25.912064)
			(end -3.469894 -25.370536)
			(stroke
				(width 0.1524)
				(type default)
			)
			(layer "F.SilkS")
		)
		(fp_line
			(start -6.469888 34.36493)
			(end -6.469888 -34.36493)
			(stroke
				(width 0.1524)
				(type default)
			)
			(layer "F.SilkS")
		)
		(fp_line
			(start -6.469888 -34.36493)
			(end 14.109954 -34.36493)
			(stroke
				(width 0.1524)
				(type default)
			)
			(layer "F.SilkS")
		)
		(fp_poly
			(pts
				(xy -5.0038 -0.508) (xy -5.0038 0.508) (xy -3.9878 0)
			)
			(stroke
				(width 0)
				(type default)
			)
			(fill yes)
			(layer "F.SilkS")
		)
		(fp_line
			(start 14.109954 34.36493)
			(end -6.469888 34.36493)
			(stroke
				(width 0.1524)
				(type default)
			)
			(layer "B.SilkS")
		)
		(fp_line
			(start 14.109954 -34.36493)
			(end 14.109954 34.36493)
			(stroke
				(width 0.1524)
				(type default)
			)
			(layer "B.SilkS")
		)
		(fp_line
			(start -6.469888 34.36493)
			(end -6.469888 -34.36493)
			(stroke
				(width 0.1524)
				(type default)
			)
			(layer "B.SilkS")
		)
		(fp_line
			(start -6.469888 -34.36493)
			(end 14.109954 -34.36493)
			(stroke
				(width 0.1524)
				(type default)
			)
			(layer "B.SilkS")
		)
		(fp_line
			(start 14.109954 34.36493)
			(end -6.469888 34.36493)
			(stroke
				(width 0.1)
				(type default)
			)
			(layer "B.Fab")
		)
		(fp_line
			(start 14.109954 -34.36493)
			(end 14.109954 34.36493)
			(stroke
				(width 0.1)
				(type default)
			)
			(layer "B.Fab")
		)
		(fp_line
			(start -6.469888 34.36493)
			(end -6.469888 -34.36493)
			(stroke
				(width 0.1)
				(type default)
			)
			(layer "B.Fab")
		)
		(fp_line
			(start -6.469888 -34.36493)
			(end 14.109954 -34.36493)
			(stroke
				(width 0.1)
				(type default)
			)
			(layer "B.Fab")
		)
		(fp_line
			(start 11.10996 31.364936)
			(end -3.469894 31.364936)
			(stroke
				(width 0.1)
				(type default)
			)
			(layer "F.Fab")
		)
		(fp_line
			(start 11.10996 -31.364936)
			(end 11.10996 31.364936)
			(stroke
				(width 0.1)
				(type default)
			)
			(layer "F.Fab")
		)
		(fp_line
			(start -3.469894 31.364936)
			(end -3.469894 -31.364936)
			(stroke
				(width 0.1)
				(type default)
			)
			(layer "F.Fab")
		)
		(fp_line
			(start -3.469894 -31.364936)
			(end 11.10996 -31.364936)
			(stroke
				(width 0.1)
				(type default)
			)
			(layer "F.Fab")
		)
		(fp_poly
			(pts
				(xy -5.0038 -0.508) (xy -5.0038 0.508) (xy -3.9878 0)
			)
			(stroke
				(width 0)
				(type default)
			)
			(fill yes)
			(layer "F.Fab")
		)
		(fp_text user "PRESS-FIT"
			(at 12.63015 -0.0127 90)
			(unlocked yes)
			(layer "F.SilkS")
			(effects
				(font
					(size 1.905 1.4224)
					(thickness 0.1524)
				)
			)
		)
		(fp_text user "PRESS-FIT"
			(at 12.629388 0.639064 270)
			(unlocked yes)
			(layer "B.SilkS")
			(effects
				(font
					(size 1.905 1.4224)
					(thickness 0.1524)
				)
				(justify mirror)
			)
		)
		(fp_text user "PRESS-FIT"
			(at 12.63015 -0.0127 90)
			(unlocked yes)
			(layer "B.Fab")
			(effects
				(font
					(size 1.905 1.4224)
					(thickness 0.1524)
				)
				(justify mirror)
			)
		)
		(fp_text user "PRESS-FIT"
			(at 12.63015 -0.0127 90)
			(unlocked yes)
			(layer "F.Fab")
			(effects
				(font
					(size 1.905 1.4224)
					(thickness 0.1524)
				)
			)
		)
		(pad "" np_thru_hole circle
			(at 0 -28.575 180)
			(size 0 0)
			(drill 3.2004)
			(layers "*.Cu" "*.Mask")
			(clearance 0)
		)
		(pad "" np_thru_hole circle
			(at 0 28.575 180)
			(size 0 0)
			(drill 3.2004)
			(layers "*.Cu" "*.Mask")
			(clearance 0)
		)
		(pad "A1" thru_hole rect
			(at 0 0 180)
			(size 1.52781 1.52781)
			(drill 1.01981)
			(layers "*.Cu" "*.Mask")
			(remove_unused_layers no)
			(net "P52V_1_BUSBAR")
			(clearance 0)
			(padstack
				(mode front_inner_back)
				(layer "Inner"
					(shape circle)
					(size 1.52781 1.52781)
					(clearance 0)
				)
				(layer "B.Cu"
					(shape rect)
					(size 1.52781 1.52781)
					(clearance 0)
				)
			)
		)
		(pad "B1" thru_hole circle
			(at 2.54 0 180)
			(size 1.52781 1.52781)
			(drill 1.01981)
			(layers "*.Cu" "*.Mask")
			(remove_unused_layers no)
			(net "GND_1_BUSBAR")
			(clearance 0)
		)
		(pad "C1" thru_hole circle
			(at 5.08 0 180)
			(size 1.52781 1.52781)
			(drill 1.01981)
			(layers "*.Cu" "*.Mask")
			(remove_unused_layers no)
			(net "NC_J6_C1")
			(clearance 0)
		)
		(pad "D1" thru_hole circle
			(at 7.62 0 180)
			(size 1.52781 1.52781)
			(drill 1.01981)
			(layers "*.Cu" "*.Mask")
			(remove_unused_layers no)
			(net "NC_J6_D1")
			(clearance 0)
		)
		(pad "P1_1" thru_hole circle
			(at 7.62 -16.51 180)
			(size 1.52781 1.52781)
			(drill 1.01981)
			(layers "*.Cu" "*.Mask")
			(remove_unused_layers no)
			(net "P52V_1")
			(clearance 0)
		)
		(pad "P1_2" thru_hole circle
			(at 5.08 -16.51 180)
			(size 1.52781 1.52781)
			(drill 1.01981)
			(layers "*.Cu" "*.Mask")
			(remove_unused_layers no)
			(net "P52V_1")
			(clearance 0)
		)
		(pad "P1_3" thru_hole circle
			(at 2.54 -16.51 180)
			(size 1.52781 1.52781)
			(drill 1.01981)
			(layers "*.Cu" "*.Mask")
			(remove_unused_layers no)
			(net "P52V_1")
			(clearance 0)
		)
		(pad "P1_4" thru_hole circle
			(at 0 -16.51 180)
			(size 1.52781 1.52781)
			(drill 1.01981)
			(layers "*.Cu" "*.Mask")
			(remove_unused_layers no)
			(net "P52V_1")
			(clearance 0)
		)
		(pad "P1_5" thru_hole circle
			(at 7.62 -13.97 180)
			(size 1.52781 1.52781)
			(drill 1.01981)
			(layers "*.Cu" "*.Mask")
			(remove_unused_layers no)
			(net "P52V_1")
			(clearance 0)
		)
		(pad "P1_6" thru_hole circle
			(at 5.08 -13.97 180)
			(size 1.52781 1.52781)
			(drill 1.01981)
			(layers "*.Cu" "*.Mask")
			(remove_unused_layers no)
			(net "P52V_1")
			(clearance 0)
		)
		(pad "P1_7" thru_hole circle
			(at 2.54 -13.97 180)
			(size 1.52781 1.52781)
			(drill 1.01981)
			(layers "*.Cu" "*.Mask")
			(remove_unused_layers no)
			(net "P52V_1")
			(clearance 0)
		)
		(pad "P1_8" thru_hole circle
			(at 0 -13.97 180)
			(size 1.52781 1.52781)
			(drill 1.01981)
			(layers "*.Cu" "*.Mask")
			(remove_unused_layers no)
			(net "P52V_1")
			(clearance 0)
		)
		(pad "P2_1" thru_hole circle
			(at 7.62 -7.62 180)
			(size 1.52781 1.52781)
			(drill 1.01981)
			(layers "*.Cu" "*.Mask")
			(remove_unused_layers no)
			(net "P52V_1")
			(clearance 0)
		)
		(pad "P2_2" thru_hole circle
			(at 5.08 -7.62 180)
			(size 1.52781 1.52781)
			(drill 1.01981)
			(layers "*.Cu" "*.Mask")
			(remove_unused_layers no)
			(net "P52V_1")
			(clearance 0)
		)
		(pad "P2_3" thru_hole circle
			(at 2.54 -7.62 180)
			(size 1.52781 1.52781)
			(drill 1.01981)
			(layers "*.Cu" "*.Mask")
			(remove_unused_layers no)
			(net "P52V_1")
			(clearance 0)
		)
		(pad "P2_4" thru_hole circle
			(at 0 -7.62 180)
			(size 1.52781 1.52781)
			(drill 1.01981)
			(layers "*.Cu" "*.Mask")
			(remove_unused_layers no)
			(net "P52V_1")
			(clearance 0)
		)
		(pad "P2_5" thru_hole circle
			(at 7.62 -5.08 180)
			(size 1.52781 1.52781)
			(drill 1.01981)
			(layers "*.Cu" "*.Mask")
			(remove_unused_layers no)
			(net "P52V_1")
			(clearance 0)
		)
		(pad "P2_6" thru_hole circle
			(at 5.08 -5.08 180)
			(size 1.52781 1.52781)
			(drill 1.01981)
			(layers "*.Cu" "*.Mask")
			(remove_unused_layers no)
			(net "P52V_1")
			(clearance 0)
		)
		(pad "P2_7" thru_hole circle
			(at 2.54 -5.08 180)
			(size 1.52781 1.52781)
			(drill 1.01981)
			(layers "*.Cu" "*.Mask")
			(remove_unused_layers no)
			(net "P52V_1")
			(clearance 0)
		)
		(pad "P2_8" thru_hole circle
			(at 0 -5.08 180)
			(size 1.52781 1.52781)
			(drill 1.01981)
			(layers "*.Cu" "*.Mask")
			(remove_unused_layers no)
			(net "P52V_1")
			(clearance 0)
		)
		(pad "P3_1" thru_hole circle
			(at 7.62 5.08 180)
			(size 1.52781 1.52781)
			(drill 1.01981)
			(layers "*.Cu" "*.Mask")
			(remove_unused_layers no)
			(net "GND")
			(clearance 0)
		)
		(pad "P3_2" thru_hole circle
			(at 5.08 5.08 180)
			(size 1.52781 1.52781)
			(drill 1.01981)
			(layers "*.Cu" "*.Mask")
			(remove_unused_layers no)
			(net "GND")
			(clearance 0)
		)
		(pad "P3_3" thru_hole circle
			(at 2.54 5.08 180)
			(size 1.52781 1.52781)
			(drill 1.01981)
			(layers "*.Cu" "*.Mask")
			(remove_unused_layers no)
			(net "GND")
			(clearance 0)
		)
		(pad "P3_4" thru_hole circle
			(at 0 5.08 180)
			(size 1.52781 1.52781)
			(drill 1.01981)
			(layers "*.Cu" "*.Mask")
			(remove_unused_layers no)
			(net "GND")
			(clearance 0)
		)
		(pad "P3_5" thru_hole circle
			(at 7.62 7.62 180)
			(size 1.52781 1.52781)
			(drill 1.01981)
			(layers "*.Cu" "*.Mask")
			(remove_unused_layers no)
			(net "GND")
			(clearance 0)
		)
		(pad "P3_6" thru_hole circle
			(at 5.08 7.62 180)
			(size 1.52781 1.52781)
			(drill 1.01981)
			(layers "*.Cu" "*.Mask")
			(remove_unused_layers no)
			(net "GND")
			(clearance 0)
		)
		(pad "P3_7" thru_hole circle
			(at 2.54 7.62 180)
			(size 1.52781 1.52781)
			(drill 1.01981)
			(layers "*.Cu" "*.Mask")
			(remove_unused_layers no)
			(net "GND")
			(clearance 0)
		)
		(pad "P3_8" thru_hole circle
			(at 0 7.62 180)
			(size 1.52781 1.52781)
			(drill 1.01981)
			(layers "*.Cu" "*.Mask")
			(remove_unused_layers no)
			(net "GND")
			(clearance 0)
		)
		(pad "P4_1" thru_hole circle
			(at 7.62 13.97 180)
			(size 1.52781 1.52781)
			(drill 1.01981)
			(layers "*.Cu" "*.Mask")
			(remove_unused_layers no)
			(net "GND")
			(clearance 0)
		)
		(pad "P4_2" thru_hole circle
			(at 5.08 13.97 180)
			(size 1.52781 1.52781)
			(drill 1.01981)
			(layers "*.Cu" "*.Mask")
			(remove_unused_layers no)
			(net "GND")
			(clearance 0)
		)
		(pad "P4_3" thru_hole circle
			(at 2.54 13.97 180)
			(size 1.52781 1.52781)
			(drill 1.01981)
			(layers "*.Cu" "*.Mask")
			(remove_unused_layers no)
			(net "GND")
			(clearance 0)
		)
		(pad "P4_4" thru_hole circle
			(at 0 13.97 180)
			(size 1.52781 1.52781)
			(drill 1.01981)
			(layers "*.Cu" "*.Mask")
			(remove_unused_layers no)
			(net "GND")
			(clearance 0)
		)
		(pad "P4_5" thru_hole circle
			(at 7.62 16.51 180)
			(size 1.52781 1.52781)
			(drill 1.01981)
			(layers "*.Cu" "*.Mask")
			(remove_unused_layers no)
			(net "GND")
			(clearance 0)
		)
		(pad "P4_6" thru_hole circle
			(at 5.08 16.51 180)
			(size 1.52781 1.52781)
			(drill 1.01981)
			(layers "*.Cu" "*.Mask")
			(remove_unused_layers no)
			(net "GND")
			(clearance 0)
		)
		(pad "P4_7" thru_hole circle
			(at 2.54 16.51 180)
			(size 1.52781 1.52781)
			(drill 1.01981)
			(layers "*.Cu" "*.Mask")
			(remove_unused_layers no)
			(net "GND")
			(clearance 0)
		)
		(pad "P4_8" thru_hole circle
			(at 0 16.51 180)
			(size 1.52781 1.52781)
			(drill 1.01981)
			(layers "*.Cu" "*.Mask")
			(remove_unused_layers no)
			(net "GND")
			(clearance 0)
		)
		(zone
			(layers "F.Cu" "B.Cu" "In1.Cu" "In2.Cu" "In3.Cu" "In4.Cu" "In5.Cu" "In6.Cu"
				"In7.Cu" "In8.Cu"
			)
			(hatch none 0.5)
			(connect_pads
				(clearance 0)
			)
			(min_thickness 0.25)
			(keepout
				(tracks not_allowed)
				(vias allowed)
				(pads allowed)
				(copperpour not_allowed)
				(footprints allowed)
			)
			(placement
				(enabled no)
				(sheetname "")
			)
			(fill
				(thermal_gap 0.5)
				(thermal_bridge_width 0.5)
				(island_removal_mode 0)
			)
			(polygon
				(pts
					(arc
						(start 242.442238 -79.624936)
						(mid 235.177838 -79.624936)
						(end 242.442238 -79.624936)
					)
				)
			)
		)
		(zone
			(layers "F.Cu" "B.Cu" "In1.Cu" "In2.Cu" "In3.Cu" "In4.Cu" "In5.Cu" "In6.Cu"
				"In7.Cu" "In8.Cu"
			)
			(hatch none 0.5)
			(connect_pads
				(clearance 0)
			)
			(min_thickness 0.25)
			(keepout
				(tracks not_allowed)
				(vias allowed)
				(pads allowed)
				(copperpour not_allowed)
				(footprints allowed)
			)
			(placement
				(enabled no)
				(sheetname "")
			)
			(fill
				(thermal_gap 0.5)
				(thermal_bridge_width 0.5)
				(island_removal_mode 0)
			)
			(polygon
				(pts
					(arc
						(start 242.442238 -22.474936)
						(mid 235.177838 -22.474936)
						(end 242.442238 -22.474936)
					)
				)
			)
		)
		(zone
			(layer "B.Cu")
			(hatch none 0.5)
			(connect_pads
				(clearance 0)
			)
			(min_thickness 0.25)
			(keepout
				(tracks allowed)
				(vias not_allowed)
				(pads allowed)
				(copperpour not_allowed)
				(footprints allowed)
			)
			(placement
				(enabled no)
				(sheetname "")
			)
			(fill
				(thermal_gap 0.5)
				(thermal_bridge_width 0.5)
				(island_removal_mode 0)
			)
			(polygon
				(pts
					(xy 239.637316 -33.712658) (xy 239.637316 -68.387214) (xy 230.36276 -68.387214) (xy 230.36276 -33.712658)
				)
			)
		)
	)
	(footprint ""
		(layer "F.Cu")
		(at 145.11782 -34.3662 180)
		(property "Reference" "PR6987"
			(at 0 0 180)
			(layer "F.SilkS")
			(hide yes)
			(effects
				(font
					(size 1.27 1.27)
				)
			)
		)
		(property "Value" ""
			(at 0 0 180)
			(layer "F.Fab")
			(effects
				(font
					(size 1.27 1.27)
				)
			)
		)
		(duplicate_pad_numbers_are_jumpers no)
		(fp_line
			(start 1.2954 0.5842)
			(end -1.2954 0.5842)
			(stroke
				(width 0.1524)
				(type default)
			)
			(layer "F.SilkS")
		)
		(fp_line
			(start 1.2954 -0.5842)
			(end 1.2954 0.5842)
			(stroke
				(width 0.1524)
				(type default)
			)
			(layer "F.SilkS")
		)
		(fp_line
			(start -1.2954 0.5842)
			(end -1.2954 -0.5842)
			(stroke
				(width 0.1524)
				(type default)
			)
			(layer "F.SilkS")
		)
		(fp_line
			(start -1.2954 -0.5842)
			(end 1.2954 -0.5842)
			(stroke
				(width 0.1524)
				(type default)
			)
			(layer "F.SilkS")
		)
		(fp_line
			(start 1.1938 0.4064)
			(end 0.8636 0.4064)
			(stroke
				(width 0.1)
				(type default)
			)
			(layer "F.Fab")
		)
		(fp_line
			(start 1.1938 -0.406654)
			(end 1.1938 0.4064)
			(stroke
				(width 0.1)
				(type default)
			)
			(layer "F.Fab")
		)
		(fp_line
			(start 0.8636 0.4572)
			(end -0.8636 0.4572)
			(stroke
				(width 0.1)
				(type default)
			)
			(layer "F.Fab")
		)
		(fp_line
			(start 0.8636 0.4064)
			(end 0.8636 0.4572)
			(stroke
				(width 0.1)
				(type default)
			)
			(layer "F.Fab")
		)
		(fp_line
			(start 0.8636 -0.406654)
			(end 1.1938 -0.406654)
			(stroke
				(width 0.1)
				(type default)
			)
			(layer "F.Fab")
		)
		(fp_line
			(start 0.8636 -0.4572)
			(end 0.8636 -0.406654)
			(stroke
				(width 0.1)
				(type default)
			)
			(layer "F.Fab")
		)
		(fp_line
			(start -0.8636 0.4572)
			(end -0.8636 0.4318)
			(stroke
				(width 0.1)
				(type default)
			)
			(layer "F.Fab")
		)
		(fp_line
			(start -0.8636 0.4318)
			(end -0.8636 0.4064)
			(stroke
				(width 0.1)
				(type default)
			)
			(layer "F.Fab")
		)
		(fp_line
			(start -0.8636 0.4064)
			(end -1.1938 0.4064)
			(stroke
				(width 0.1)
				(type default)
			)
			(layer "F.Fab")
		)
		(fp_line
			(start -0.8636 -0.406654)
			(end -0.8636 -0.4572)
			(stroke
				(width 0.1)
				(type default)
			)
			(layer "F.Fab")
		)
		(fp_line
			(start -0.8636 -0.4572)
			(end 0.8636 -0.4572)
			(stroke
				(width 0.1)
				(type default)
			)
			(layer "F.Fab")
		)
		(fp_line
			(start -1.1938 0.4064)
			(end -1.1938 -0.406654)
			(stroke
				(width 0.1)
				(type default)
			)
			(layer "F.Fab")
		)
		(fp_line
			(start -1.1938 -0.406654)
			(end -0.8636 -0.406654)
			(stroke
				(width 0.1)
				(type default)
			)
			(layer "F.Fab")
		)
		(pad "1" smd rect
			(at -0.7366 0 90)
			(size 0.7112 0.8128)
			(layers "F.Cu" "F.Mask" "F.Paste")
			(net "P52V_HS2_SENSE_P_R2")
		)
		(pad "2" smd rect
			(at 0.7366 0 90)
			(size 0.7112 0.8128)
			(layers "F.Cu" "F.Mask" "F.Paste")
			(net "P52V_HS2_4287_ADC_P")
		)
	)
	(footprint ""
		(layer "F.Cu")
		(at 414.02 -42.545 180)
		(property "Reference" "R5927"
			(at 0 0 180)
			(layer "F.SilkS")
			(hide yes)
			(effects
				(font
					(size 1.27 1.27)
				)
			)
		)
		(property "Value" ""
			(at 0 0 180)
			(layer "F.Fab")
			(effects
				(font
					(size 1.27 1.27)
				)
			)
		)
		(duplicate_pad_numbers_are_jumpers no)
		(fp_line
			(start 0.7874 0.4064)
			(end -0.7874 0.4064)
			(stroke
				(width 0.1524)
				(type default)
			)
			(layer "F.SilkS")
		)
		(fp_line
			(start 0.7874 -0.4064)
			(end 0.7874 0.4064)
			(stroke
				(width 0.1524)
				(type default)
			)
			(layer "F.SilkS")
		)
		(fp_line
			(start -0.7874 0.4064)
			(end -0.7874 -0.4064)
			(stroke
				(width 0.1524)
				(type default)
			)
			(layer "F.SilkS")
		)
		(fp_line
			(start -0.7874 -0.4064)
			(end 0.7874 -0.4064)
			(stroke
				(width 0.1524)
				(type default)
			)
			(layer "F.SilkS")
		)
		(fp_line
			(start 0.67945 0.3048)
			(end 0.120396 0.3048)
			(stroke
				(width 0.1)
				(type default)
			)
			(layer "F.Fab")
		)
		(fp_line
			(start 0.67945 -0.3048)
			(end 0.67945 0.3048)
			(stroke
				(width 0.1)
				(type default)
			)
			(layer "F.Fab")
		)
		(fp_line
			(start 0.12065 -0.2794)
			(end 0.12065 -0.3048)
			(stroke
				(width 0.1)
				(type default)
			)
			(layer "F.Fab")
		)
		(fp_line
			(start 0.12065 -0.3048)
			(end 0.67945 -0.3048)
			(stroke
				(width 0.1)
				(type default)
			)
			(layer "F.Fab")
		)
		(fp_line
			(start 0.120396 0.3048)
			(end 0.120396 0.2794)
			(stroke
				(width 0.1)
				(type default)
			)
			(layer "F.Fab")
		)
		(fp_line
			(start 0.120396 0.2794)
			(end -0.12065 0.2794)
			(stroke
				(width 0.1)
				(type default)
			)
			(layer "F.Fab")
		)
		(fp_line
			(start -0.12065 0.3048)
			(end -0.67945 0.3048)
			(stroke
				(width 0.1)
				(type default)
			)
			(layer "F.Fab")
		)
		(fp_line
			(start -0.12065 0.2794)
			(end -0.12065 0.3048)
			(stroke
				(width 0.1)
				(type default)
			)
			(layer "F.Fab")
		)
		(fp_line
			(start -0.12065 -0.2794)
			(end 0.12065 -0.2794)
			(stroke
				(width 0.1)
				(type default)
			)
			(layer "F.Fab")
		)
		(fp_line
			(start -0.12065 -0.305054)
			(end -0.12065 -0.2794)
			(stroke
				(width 0.1)
				(type default)
			)
			(layer "F.Fab")
		)
		(fp_line
			(start -0.67945 0.3048)
			(end -0.67945 -0.305054)
			(stroke
				(width 0.1)
				(type default)
			)
			(layer "F.Fab")
		)
		(fp_line
			(start -0.67945 -0.305054)
			(end -0.12065 -0.305054)
			(stroke
				(width 0.1)
				(type default)
			)
			(layer "F.Fab")
		)
		(pad "1" smd circle
			(at -0.40005 0 180)
			(size 0 0)
			(layers "F.Cu" "F.Mask" "F.Paste")
			(net "PRSNT_FAN_BP0_N")
		)
		(pad "2" smd circle
			(at 0.40005 0 180)
			(size 0 0)
			(layers "F.Cu" "F.Mask" "F.Paste")
			(net "PRSNT_FAN_BP0_R_N")
		)
	)
	(footprint ""
		(layer "F.Cu")
		(at 378.517912 -17.907254 -90)
		(property "Reference" "R73"
			(at 0 0 270)
			(layer "F.SilkS")
			(hide yes)
			(effects
				(font
					(size 1.27 1.27)
				)
			)
		)
		(property "Value" ""
			(at 0 0 270)
			(layer "F.Fab")
			(effects
				(font
					(size 1.27 1.27)
				)
			)
		)
		(duplicate_pad_numbers_are_jumpers no)
		(fp_line
			(start -0.7874 0.4064)
			(end -0.7874 -0.4064)
			(stroke
				(width 0.1524)
				(type default)
			)
			(layer "F.SilkS")
		)
		(fp_line
			(start 0.7874 0.4064)
			(end -0.7874 0.4064)
			(stroke
				(width 0.1524)
				(type default)
			)
			(layer "F.SilkS")
		)
		(fp_line
			(start -0.7874 -0.4064)
			(end 0.7874 -0.4064)
			(stroke
				(width 0.1524)
				(type default)
			)
			(layer "F.SilkS")
		)
		(fp_line
			(start 0.7874 -0.4064)
			(end 0.7874 0.4064)
			(stroke
				(width 0.1524)
				(type default)
			)
			(layer "F.SilkS")
		)
		(fp_line
			(start -0.67945 0.3048)
			(end -0.67945 -0.305054)
			(stroke
				(width 0.1)
				(type default)
			)
			(layer "F.Fab")
		)
		(fp_line
			(start -0.12065 0.3048)
			(end -0.67945 0.3048)
			(stroke
				(width 0.1)
				(type default)
			)
			(layer "F.Fab")
		)
		(fp_line
			(start 0.120396 0.3048)
			(end 0.120396 0.2794)
			(stroke
				(width 0.1)
				(type default)
			)
			(layer "F.Fab")
		)
		(fp_line
			(start 0.67945 0.3048)
			(end 0.120396 0.3048)
			(stroke
				(width 0.1)
				(type default)
			)
			(layer "F.Fab")
		)
		(fp_line
			(start -0.12065 0.2794)
			(end -0.12065 0.3048)
			(stroke
				(width 0.1)
				(type default)
			)
			(layer "F.Fab")
		)
		(fp_line
			(start 0.120396 0.2794)
			(end -0.12065 0.2794)
			(stroke
				(width 0.1)
				(type default)
			)
			(layer "F.Fab")
		)
		(fp_line
			(start -0.12065 -0.2794)
			(end 0.12065 -0.2794)
			(stroke
				(width 0.1)
				(type default)
			)
			(layer "F.Fab")
		)
		(fp_line
			(start 0.12065 -0.2794)
			(end 0.12065 -0.3048)
			(stroke
				(width 0.1)
				(type default)
			)
			(layer "F.Fab")
		)
		(fp_line
			(start 0.12065 -0.3048)
			(end 0.67945 -0.3048)
			(stroke
				(width 0.1)
				(type default)
			)
			(layer "F.Fab")
		)
		(fp_line
			(start 0.67945 -0.3048)
			(end 0.67945 0.3048)
			(stroke
				(width 0.1)
				(type default)
			)
			(layer "F.Fab")
		)
		(fp_line
			(start -0.67945 -0.305054)
			(end -0.12065 -0.305054)
			(stroke
				(width 0.1)
				(type default)
			)
			(layer "F.Fab")
		)
		(fp_line
			(start -0.12065 -0.305054)
			(end -0.12065 -0.2794)
			(stroke
				(width 0.1)
				(type default)
			)
			(layer "F.Fab")
		)
		(pad "1" smd circle
			(at -0.40005 0 270)
			(size 0 0)
			(layers "F.Cu" "F.Mask" "F.Paste")
			(net "SMB_PDB_FAN_0_SDA")
		)
		(pad "2" smd circle
			(at 0.40005 0 270)
			(size 0 0)
			(layers "F.Cu" "F.Mask" "F.Paste")
			(net "SMB_PDB_FAN_0_R_SDA")
		)
	)
	(footprint ""
		(layer "F.Cu")
		(at 449.3514 -93.98)
		(property "Reference" "PC58"
			(at 0 0 0)
			(layer "F.SilkS")
			(hide yes)
			(effects
				(font
					(size 1.27 1.27)
				)
			)
		)
		(property "Value" ""
			(at 0 0 0)
			(layer "F.Fab")
			(effects
				(font
					(size 1.27 1.27)
				)
			)
		)
		(duplicate_pad_numbers_are_jumpers no)
		(fp_line
			(start -1.524 -0.762)
			(end 1.524 -0.762)
			(stroke
				(width 0.1524)
				(type default)
			)
			(layer "F.SilkS")
		)
		(fp_line
			(start -1.524 0.762)
			(end -1.524 -0.762)
			(stroke
				(width 0.1524)
				(type default)
			)
			(layer "F.SilkS")
		)
		(fp_line
			(start 1.524 -0.762)
			(end 1.524 0.762)
			(stroke
				(width 0.1524)
				(type default)
			)
			(layer "F.SilkS")
		)
		(fp_line
			(start 1.524 0.762)
			(end -1.524 0.762)
			(stroke
				(width 0.1524)
				(type default)
			)
			(layer "F.SilkS")
		)
		(fp_line
			(start -1.1049 -0.724916)
			(end -1.1049 0.724916)
			(stroke
				(width 0.1)
				(type default)
			)
			(layer "F.Fab")
		)
		(fp_line
			(start -1.1049 0.724916)
			(end 1.1049 0.724916)
			(stroke
				(width 0.1)
				(type default)
			)
			(layer "F.Fab")
		)
		(fp_line
			(start 1.1049 -0.724916)
			(end -1.1049 -0.724916)
			(stroke
				(width 0.1)
				(type default)
			)
			(layer "F.Fab")
		)
		(fp_line
			(start 1.1049 0.724916)
			(end 1.1049 -0.724916)
			(stroke
				(width 0.1)
				(type default)
			)
			(layer "F.Fab")
		)
		(pad "1" smd rect
			(at -0.889 0 180)
			(size 1.016 1.27)
			(layers "F.Cu" "F.Mask" "F.Paste")
			(net "SW_P3V3_HPDB_FLT")
		)
		(pad "2" smd rect
			(at 0.889 0 180)
			(size 1.016 1.27)
			(layers "F.Cu" "F.Mask" "F.Paste")
			(net "GND")
		)
	)
	(footprint ""
		(layer "F.Cu")
		(at 378.079 -78.74)
		(property "Reference" "PC40"
			(at 5.1054 -4.79933 0)
			(unlocked yes)
			(layer "F.SilkS")
			(effects
				(font
					(size 0.7874 0.5842)
					(thickness 0.1524)
				)
				(justify left)
			)
		)
		(property "Value" ""
			(at 0 0 0)
			(layer "F.Fab")
			(effects
				(font
					(size 1.27 1.27)
				)
			)
		)
		(duplicate_pad_numbers_are_jumpers no)
		(fp_line
			(start -9.253728 3.750056)
			(end 9.249918 3.750056)
			(stroke
				(width 0.1524)
				(type default)
			)
			(layer "F.SilkS")
		)
		(fp_line
			(start 0 3.750056)
			(end -9.253728 3.750056)
			(stroke
				(width 0.1524)
				(type default)
			)
			(layer "F.SilkS")
		)
		(fp_circle
			(center 0 3.750056)
			(end 9.249918 3.750056)
			(stroke
				(width 0.1524)
				(type default)
			)
			(fill no)
			(layer "F.SilkS")
		)
		(fp_poly
			(pts
				(arc
					(start 9.249918 3.750056)
					(mid 0 12.999974)
					(end -9.249918 3.750056)
				)
			)
			(stroke
				(width 0)
				(type default)
			)
			(fill yes)
			(layer "F.SilkS")
		)
		(fp_circle
			(center 0 3.750056)
			(end 9.249918 3.750056)
			(stroke
				(width 0.1)
				(type default)
			)
			(fill no)
			(layer "F.Fab")
		)
		(pad "1" thru_hole rect
			(at 0 0)
			(size 1.778 1.778)
			(drill 1.27)
			(layers "*.Cu" "*.Mask")
			(remove_unused_layers no)
			(net "P52V_HS1")
			(clearance 0)
			(padstack
				(mode front_inner_back)
				(layer "Inner"
					(shape circle)
					(size 1.778 1.778)
					(clearance 0)
				)
				(layer "B.Cu"
					(shape rect)
					(size 1.778 1.778)
					(clearance 0)
				)
			)
		)
		(pad "2" thru_hole circle
			(at 0 7.500112)
			(size 1.778 1.778)
			(drill 1.27)
			(layers "*.Cu" "*.Mask")
			(remove_unused_layers no)
			(net "GND")
			(clearance 0)
		)
	)
	(footprint ""
		(layer "F.Cu")
		(at 25.183846 -153.440892)
		(property "Reference" ""
			(at 0 0 0)
			(layer "F.SilkS")
			(hide yes)
			(effects
				(font
					(size 1.27 1.27)
				)
			)
		)
		(property "Value" ""
			(at 0 0 0)
			(layer "F.Fab")
			(effects
				(font
					(size 1.27 1.27)
				)
			)
		)
		(duplicate_pad_numbers_are_jumpers no)
		(pad "1" smd circle
			(at 0 0)
			(size 0.9906 0.9906)
			(layers "F.Cu" "F.Mask" "F.Paste")
			(net "Net_245")
		)
		(zone
			(layer "F.Cu")
			(hatch none 0.5)
			(connect_pads
				(clearance 0)
			)
			(min_thickness 0.25)
			(keepout
				(tracks not_allowed)
				(vias allowed)
				(pads allowed)
				(copperpour not_allowed)
				(footprints allowed)
			)
			(placement
				(enabled no)
				(sheetname "")
			)
			(fill
				(thermal_gap 0.5)
				(thermal_bridge_width 0.5)
				(island_removal_mode 0)
			)
			(polygon
				(pts
					(arc
						(start 26.809446 -153.440892)
						(mid 23.558246 -153.440892)
						(end 26.809446 -153.440892)
					)
				)
			)
		)
	)
	(footprint ""
		(layer "F.Cu")
		(at 90.043 -50.3936)
		(property "Reference" "ME1"
			(at 0 0 0)
			(layer "F.SilkS")
			(hide yes)
			(effects
				(font
					(size 1.27 1.27)
				)
			)
		)
		(property "Value" ""
			(at 0 0 0)
			(layer "F.Fab")
			(effects
				(font
					(size 1.27 1.27)
				)
			)
		)
		(duplicate_pad_numbers_are_jumpers no)
		(fp_line
			(start -3.1369 2.5527)
			(end -3.1115 2.5019)
			(stroke
				(width 0.1524)
				(type default)
			)
			(layer "F.SilkS")
		)
		(fp_line
			(start -3.1369 3.0861)
			(end -2.8321 3.0861)
			(stroke
				(width 0.1524)
				(type default)
			)
			(layer "F.SilkS")
		)
		(fp_line
			(start -3.1242 2.9972)
			(end -3.1369 3.0861)
			(stroke
				(width 0.1524)
				(type default)
			)
			(layer "F.SilkS")
		)
		(fp_line
			(start -3.1115 2.5019)
			(end -3.0861 2.4765)
			(stroke
				(width 0.1524)
				(type default)
			)
			(layer "F.SilkS")
		)
		(fp_line
			(start -3.0988 2.921)
			(end -3.1242 2.9972)
			(stroke
				(width 0.1524)
				(type default)
			)
			(layer "F.SilkS")
		)
		(fp_line
			(start -3.0861 2.4765)
			(end -3.048 2.4511)
			(stroke
				(width 0.1524)
				(type default)
			)
			(layer "F.SilkS")
		)
		(fp_line
			(start -3.0734 2.8829)
			(end -3.0988 2.921)
			(stroke
				(width 0.1524)
				(type default)
			)
			(layer "F.SilkS")
		)
		(fp_line
			(start -3.048 2.4511)
			(end -2.9972 2.4384)
			(stroke
				(width 0.1524)
				(type default)
			)
			(layer "F.SilkS")
		)
		(fp_line
			(start -3.048 2.8575)
			(end -3.0734 2.8829)
			(stroke
				(width 0.1524)
				(type default)
			)
			(layer "F.SilkS")
		)
		(fp_line
			(start -3.0099 2.8067)
			(end -3.048 2.8575)
			(stroke
				(width 0.1524)
				(type default)
			)
			(layer "F.SilkS")
		)
		(fp_line
			(start -2.9972 2.4384)
			(end -2.9337 2.4511)
			(stroke
				(width 0.1524)
				(type default)
			)
			(layer "F.SilkS")
		)
		(fp_line
			(start -2.9591 2.7686)
			(end -3.0099 2.8067)
			(stroke
				(width 0.1524)
				(type default)
			)
			(layer "F.SilkS")
		)
		(fp_line
			(start -2.9337 2.4511)
			(end -2.8702 2.5146)
			(stroke
				(width 0.1524)
				(type default)
			)
			(layer "F.SilkS")
		)
		(fp_line
			(start -2.921 2.7432)
			(end -2.9591 2.7686)
			(stroke
				(width 0.1524)
				(type default)
			)
			(layer "F.SilkS")
		)
		(fp_line
			(start -2.8956 2.7178)
			(end -2.921 2.7432)
			(stroke
				(width 0.1524)
				(type default)
			)
			(layer "F.SilkS")
		)
		(fp_line
			(start -2.8702 2.5146)
			(end -2.8575 2.5527)
			(stroke
				(width 0.1524)
				(type default)
			)
			(layer "F.SilkS")
		)
		(fp_line
			(start -2.8702 2.6797)
			(end -2.8956 2.7178)
			(stroke
				(width 0.1524)
				(type default)
			)
			(layer "F.SilkS")
		)
		(fp_line
			(start -2.8575 2.5527)
			(end -2.8575 2.6416)
			(stroke
				(width 0.1524)
				(type default)
			)
			(layer "F.SilkS")
		)
		(fp_line
			(start -2.8575 2.6416)
			(end -2.8702 2.6797)
			(stroke
				(width 0.1524)
				(type default)
			)
			(layer "F.SilkS")
		)
		(fp_line
			(start -2.5908 2.6543)
			(end -2.5908 3.0861)
			(stroke
				(width 0.1524)
				(type default)
			)
			(layer "F.SilkS")
		)
		(fp_line
			(start -2.5908 2.7813)
			(end -2.5654 2.7305)
			(stroke
				(width 0.1524)
				(type default)
			)
			(layer "F.SilkS")
		)
		(fp_line
			(start -2.5654 2.7305)
			(end -2.54 2.6924)
			(stroke
				(width 0.1524)
				(type default)
			)
			(layer "F.SilkS")
		)
		(fp_line
			(start -2.54 2.6924)
			(end -2.5146 2.667)
			(stroke
				(width 0.1524)
				(type default)
			)
			(layer "F.SilkS")
		)
		(fp_line
			(start -2.5146 2.667)
			(end -2.4638 2.6543)
			(stroke
				(width 0.1524)
				(type default)
			)
			(layer "F.SilkS")
		)
		(fp_line
			(start -2.4638 2.6543)
			(end -2.4257 2.6543)
			(stroke
				(width 0.1524)
				(type default)
			)
			(layer "F.SilkS")
		)
		(fp_line
			(start -2.4257 2.6543)
			(end -2.3749 2.667)
			(stroke
				(width 0.1524)
				(type default)
			)
			(layer "F.SilkS")
		)
		(fp_line
			(start -2.3749 2.667)
			(end -2.3368 2.7178)
			(stroke
				(width 0.1524)
				(type default)
			)
			(layer "F.SilkS")
		)
		(fp_line
			(start -2.3368 2.7178)
			(end -2.3114 2.7686)
			(stroke
				(width 0.1524)
				(type default)
			)
			(layer "F.SilkS")
		)
		(fp_line
			(start -2.3114 2.7686)
			(end -2.3114 3.0861)
			(stroke
				(width 0.1524)
				(type default)
			)
			(layer "F.SilkS")
		)
		(fp_line
			(start -2.0701 2.8575)
			(end -2.0701 2.9083)
			(stroke
				(width 0.1524)
				(type default)
			)
			(layer "F.SilkS")
		)
		(fp_line
			(start -2.0701 2.9083)
			(end -2.0574 2.9718)
			(stroke
				(width 0.1524)
				(type default)
			)
			(layer "F.SilkS")
		)
		(fp_line
			(start -2.0574 2.8194)
			(end -2.0701 2.8575)
			(stroke
				(width 0.1524)
				(type default)
			)
			(layer "F.SilkS")
		)
		(fp_line
			(start -2.0574 2.9718)
			(end -2.032 3.0099)
			(stroke
				(width 0.1524)
				(type default)
			)
			(layer "F.SilkS")
		)
		(fp_line
			(start -2.0447 2.794)
			(end -2.0574 2.8194)
			(stroke
				(width 0.1524)
				(type default)
			)
			(layer "F.SilkS")
		)
		(fp_line
			(start -2.032 3.0099)
			(end -2.0066 3.0353)
			(stroke
				(width 0.1524)
				(type default)
			)
			(layer "F.SilkS")
		)
		(fp_line
			(start -2.0066 2.7559)
			(end -2.0447 2.794)
			(stroke
				(width 0.1524)
				(type default)
			)
			(layer "F.SilkS")
		)
		(fp_line
			(start -2.0066 3.0353)
			(end -1.9685 3.0607)
			(stroke
				(width 0.1524)
				(type default)
			)
			(layer "F.SilkS")
		)
		(fp_line
			(start -1.9685 2.7305)
			(end -2.0066 2.7559)
			(stroke
				(width 0.1524)
				(type default)
			)
			(layer "F.SilkS")
		)
		(fp_line
			(start -1.9685 3.0607)
			(end -1.9304 3.0734)
			(stroke
				(width 0.1524)
				(type default)
			)
			(layer "F.SilkS")
		)
		(fp_line
			(start -1.9304 3.0734)
			(end -1.8796 3.0734)
			(stroke
				(width 0.1524)
				(type default)
			)
			(layer "F.SilkS")
		)
		(fp_line
			(start -1.9177 2.7178)
			(end -1.9685 2.7305)
			(stroke
				(width 0.1524)
				(type default)
			)
			(layer "F.SilkS")
		)
		(fp_line
			(start -1.8796 3.0734)
			(end -1.8161 3.0607)
			(stroke
				(width 0.1524)
				(type default)
			)
			(layer "F.SilkS")
		)
		(fp_line
			(start -1.8542 2.7178)
			(end -1.9177 2.7178)
			(stroke
				(width 0.1524)
				(type default)
			)
			(layer "F.SilkS")
		)
		(fp_line
			(start -1.8161 2.7305)
			(end -1.8542 2.7178)
			(stroke
				(width 0.1524)
				(type default)
			)
			(layer "F.SilkS")
		)
		(fp_line
			(start -1.8161 3.0607)
			(end -1.778 3.0353)
			(stroke
				(width 0.1524)
				(type default)
			)
			(layer "F.SilkS")
		)
		(fp_line
			(start -1.778 2.7559)
			(end -1.8161 2.7305)
			(stroke
				(width 0.1524)
				(type default)
			)
			(layer "F.SilkS")
		)
		(fp_line
			(start -1.778 3.0353)
			(end -1.7526 3.0099)
			(stroke
				(width 0.1524)
				(type default)
			)
			(layer "F.SilkS")
		)
		(fp_line
			(start -1.7526 2.4384)
			(end -1.7526 3.0861)
			(stroke
				(width 0.1524)
				(type default)
			)
			(layer "F.SilkS")
		)
		(fp_line
			(start -1.7526 2.7813)
			(end -1.778 2.7559)
			(stroke
				(width 0.1524)
				(type default)
			)
			(layer "F.SilkS")
		)
		(fp_line
			(start -1.3208 -1.524)
			(end 1.4732 1.397)
			(stroke
				(width 0.1524)
				(type default)
			)
			(layer "F.SilkS")
		)
		(fp_line
			(start -1.1938 -1.27)
			(end -1.1938 1.2954)
			(stroke
				(width 0.254)
				(type default)
			)
			(layer "F.SilkS")
		)
		(fp_line
			(start -1.1938 -1.27)
			(end -0.5588 -1.27)
			(stroke
				(width 0.254)
				(type default)
			)
			(layer "F.SilkS")
		)
		(fp_line
			(start -1.1557 2.4257)
			(end -1.1557 3.0861)
			(stroke
				(width 0.1524)
				(type default)
			)
			(layer "F.SilkS")
		)
		(fp_line
			(start -1.016 4.7498)
			(end -1.016 4.826)
			(stroke
				(width 0.254)
				(type default)
			)
			(layer "F.SilkS")
		)
		(fp_line
			(start -1.016 4.7752)
			(end 0.3048 4.7752)
			(stroke
				(width 0.254)
				(type default)
			)
			(layer "F.SilkS")
		)
		(fp_line
			(start -1.016 4.826)
			(end -0.9906 4.953)
			(stroke
				(width 0.254)
				(type default)
			)
			(layer "F.SilkS")
		)
		(fp_line
			(start -0.9906 4.5974)
			(end -1.016 4.7498)
			(stroke
				(width 0.254)
				(type default)
			)
			(layer "F.SilkS")
		)
		(fp_line
			(start -0.9906 4.953)
			(end -0.9652 5.0292)
			(stroke
				(width 0.254)
				(type default)
			)
			(layer "F.SilkS")
		)
		(fp_line
			(start -0.9652 4.5212)
			(end -0.9906 4.5974)
			(stroke
				(width 0.254)
				(type default)
			)
			(layer "F.SilkS")
		)
		(fp_line
			(start -0.9652 5.0292)
			(end -0.9144 5.1308)
			(stroke
				(width 0.254)
				(type default)
			)
			(layer "F.SilkS")
		)
		(fp_line
			(start -0.9144 4.4196)
			(end -0.9652 4.5212)
			(stroke
				(width 0.254)
				(type default)
			)
			(layer "F.SilkS")
		)
		(fp_line
			(start -0.9144 5.1308)
			(end -0.8382 5.2324)
			(stroke
				(width 0.254)
				(type default)
			)
			(layer "F.SilkS")
		)
		(fp_line
			(start -0.8382 4.318)
			(end -0.9144 4.4196)
			(stroke
				(width 0.254)
				(type default)
			)
			(layer "F.SilkS")
		)
		(fp_line
			(start -0.8382 5.2324)
			(end -0.7112 5.334)
			(stroke
				(width 0.254)
				(type default)
			)
			(layer "F.SilkS")
		)
		(fp_line
			(start -0.8128 4.2926)
			(end -0.8382 4.318)
			(stroke
				(width 0.254)
				(type default)
			)
			(layer "F.SilkS")
		)
		(fp_line
			(start -0.7747 2.6543)
			(end -0.5969 3.0861)
			(stroke
				(width 0.1524)
				(type default)
			)
			(layer "F.SilkS")
		)
		(fp_line
			(start -0.7112 4.2164)
			(end -0.8128 4.2926)
			(stroke
				(width 0.254)
				(type default)
			)
			(layer "F.SilkS")
		)
		(fp_line
			(start -0.7112 5.334)
			(end -0.6096 5.3848)
			(stroke
				(width 0.254)
				(type default)
			)
			(layer "F.SilkS")
		)
		(fp_line
			(start -0.6096 4.1656)
			(end -0.7112 4.2164)
			(stroke
				(width 0.254)
				(type default)
			)
			(layer "F.SilkS")
		)
		(fp_line
			(start -0.6096 5.3848)
			(end -0.5334 5.4102)
			(stroke
				(width 0.254)
				(type default)
			)
			(layer "F.SilkS")
		)
		(fp_line
			(start -0.5969 3.0861)
			(end -0.4191 2.6543)
			(stroke
				(width 0.1524)
				(type default)
			)
			(layer "F.SilkS")
		)
		(fp_line
			(start -0.5588 0)
			(end -1.1938 0)
			(stroke
				(width 0.254)
				(type default)
			)
			(layer "F.SilkS")
		)
		(fp_line
			(start -0.5334 4.1402)
			(end -0.6096 4.1656)
			(stroke
				(width 0.254)
				(type default)
			)
			(layer "F.SilkS")
		)
		(fp_line
			(start -0.5334 5.4102)
			(end -0.381 5.4356)
			(stroke
				(width 0.254)
				(type default)
			)
			(layer "F.SilkS")
		)
		(fp_line
			(start -0.4064 4.1148)
			(end -0.5334 4.1402)
			(stroke
				(width 0.254)
				(type default)
			)
			(layer "F.SilkS")
		)
		(fp_line
			(start -0.381 5.4356)
			(end -0.3556 5.4356)
			(stroke
				(width 0.254)
				(type default)
			)
			(layer "F.SilkS")
		)
		(fp_line
			(start -0.3556 5.4356)
			(end -0.1778 5.4102)
			(stroke
				(width 0.254)
				(type default)
			)
			(layer "F.SilkS")
		)
		(fp_line
			(start -0.3048 4.1148)
			(end -0.4064 4.1148)
			(stroke
				(width 0.254)
				(type default)
			)
			(layer "F.SilkS")
		)
		(fp_line
			(start -0.1778 4.1402)
			(end -0.3048 4.1148)
			(stroke
				(width 0.254)
				(type default)
			)
			(layer "F.SilkS")
		)
		(fp_line
			(start -0.1778 5.4102)
			(end -0.1016 5.3848)
			(stroke
				(width 0.254)
				(type default)
			)
			(layer "F.SilkS")
		)
		(fp_line
			(start -0.1016 4.1656)
			(end -0.1778 4.1402)
			(stroke
				(width 0.254)
				(type default)
			)
			(layer "F.SilkS")
		)
		(fp_line
			(start -0.1016 5.3848)
			(end -0.0508 5.3594)
			(stroke
				(width 0.254)
				(type default)
			)
			(layer "F.SilkS")
		)
		(fp_line
			(start -0.0508 5.3594)
			(end 0.1016 5.2578)
			(stroke
				(width 0.254)
				(type default)
			)
			(layer "F.SilkS")
		)
		(fp_line
			(start -0.0381 2.4257)
			(end -0.0381 3.0861)
			(stroke
				(width 0.1524)
				(type default)
			)
			(layer "F.SilkS")
		)
		(fp_line
			(start 0 4.2164)
			(end -0.1016 4.1656)
			(stroke
				(width 0.254)
				(type default)
			)
			(layer "F.SilkS")
		)
		(fp_line
			(start 0.1016 5.2578)
			(end 0.2032 5.1308)
			(stroke
				(width 0.254)
				(type default)
			)
			(layer "F.SilkS")
		)
		(fp_line
			(start 0.127 4.318)
			(end 0 4.2164)
			(stroke
				(width 0.254)
				(type default)
			)
			(layer "F.SilkS")
		)
		(fp_line
			(start 0.2032 4.4196)
			(end 0.127 4.318)
			(stroke
				(width 0.254)
				(type default)
			)
			(layer "F.SilkS")
		)
		(fp_line
			(start 0.254 4.5212)
			(end 0.2032 4.4196)
			(stroke
				(width 0.254)
				(type default)
			)
			(layer "F.SilkS")
		)
		(fp_line
			(start 0.2794 4.5974)
			(end 0.254 4.5212)
			(stroke
				(width 0.254)
				(type default)
			)
			(layer "F.SilkS")
		)
		(fp_line
			(start 0.3048 4.7752)
			(end 0.2794 4.5974)
			(stroke
				(width 0.254)
				(type default)
			)
			(layer "F.SilkS")
		)
		(fp_line
			(start 0.3556 -1.27)
			(end 0.3556 1.2954)
			(stroke
				(width 0.254)
				(type default)
			)
			(layer "F.SilkS")
		)
		(fp_line
			(start 0.635 4.3434)
			(end 0.9144 4.191)
			(stroke
				(width 0.254)
				(type default)
			)
			(layer "F.SilkS")
		)
		(fp_line
			(start 0.6731 2.3495)
			(end 0.6731 2.3749)
			(stroke
				(width 0.1524)
				(type default)
			)
			(layer "F.SilkS")
		)
		(fp_line
			(start 0.6731 2.3749)
			(end 0.6985 2.4003)
			(stroke
				(width 0.1524)
				(type default)
			)
			(layer "F.SilkS")
		)
		(fp_line
			(start 0.6985 2.3241)
			(end 0.6731 2.3495)
			(stroke
				(width 0.1524)
				(type default)
			)
			(layer "F.SilkS")
		)
		(fp_line
			(start 0.6985 2.4003)
			(end 0.7239 2.3749)
			(stroke
				(width 0.1524)
				(type default)
			)
			(layer "F.SilkS")
		)
		(fp_line
			(start 0.6985 2.6416)
			(end 0.6985 3.0861)
			(stroke
				(width 0.1524)
				(type default)
			)
			(layer "F.SilkS")
		)
		(fp_line
			(start 0.7239 2.3495)
			(end 0.6985 2.3241)
			(stroke
				(width 0.1524)
				(type default)
			)
			(layer "F.SilkS")
		)
		(fp_line
			(start 0.7239 2.3749)
			(end 0.7239 2.3495)
			(stroke
				(width 0.1524)
				(type default)
			)
			(layer "F.SilkS")
		)
		(fp_line
			(start 0.9144 4.191)
			(end 0.9144 5.461)
			(stroke
				(width 0.254)
				(type default)
			)
			(layer "F.SilkS")
		)
		(fp_line
			(start 1.143 2.6543)
			(end 1.143 3.0861)
			(stroke
				(width 0.1524)
				(type default)
			)
			(layer "F.SilkS")
		)
		(fp_line
			(start 1.143 2.7813)
			(end 1.1684 2.7305)
			(stroke
				(width 0.1524)
				(type default)
			)
			(layer "F.SilkS")
		)
		(fp_line
			(start 1.1684 2.7305)
			(end 1.1938 2.6924)
			(stroke
				(width 0.1524)
				(type default)
			)
			(layer "F.SilkS")
		)
		(fp_line
			(start 1.1938 2.6924)
			(end 1.2192 2.667)
			(stroke
				(width 0.1524)
				(type default)
			)
			(layer "F.SilkS")
		)
		(fp_line
			(start 1.2192 2.667)
			(end 1.27 2.6543)
			(stroke
				(width 0.1524)
				(type default)
			)
			(layer "F.SilkS")
		)
		(fp_line
			(start 1.27 2.6543)
			(end 1.3081 2.6543)
			(stroke
				(width 0.1524)
				(type default)
			)
			(layer "F.SilkS")
		)
		(fp_line
			(start 1.3081 2.6543)
			(end 1.3589 2.667)
			(stroke
				(width 0.1524)
				(type default)
			)
			(layer "F.SilkS")
		)
		(fp_line
			(start 1.3589 2.667)
			(end 1.397 2.7178)
			(stroke
				(width 0.1524)
				(type default)
			)
			(layer "F.SilkS")
		)
		(fp_line
			(start 1.397 2.7178)
			(end 1.4224 2.7686)
			(stroke
				(width 0.1524)
				(type default)
			)
			(layer "F.SilkS")
		)
		(fp_line
			(start 1.4224 2.7686)
			(end 1.4224 3.0861)
			(stroke
				(width 0.1524)
				(type default)
			)
			(layer "F.SilkS")
		)
		(fp_line
			(start 1.7018 2.667)
			(end 1.9304 2.667)
			(stroke
				(width 0.1524)
				(type default)
			)
			(layer "F.SilkS")
		)
		(fp_line
			(start 1.8161 2.4511)
			(end 1.8161 3.0861)
			(stroke
				(width 0.1524)
				(type default)
			)
			(layer "F.SilkS")
		)
		(fp_line
			(start 1.8161 3.0861)
			(end 1.9939 3.0734)
			(stroke
				(width 0.1524)
				(type default)
			)
			(layer "F.SilkS")
		)
		(fp_line
			(start 2.1844 2.8575)
			(end 2.1844 2.8956)
			(stroke
				(width 0.1524)
				(type default)
			)
			(layer "F.SilkS")
		)
		(fp_line
			(start 2.1844 2.8956)
			(end 2.1971 2.9464)
			(stroke
				(width 0.1524)
				(type default)
			)
			(layer "F.SilkS")
		)
		(fp_line
			(start 2.1971 2.794)
			(end 2.1844 2.8575)
			(stroke
				(width 0.1524)
				(type default)
			)
			(layer "F.SilkS")
		)
		(fp_line
			(start 2.1971 2.9464)
			(end 2.2098 2.9718)
			(stroke
				(width 0.1524)
				(type default)
			)
			(layer "F.SilkS")
		)
		(fp_line
			(start 2.2098 2.7686)
			(end 2.1971 2.794)
			(stroke
				(width 0.1524)
				(type default)
			)
			(layer "F.SilkS")
		)
		(fp_line
			(start 2.2098 2.9718)
			(end 2.2352 3.0099)
			(stroke
				(width 0.1524)
				(type default)
			)
			(layer "F.SilkS")
		)
		(fp_line
			(start 2.2352 2.7305)
			(end 2.2098 2.7686)
			(stroke
				(width 0.1524)
				(type default)
			)
			(layer "F.SilkS")
		)
		(fp_line
			(start 2.2352 3.0099)
			(end 2.2606 3.0353)
			(stroke
				(width 0.1524)
				(type default)
			)
			(layer "F.SilkS")
		)
		(fp_line
			(start 2.2606 2.7051)
			(end 2.2352 2.7305)
			(stroke
				(width 0.1524)
				(type default)
			)
			(layer "F.SilkS")
		)
		(fp_line
			(start 2.2606 3.0353)
			(end 2.2987 3.0607)
			(stroke
				(width 0.1524)
				(type default)
			)
			(layer "F.SilkS")
		)
		(fp_line
			(start 2.2987 2.6797)
			(end 2.2606 2.7051)
			(stroke
				(width 0.1524)
				(type default)
			)
			(layer "F.SilkS")
		)
		(fp_line
			(start 2.2987 3.0607)
			(end 2.3241 3.0734)
			(stroke
				(width 0.1524)
				(type default)
			)
			(layer "F.SilkS")
		)
		(fp_line
			(start 2.3241 2.667)
			(end 2.2987 2.6797)
			(stroke
				(width 0.1524)
				(type default)
			)
			(layer "F.SilkS")
		)
		(fp_line
			(start 2.3241 3.0734)
			(end 2.3876 3.0861)
			(stroke
				(width 0.1524)
				(type default)
			)
			(layer "F.SilkS")
		)
		(fp_line
			(start 2.3749 2.6543)
			(end 2.3241 2.667)
			(stroke
				(width 0.1524)
				(type default)
			)
			(layer "F.SilkS")
		)
		(fp_line
			(start 2.3876 3.0861)
			(end 2.4384 3.0861)
			(stroke
				(width 0.1524)
				(type default)
			)
			(layer "F.SilkS")
		)
		(fp_line
			(start 2.413 2.6543)
			(end 2.3749 2.6543)
			(stroke
				(width 0.1524)
				(type default)
			)
			(layer "F.SilkS")
		)
		(fp_line
			(start 2.4384 3.0861)
			(end 2.5019 3.0607)
			(stroke
				(width 0.1524)
				(type default)
			)
			(layer "F.SilkS")
		)
		(fp_line
			(start 2.4638 2.667)
			(end 2.413 2.6543)
			(stroke
				(width 0.1524)
				(type default)
			)
			(layer "F.SilkS")
		)
		(fp_line
			(start 2.5019 2.6797)
			(end 2.4638 2.667)
			(stroke
				(width 0.1524)
				(type default)
			)
			(layer "F.SilkS")
		)
		(fp_line
			(start 2.8194 2.667)
			(end 3.048 2.667)
			(stroke
				(width 0.1524)
				(type default)
			)
			(layer "F.SilkS")
		)
		(fp_line
			(start 2.9337 2.4511)
			(end 2.9337 3.0861)
			(stroke
				(width 0.1524)
				(type default)
			)
			(layer "F.SilkS")
		)
		(fp_line
			(start 2.9337 3.0861)
			(end 3.1115 3.0734)
			(stroke
				(width 0.1524)
				(type default)
			)
			(layer "F.SilkS")
		)
		(fp_arc
			(start -1.5748 4.826)
			(mid -0.985652 3.828319)
			(end 0.127 3.5052)
			(stroke
				(width 0.1524)
				(type default)
			)
			(layer "F.SilkS")
		)
		(fp_arc
			(start -0.5588 -1.27)
			(mid 0.0762 -0.635)
			(end -0.5588 0)
			(stroke
				(width 0.254)
				(type default)
			)
			(layer "F.SilkS")
		)
		(fp_arc
			(start -0.127 3.5052)
			(mid 0.985653 3.828369)
			(end 1.5748 4.826)
			(stroke
				(width 0.1524)
				(type default)
			)
			(layer "F.SilkS")
		)
		(fp_arc
			(start 0.1524 6.096)
			(mid -0.964559 5.805562)
			(end -1.5748 4.826)
			(stroke
				(width 0.1524)
				(type default)
			)
			(layer "F.SilkS")
		)
		(fp_arc
			(start 1.5748 4.826)
			(mid 0.964538 5.805581)
			(end -0.1524 6.096)
			(stroke
				(width 0.1524)
				(type default)
			)
			(layer "F.SilkS")
		)
		(fp_circle
			(center -1.8923 2.8956)
			(end -1.71196 2.8956)
			(stroke
				(width 0.1524)
				(type default)
			)
			(fill no)
			(layer "F.SilkS")
		)
		(fp_circle
			(center 0 0)
			(end 2.03454 0)
			(stroke
				(width 0.1524)
				(type default)
			)
			(fill no)
			(layer "F.SilkS")
		)
		(fp_circle
			(center 0.9652 0.6858)
			(end 1.57734 0.6858)
			(stroke
				(width 0.254)
				(type default)
			)
			(fill no)
			(layer "F.SilkS")
		)
	)
	(footprint ""
		(layer "F.Cu")
		(at 163.576 -63.881 180)
		(property "Reference" "PC614"
			(at 0 0 180)
			(layer "F.SilkS")
			(hide yes)
			(effects
				(font
					(size 1.27 1.27)
				)
			)
		)
		(property "Value" ""
			(at 0 0 180)
			(layer "F.Fab")
			(effects
				(font
					(size 1.27 1.27)
				)
			)
		)
		(duplicate_pad_numbers_are_jumpers no)
		(fp_line
			(start 1.2954 0.5842)
			(end -1.2954 0.5842)
			(stroke
				(width 0.1524)
				(type default)
			)
			(layer "F.SilkS")
		)
		(fp_line
			(start 1.2954 -0.5842)
			(end 1.2954 0.5842)
			(stroke
				(width 0.1524)
				(type default)
			)
			(layer "F.SilkS")
		)
		(fp_line
			(start -1.2954 0.5842)
			(end -1.2954 -0.5842)
			(stroke
				(width 0.1524)
				(type default)
			)
			(layer "F.SilkS")
		)
		(fp_line
			(start -1.2954 -0.5842)
			(end 1.2954 -0.5842)
			(stroke
				(width 0.1524)
				(type default)
			)
			(layer "F.SilkS")
		)
		(fp_line
			(start 1.1938 0.4064)
			(end 0.8636 0.4064)
			(stroke
				(width 0.1)
				(type default)
			)
			(layer "F.Fab")
		)
		(fp_line
			(start 1.1938 -0.4064)
			(end 1.1938 0.4064)
			(stroke
				(width 0.1)
				(type default)
			)
			(layer "F.Fab")
		)
		(fp_line
			(start 0.8636 0.4572)
			(end -0.8636 0.4572)
			(stroke
				(width 0.1)
				(type default)
			)
			(layer "F.Fab")
		)
		(fp_line
			(start 0.8636 0.4064)
			(end 0.8636 0.4572)
			(stroke
				(width 0.1)
				(type default)
			)
			(layer "F.Fab")
		)
		(fp_line
			(start 0.8636 -0.4064)
			(end 1.1938 -0.4064)
			(stroke
				(width 0.1)
				(type default)
			)
			(layer "F.Fab")
		)
		(fp_line
			(start 0.8636 -0.4572)
			(end 0.8636 -0.4064)
			(stroke
				(width 0.1)
				(type default)
			)
			(layer "F.Fab")
		)
		(fp_line
			(start -0.8636 0.4572)
			(end -0.8636 0.4064)
			(stroke
				(width 0.1)
				(type default)
			)
			(layer "F.Fab")
		)
		(fp_line
			(start -0.8636 0.4064)
			(end -1.1938 0.4064)
			(stroke
				(width 0.1)
				(type default)
			)
			(layer "F.Fab")
		)
		(fp_line
			(start -0.8636 -0.4064)
			(end -0.8636 -0.4572)
			(stroke
				(width 0.1)
				(type default)
			)
			(layer "F.Fab")
		)
		(fp_line
			(start -0.8636 -0.4572)
			(end 0.8636 -0.4572)
			(stroke
				(width 0.1)
				(type default)
			)
			(layer "F.Fab")
		)
		(fp_line
			(start -1.1938 0.4064)
			(end -1.1938 -0.4064)
			(stroke
				(width 0.1)
				(type default)
			)
			(layer "F.Fab")
		)
		(fp_line
			(start -1.1938 -0.4064)
			(end -0.8636 -0.4064)
			(stroke
				(width 0.1)
				(type default)
			)
			(layer "F.Fab")
		)
		(pad "1" smd rect
			(at -0.7366 0 90)
			(size 0.7112 0.8128)
			(layers "F.Cu" "F.Mask" "F.Paste")
			(net "P52V_HS2_ESTART")
		)
		(pad "2" smd rect
			(at 0.7366 0 90)
			(size 0.7112 0.8128)
			(layers "F.Cu" "F.Mask" "F.Paste")
			(net "GND1_FIELD_SIGNAL")
		)
	)
	(footprint ""
		(layer "F.Cu")
		(at 256.798318 -151.939498 90)
		(property "Reference" "J10"
			(at -3.222498 -5.819648 90)
			(unlocked yes)
			(layer "F.SilkS")
			(effects
				(font
					(size 0.7874 0.5842)
					(thickness 0.1524)
				)
				(justify left)
			)
		)
		(property "Value" ""
			(at 0 0 90)
			(layer "F.Fab")
			(effects
				(font
					(size 1.27 1.27)
				)
			)
		)
		(duplicate_pad_numbers_are_jumpers no)
		(fp_line
			(start 3.330702 -4.771136)
			(end 0 4.011168)
			(stroke
				(width 0.1524)
				(type default)
			)
			(layer "F.SilkS")
		)
		(fp_line
			(start -3.330702 -4.771136)
			(end 3.330702 -4.771136)
			(stroke
				(width 0.1524)
				(type default)
			)
			(layer "F.SilkS")
		)
		(fp_line
			(start 0 4.011168)
			(end -3.330702 -4.771136)
			(stroke
				(width 0.1524)
				(type default)
			)
			(layer "F.SilkS")
		)
		(fp_line
			(start 3.330702 -4.771136)
			(end 0 4.011168)
			(stroke
				(width 0.1)
				(type default)
			)
			(layer "F.Fab")
		)
		(fp_line
			(start -3.330702 -4.771136)
			(end 3.330702 -4.771136)
			(stroke
				(width 0.1)
				(type default)
			)
			(layer "F.Fab")
		)
		(fp_line
			(start 0 4.011168)
			(end -3.330702 -4.771136)
			(stroke
				(width 0.1)
				(type default)
			)
			(layer "F.Fab")
		)
		(pad "1" thru_hole circle
			(at 0 0 90)
			(size 2.159 2.159)
			(drill 1.7018)
			(layers "*.Cu" "*.Mask")
			(remove_unused_layers no)
			(net "GND3")
			(clearance 0.0254)
			(thermal_gap 0.0254)
		)
		(pad "2" thru_hole circle
			(at -1.27 -3.348736 90)
			(size 2.159 2.159)
			(drill 1.7018)
			(layers "*.Cu" "*.Mask")
			(remove_unused_layers no)
			(net "TDR_SE_50_OHM_TOP")
			(clearance 0.0254)
			(thermal_gap 0.0254)
		)
		(pad "3" thru_hole circle
			(at 1.27 -3.348736 90)
			(size 2.159 2.159)
			(drill 1.7018)
			(layers "*.Cu" "*.Mask")
			(remove_unused_layers no)
			(net "TDR_SE_50_OHM_TOP")
			(clearance 0.0254)
			(thermal_gap 0.0254)
		)
	)
	(footprint ""
		(layer "F.Cu")
		(at 431.8254 -31.3436 90)
		(property "Reference" "R62"
			(at 0 0 90)
			(layer "F.SilkS")
			(hide yes)
			(effects
				(font
					(size 1.27 1.27)
				)
			)
		)
		(property "Value" ""
			(at 0 0 90)
			(layer "F.Fab")
			(effects
				(font
					(size 1.27 1.27)
				)
			)
		)
		(duplicate_pad_numbers_are_jumpers no)
		(fp_line
			(start 0.7874 -0.4064)
			(end 0.7874 0.4064)
			(stroke
				(width 0.1524)
				(type default)
			)
			(layer "F.SilkS")
		)
		(fp_line
			(start -0.7874 -0.4064)
			(end 0.7874 -0.4064)
			(stroke
				(width 0.1524)
				(type default)
			)
			(layer "F.SilkS")
		)
		(fp_line
			(start 0.7874 0.4064)
			(end -0.7874 0.4064)
			(stroke
				(width 0.1524)
				(type default)
			)
			(layer "F.SilkS")
		)
		(fp_line
			(start -0.7874 0.4064)
			(end -0.7874 -0.4064)
			(stroke
				(width 0.1524)
				(type default)
			)
			(layer "F.SilkS")
		)
		(fp_line
			(start -0.12065 -0.305054)
			(end -0.12065 -0.2794)
			(stroke
				(width 0.1)
				(type default)
			)
			(layer "F.Fab")
		)
		(fp_line
			(start -0.67945 -0.305054)
			(end -0.12065 -0.305054)
			(stroke
				(width 0.1)
				(type default)
			)
			(layer "F.Fab")
		)
		(fp_line
			(start 0.67945 -0.3048)
			(end 0.67945 0.3048)
			(stroke
				(width 0.1)
				(type default)
			)
			(layer "F.Fab")
		)
		(fp_line
			(start 0.12065 -0.3048)
			(end 0.67945 -0.3048)
			(stroke
				(width 0.1)
				(type default)
			)
			(layer "F.Fab")
		)
		(fp_line
			(start 0.12065 -0.2794)
			(end 0.12065 -0.3048)
			(stroke
				(width 0.1)
				(type default)
			)
			(layer "F.Fab")
		)
		(fp_line
			(start -0.12065 -0.2794)
			(end 0.12065 -0.2794)
			(stroke
				(width 0.1)
				(type default)
			)
			(layer "F.Fab")
		)
		(fp_line
			(start 0.120396 0.2794)
			(end -0.12065 0.2794)
			(stroke
				(width 0.1)
				(type default)
			)
			(layer "F.Fab")
		)
		(fp_line
			(start -0.12065 0.2794)
			(end -0.12065 0.3048)
			(stroke
				(width 0.1)
				(type default)
			)
			(layer "F.Fab")
		)
		(fp_line
			(start 0.67945 0.3048)
			(end 0.120396 0.3048)
			(stroke
				(width 0.1)
				(type default)
			)
			(layer "F.Fab")
		)
		(fp_line
			(start 0.120396 0.3048)
			(end 0.120396 0.2794)
			(stroke
				(width 0.1)
				(type default)
			)
			(layer "F.Fab")
		)
		(fp_line
			(start -0.12065 0.3048)
			(end -0.67945 0.3048)
			(stroke
				(width 0.1)
				(type default)
			)
			(layer "F.Fab")
		)
		(fp_line
			(start -0.67945 0.3048)
			(end -0.67945 -0.305054)
			(stroke
				(width 0.1)
				(type default)
			)
			(layer "F.Fab")
		)
		(pad "1" smd circle
			(at -0.40005 0 90)
			(size 0 0)
			(layers "F.Cu" "F.Mask" "F.Paste")
			(net "SMB_FRU_DAT")
		)
		(pad "2" smd circle
			(at 0.40005 0 90)
			(size 0 0)
			(layers "F.Cu" "F.Mask" "F.Paste")
			(net "SMB_PDB_MISC_SDA")
		)
	)
	(footprint ""
		(layer "F.Cu")
		(at 169.672 -80.772 -90)
		(property "Reference" "C92"
			(at 0 0 270)
			(layer "F.SilkS")
			(hide yes)
			(effects
				(font
					(size 1.27 1.27)
				)
			)
		)
		(property "Value" ""
			(at 0 0 270)
			(layer "F.Fab")
			(effects
				(font
					(size 1.27 1.27)
				)
			)
		)
		(duplicate_pad_numbers_are_jumpers no)
		(fp_line
			(start -1.2954 0.5842)
			(end -1.2954 -0.5842)
			(stroke
				(width 0.1524)
				(type default)
			)
			(layer "F.SilkS")
		)
		(fp_line
			(start 1.2954 0.5842)
			(end -1.2954 0.5842)
			(stroke
				(width 0.1524)
				(type default)
			)
			(layer "F.SilkS")
		)
		(fp_line
			(start -1.2954 -0.5842)
			(end 1.2954 -0.5842)
			(stroke
				(width 0.1524)
				(type default)
			)
			(layer "F.SilkS")
		)
		(fp_line
			(start 1.2954 -0.5842)
			(end 1.2954 0.5842)
			(stroke
				(width 0.1524)
				(type default)
			)
			(layer "F.SilkS")
		)
		(fp_line
			(start -0.8636 0.4572)
			(end -0.8636 0.4064)
			(stroke
				(width 0.1)
				(type default)
			)
			(layer "F.Fab")
		)
		(fp_line
			(start 0.8636 0.4572)
			(end -0.8636 0.4572)
			(stroke
				(width 0.1)
				(type default)
			)
			(layer "F.Fab")
		)
		(fp_line
			(start -1.1938 0.4064)
			(end -1.1938 -0.4064)
			(stroke
				(width 0.1)
				(type default)
			)
			(layer "F.Fab")
		)
		(fp_line
			(start -0.8636 0.4064)
			(end -1.1938 0.4064)
			(stroke
				(width 0.1)
				(type default)
			)
			(layer "F.Fab")
		)
		(fp_line
			(start 0.8636 0.4064)
			(end 0.8636 0.4572)
			(stroke
				(width 0.1)
				(type default)
			)
			(layer "F.Fab")
		)
		(fp_line
			(start 1.1938 0.4064)
			(end 0.8636 0.4064)
			(stroke
				(width 0.1)
				(type default)
			)
			(layer "F.Fab")
		)
		(fp_line
			(start -1.1938 -0.4064)
			(end -0.8636 -0.4064)
			(stroke
				(width 0.1)
				(type default)
			)
			(layer "F.Fab")
		)
		(fp_line
			(start -0.8636 -0.4064)
			(end -0.8636 -0.4572)
			(stroke
				(width 0.1)
				(type default)
			)
			(layer "F.Fab")
		)
		(fp_line
			(start 0.8636 -0.4064)
			(end 1.1938 -0.4064)
			(stroke
				(width 0.1)
				(type default)
			)
			(layer "F.Fab")
		)
		(fp_line
			(start 1.1938 -0.4064)
			(end 1.1938 0.4064)
			(stroke
				(width 0.1)
				(type default)
			)
			(layer "F.Fab")
		)
		(fp_line
			(start -0.8636 -0.4572)
			(end 0.8636 -0.4572)
			(stroke
				(width 0.1)
				(type default)
			)
			(layer "F.Fab")
		)
		(fp_line
			(start 0.8636 -0.4572)
			(end 0.8636 -0.4064)
			(stroke
				(width 0.1)
				(type default)
			)
			(layer "F.Fab")
		)
		(pad "1" smd rect
			(at -0.7366 0 180)
			(size 0.7112 0.8128)
			(layers "F.Cu" "F.Mask" "F.Paste")
			(net "FM_HS2_EN_BUSBAR")
		)
		(pad "2" smd rect
			(at 0.7366 0 180)
			(size 0.7112 0.8128)
			(layers "F.Cu" "F.Mask" "F.Paste")
			(net "GND")
		)
	)
	(footprint ""
		(layer "B.Cu")
		(at 161.717736 -66.04)
		(property "Reference" "R5872"
			(at 0 0 0)
			(layer "B.SilkS")
			(hide yes)
			(effects
				(font
					(size 1.27 1.27)
				)
				(justify mirror)
			)
		)
		(property "Value" ""
			(at 0 0 0)
			(layer "B.Fab")
			(effects
				(font
					(size 1.27 1.27)
				)
				(justify mirror)
			)
		)
		(duplicate_pad_numbers_are_jumpers no)
		(fp_line
			(start -0.7874 -0.4064)
			(end -0.7874 0.4064)
			(stroke
				(width 0.1524)
				(type default)
			)
			(layer "B.SilkS")
		)
		(fp_line
			(start -0.7874 0.4064)
			(end 0.7874 0.4064)
			(stroke
				(width 0.1524)
				(type default)
			)
			(layer "B.SilkS")
		)
		(fp_line
			(start 0.7874 -0.4064)
			(end -0.7874 -0.4064)
			(stroke
				(width 0.1524)
				(type default)
			)
			(layer "B.SilkS")
		)
		(fp_line
			(start 0.7874 0.4064)
			(end 0.7874 -0.4064)
			(stroke
				(width 0.1524)
				(type default)
			)
			(layer "B.SilkS")
		)
		(fp_line
			(start -0.67945 -0.3048)
			(end -0.67945 0.3048)
			(stroke
				(width 0.1)
				(type default)
			)
			(layer "B.Fab")
		)
		(fp_line
			(start -0.67945 0.3048)
			(end -0.120396 0.3048)
			(stroke
				(width 0.1)
				(type default)
			)
			(layer "B.Fab")
		)
		(fp_line
			(start -0.12065 -0.3048)
			(end -0.67945 -0.3048)
			(stroke
				(width 0.1)
				(type default)
			)
			(layer "B.Fab")
		)
		(fp_line
			(start -0.12065 -0.2794)
			(end -0.12065 -0.3048)
			(stroke
				(width 0.1)
				(type default)
			)
			(layer "B.Fab")
		)
		(fp_line
			(start -0.120396 0.2794)
			(end 0.12065 0.2794)
			(stroke
				(width 0.1)
				(type default)
			)
			(layer "B.Fab")
		)
		(fp_line
			(start -0.120396 0.3048)
			(end -0.120396 0.2794)
			(stroke
				(width 0.1)
				(type default)
			)
			(layer "B.Fab")
		)
		(fp_line
			(start 0.12065 -0.305054)
			(end 0.12065 -0.2794)
			(stroke
				(width 0.1)
				(type default)
			)
			(layer "B.Fab")
		)
		(fp_line
			(start 0.12065 -0.2794)
			(end -0.12065 -0.2794)
			(stroke
				(width 0.1)
				(type default)
			)
			(layer "B.Fab")
		)
		(fp_line
			(start 0.12065 0.2794)
			(end 0.12065 0.3048)
			(stroke
				(width 0.1)
				(type default)
			)
			(layer "B.Fab")
		)
		(fp_line
			(start 0.12065 0.3048)
			(end 0.67945 0.3048)
			(stroke
				(width 0.1)
				(type default)
			)
			(layer "B.Fab")
		)
		(fp_line
			(start 0.67945 -0.305054)
			(end 0.12065 -0.305054)
			(stroke
				(width 0.1)
				(type default)
			)
			(layer "B.Fab")
		)
		(fp_line
			(start 0.67945 0.3048)
			(end 0.67945 -0.305054)
			(stroke
				(width 0.1)
				(type default)
			)
			(layer "B.Fab")
		)
		(pad "1" smd circle
			(at 0.40005 0 180)
			(size 0 0)
			(layers "B.Cu" "B.Mask" "B.Paste")
			(net "SMB_P52V_PDB_SDA")
		)
		(pad "2" smd circle
			(at -0.40005 0 180)
			(size 0 0)
			(layers "B.Cu" "B.Mask" "B.Paste")
			(net "SMB_P52V_HS2_SDAO")
		)
	)
	(footprint ""
		(layer "B.Cu")
		(at 336.3214 -39.37 -90)
		(property "Reference" "R5861"
			(at 0 0 90)
			(layer "B.SilkS")
			(hide yes)
			(effects
				(font
					(size 1.27 1.27)
				)
				(justify mirror)
			)
		)
		(property "Value" ""
			(at 0 0 90)
			(layer "B.Fab")
			(effects
				(font
					(size 1.27 1.27)
				)
				(justify mirror)
			)
		)
		(duplicate_pad_numbers_are_jumpers no)
		(fp_line
			(start -0.7874 0.4064)
			(end 0.7874 0.4064)
			(stroke
				(width 0.1524)
				(type default)
			)
			(layer "B.SilkS")
		)
		(fp_line
			(start 0.7874 0.4064)
			(end 0.7874 -0.4064)
			(stroke
				(width 0.1524)
				(type default)
			)
			(layer "B.SilkS")
		)
		(fp_line
			(start -0.7874 -0.4064)
			(end -0.7874 0.4064)
			(stroke
				(width 0.1524)
				(type default)
			)
			(layer "B.SilkS")
		)
		(fp_line
			(start 0.7874 -0.4064)
			(end -0.7874 -0.4064)
			(stroke
				(width 0.1524)
				(type default)
			)
			(layer "B.SilkS")
		)
		(fp_line
			(start -0.67945 0.3048)
			(end -0.120396 0.3048)
			(stroke
				(width 0.1)
				(type default)
			)
			(layer "B.Fab")
		)
		(fp_line
			(start -0.120396 0.3048)
			(end -0.120396 0.2794)
			(stroke
				(width 0.1)
				(type default)
			)
			(layer "B.Fab")
		)
		(fp_line
			(start 0.12065 0.3048)
			(end 0.67945 0.3048)
			(stroke
				(width 0.1)
				(type default)
			)
			(layer "B.Fab")
		)
		(fp_line
			(start 0.67945 0.3048)
			(end 0.67945 -0.305054)
			(stroke
				(width 0.1)
				(type default)
			)
			(layer "B.Fab")
		)
		(fp_line
			(start -0.120396 0.2794)
			(end 0.12065 0.2794)
			(stroke
				(width 0.1)
				(type default)
			)
			(layer "B.Fab")
		)
		(fp_line
			(start 0.12065 0.2794)
			(end 0.12065 0.3048)
			(stroke
				(width 0.1)
				(type default)
			)
			(layer "B.Fab")
		)
		(fp_line
			(start -0.12065 -0.2794)
			(end -0.12065 -0.3048)
			(stroke
				(width 0.1)
				(type default)
			)
			(layer "B.Fab")
		)
		(fp_line
			(start 0.12065 -0.2794)
			(end -0.12065 -0.2794)
			(stroke
				(width 0.1)
				(type default)
			)
			(layer "B.Fab")
		)
		(fp_line
			(start -0.67945 -0.3048)
			(end -0.67945 0.3048)
			(stroke
				(width 0.1)
				(type default)
			)
			(layer "B.Fab")
		)
		(fp_line
			(start -0.12065 -0.3048)
			(end -0.67945 -0.3048)
			(stroke
				(width 0.1)
				(type default)
			)
			(layer "B.Fab")
		)
		(fp_line
			(start 0.12065 -0.305054)
			(end 0.12065 -0.2794)
			(stroke
				(width 0.1)
				(type default)
			)
			(layer "B.Fab")
		)
		(fp_line
			(start 0.67945 -0.305054)
			(end 0.12065 -0.305054)
			(stroke
				(width 0.1)
				(type default)
			)
			(layer "B.Fab")
		)
		(pad "1" smd circle
			(at 0.40005 0 90)
			(size 0 0)
			(layers "B.Cu" "B.Mask" "B.Paste")
			(net "P52V_HS1_1272_GATE")
		)
		(pad "2" smd circle
			(at -0.40005 0 90)
			(size 0 0)
			(layers "B.Cu" "B.Mask" "B.Paste")
			(net "P52V_HS1_GATE2_R")
		)
	)
	(footprint ""
		(layer "B.Cu")
		(at 179.9844 -49.022 -90)
		(property "Reference" "R5893"
			(at 0 0 90)
			(layer "B.SilkS")
			(hide yes)
			(effects
				(font
					(size 1.27 1.27)
				)
				(justify mirror)
			)
		)
		(property "Value" ""
			(at 0 0 90)
			(layer "B.Fab")
			(effects
				(font
					(size 1.27 1.27)
				)
				(justify mirror)
			)
		)
		(duplicate_pad_numbers_are_jumpers no)
		(fp_line
			(start -1.651 0.8382)
			(end 1.651 0.8382)
			(stroke
				(width 0.1524)
				(type default)
			)
			(layer "B.SilkS")
		)
		(fp_line
			(start 1.651 0.8382)
			(end 1.651 -0.8382)
			(stroke
				(width 0.1524)
				(type default)
			)
			(layer "B.SilkS")
		)
		(fp_line
			(start -1.651 -0.8382)
			(end -1.651 0.8382)
			(stroke
				(width 0.1524)
				(type default)
			)
			(layer "B.SilkS")
		)
		(fp_line
			(start 1.651 -0.8382)
			(end -1.651 -0.8382)
			(stroke
				(width 0.1524)
				(type default)
			)
			(layer "B.SilkS")
		)
		(fp_line
			(start -1.560576 0.7366)
			(end -1.560576 -0.7366)
			(stroke
				(width 0.1)
				(type default)
			)
			(layer "B.Fab")
		)
		(fp_line
			(start -1.524 0.7366)
			(end -1.560576 0.7366)
			(stroke
				(width 0.1)
				(type default)
			)
			(layer "B.Fab")
		)
		(fp_line
			(start 1.524 0.7366)
			(end -1.524 0.7366)
			(stroke
				(width 0.1)
				(type default)
			)
			(layer "B.Fab")
		)
		(fp_line
			(start 1.559814 0.7366)
			(end 1.524 0.7366)
			(stroke
				(width 0.1)
				(type default)
			)
			(layer "B.Fab")
		)
		(fp_line
			(start -1.560576 -0.7366)
			(end -1.524 -0.7366)
			(stroke
				(width 0.1)
				(type default)
			)
			(layer "B.Fab")
		)
		(fp_line
			(start -1.524 -0.7366)
			(end 1.524 -0.7366)
			(stroke
				(width 0.1)
				(type default)
			)
			(layer "B.Fab")
		)
		(fp_line
			(start 1.524 -0.7366)
			(end 1.559814 -0.7366)
			(stroke
				(width 0.1)
				(type default)
			)
			(layer "B.Fab")
		)
		(fp_line
			(start 1.559814 -0.7366)
			(end 1.559814 0.7366)
			(stroke
				(width 0.1)
				(type default)
			)
			(layer "B.Fab")
		)
		(pad "1" smd rect
			(at 0.94996 0 270)
			(size 1.1176 1.3716)
			(layers "B.Cu" "B.Mask" "B.Paste")
			(net "P52V_2_FUSE_1")
		)
		(pad "2" smd rect
			(at -0.94996 0 270)
			(size 1.1176 1.3716)
			(layers "B.Cu" "B.Mask" "B.Paste")
			(net "FM_HS2_EN_FUSE")
		)
	)
	(footprint ""
		(layer "B.Cu")
		(at 156.637736 -79.375 -90)
		(property "Reference" "R5876"
			(at 0 0 90)
			(layer "B.SilkS")
			(hide yes)
			(effects
				(font
					(size 1.27 1.27)
				)
				(justify mirror)
			)
		)
		(property "Value" ""
			(at 0 0 90)
			(layer "B.Fab")
			(effects
				(font
					(size 1.27 1.27)
				)
				(justify mirror)
			)
		)
		(duplicate_pad_numbers_are_jumpers no)
		(fp_line
			(start -0.7874 0.4064)
			(end 0.7874 0.4064)
			(stroke
				(width 0.1524)
				(type default)
			)
			(layer "B.SilkS")
		)
		(fp_line
			(start 0.7874 0.4064)
			(end 0.7874 -0.4064)
			(stroke
				(width 0.1524)
				(type default)
			)
			(layer "B.SilkS")
		)
		(fp_line
			(start -0.7874 -0.4064)
			(end -0.7874 0.4064)
			(stroke
				(width 0.1524)
				(type default)
			)
			(layer "B.SilkS")
		)
		(fp_line
			(start 0.7874 -0.4064)
			(end -0.7874 -0.4064)
			(stroke
				(width 0.1524)
				(type default)
			)
			(layer "B.SilkS")
		)
		(fp_line
			(start -0.67945 0.3048)
			(end -0.120396 0.3048)
			(stroke
				(width 0.1)
				(type default)
			)
			(layer "B.Fab")
		)
		(fp_line
			(start -0.120396 0.3048)
			(end -0.120396 0.2794)
			(stroke
				(width 0.1)
				(type default)
			)
			(layer "B.Fab")
		)
		(fp_line
			(start 0.12065 0.3048)
			(end 0.67945 0.3048)
			(stroke
				(width 0.1)
				(type default)
			)
			(layer "B.Fab")
		)
		(fp_line
			(start 0.67945 0.3048)
			(end 0.67945 -0.305054)
			(stroke
				(width 0.1)
				(type default)
			)
			(layer "B.Fab")
		)
		(fp_line
			(start -0.120396 0.2794)
			(end 0.12065 0.2794)
			(stroke
				(width 0.1)
				(type default)
			)
			(layer "B.Fab")
		)
		(fp_line
			(start 0.12065 0.2794)
			(end 0.12065 0.3048)
			(stroke
				(width 0.1)
				(type default)
			)
			(layer "B.Fab")
		)
		(fp_line
			(start -0.12065 -0.2794)
			(end -0.12065 -0.3048)
			(stroke
				(width 0.1)
				(type default)
			)
			(layer "B.Fab")
		)
		(fp_line
			(start 0.12065 -0.2794)
			(end -0.12065 -0.2794)
			(stroke
				(width 0.1)
				(type default)
			)
			(layer "B.Fab")
		)
		(fp_line
			(start -0.67945 -0.3048)
			(end -0.67945 0.3048)
			(stroke
				(width 0.1)
				(type default)
			)
			(layer "B.Fab")
		)
		(fp_line
			(start -0.12065 -0.3048)
			(end -0.67945 -0.3048)
			(stroke
				(width 0.1)
				(type default)
			)
			(layer "B.Fab")
		)
		(fp_line
			(start 0.12065 -0.305054)
			(end 0.12065 -0.2794)
			(stroke
				(width 0.1)
				(type default)
			)
			(layer "B.Fab")
		)
		(fp_line
			(start 0.67945 -0.305054)
			(end 0.12065 -0.305054)
			(stroke
				(width 0.1)
				(type default)
			)
			(layer "B.Fab")
		)
		(pad "1" smd circle
			(at 0.40005 0 90)
			(size 0 0)
			(layers "B.Cu" "B.Mask" "B.Paste")
			(net "P52V_HS2_ADR1")
		)
		(pad "2" smd circle
			(at -0.40005 0 90)
			(size 0 0)
			(layers "B.Cu" "B.Mask" "B.Paste")
			(net "GND1_FIELD_SIGNAL")
		)
	)
	(footprint ""
		(layer "B.Cu")
		(at 278.4094 -66.929)
		(property "Reference" "R147"
			(at 0 0 0)
			(layer "B.SilkS")
			(hide yes)
			(effects
				(font
					(size 1.27 1.27)
				)
				(justify mirror)
			)
		)
		(property "Value" ""
			(at 0 0 0)
			(layer "B.Fab")
			(effects
				(font
					(size 1.27 1.27)
				)
				(justify mirror)
			)
		)
		(duplicate_pad_numbers_are_jumpers no)
		(fp_line
			(start -0.7874 -0.4064)
			(end -0.7874 0.4064)
			(stroke
				(width 0.1524)
				(type default)
			)
			(layer "B.SilkS")
		)
		(fp_line
			(start -0.7874 0.4064)
			(end 0.7874 0.4064)
			(stroke
				(width 0.1524)
				(type default)
			)
			(layer "B.SilkS")
		)
		(fp_line
			(start 0.7874 -0.4064)
			(end -0.7874 -0.4064)
			(stroke
				(width 0.1524)
				(type default)
			)
			(layer "B.SilkS")
		)
		(fp_line
			(start 0.7874 0.4064)
			(end 0.7874 -0.4064)
			(stroke
				(width 0.1524)
				(type default)
			)
			(layer "B.SilkS")
		)
		(fp_line
			(start -0.67945 -0.3048)
			(end -0.67945 0.3048)
			(stroke
				(width 0.1)
				(type default)
			)
			(layer "B.Fab")
		)
		(fp_line
			(start -0.67945 0.3048)
			(end -0.120396 0.3048)
			(stroke
				(width 0.1)
				(type default)
			)
			(layer "B.Fab")
		)
		(fp_line
			(start -0.12065 -0.3048)
			(end -0.67945 -0.3048)
			(stroke
				(width 0.1)
				(type default)
			)
			(layer "B.Fab")
		)
		(fp_line
			(start -0.12065 -0.2794)
			(end -0.12065 -0.3048)
			(stroke
				(width 0.1)
				(type default)
			)
			(layer "B.Fab")
		)
		(fp_line
			(start -0.120396 0.2794)
			(end 0.12065 0.2794)
			(stroke
				(width 0.1)
				(type default)
			)
			(layer "B.Fab")
		)
		(fp_line
			(start -0.120396 0.3048)
			(end -0.120396 0.2794)
			(stroke
				(width 0.1)
				(type default)
			)
			(layer "B.Fab")
		)
		(fp_line
			(start 0.12065 -0.305054)
			(end 0.12065 -0.2794)
			(stroke
				(width 0.1)
				(type default)
			)
			(layer "B.Fab")
		)
		(fp_line
			(start 0.12065 -0.2794)
			(end -0.12065 -0.2794)
			(stroke
				(width 0.1)
				(type default)
			)
			(layer "B.Fab")
		)
		(fp_line
			(start 0.12065 0.2794)
			(end 0.12065 0.3048)
			(stroke
				(width 0.1)
				(type default)
			)
			(layer "B.Fab")
		)
		(fp_line
			(start 0.12065 0.3048)
			(end 0.67945 0.3048)
			(stroke
				(width 0.1)
				(type default)
			)
			(layer "B.Fab")
		)
		(fp_line
			(start 0.67945 -0.305054)
			(end 0.12065 -0.305054)
			(stroke
				(width 0.1)
				(type default)
			)
			(layer "B.Fab")
		)
		(fp_line
			(start 0.67945 0.3048)
			(end 0.67945 -0.305054)
			(stroke
				(width 0.1)
				(type default)
			)
			(layer "B.Fab")
		)
		(pad "1" smd circle
			(at 0.40005 0 180)
			(size 0 0)
			(layers "B.Cu" "B.Mask" "B.Paste")
			(net "P3V3_AUX")
		)
		(pad "2" smd circle
			(at -0.40005 0 180)
			(size 0 0)
			(layers "B.Cu" "B.Mask" "B.Paste")
			(net "SMB_P52V_PDB_SDA")
		)
	)
	(footprint ""
		(layer "B.Cu")
		(at 108.7374 -55.626 -90)
		(property "Reference" "PD17"
			(at 3.46837 -1.0668 0)
			(unlocked yes)
			(layer "B.SilkS")
			(effects
				(font
					(size 0.7874 0.5842)
					(thickness 0.1524)
				)
				(justify left mirror)
			)
		)
		(property "Value" ""
			(at 0 0 90)
			(layer "B.Fab")
			(effects
				(font
					(size 1.27 1.27)
				)
				(justify mirror)
			)
		)
		(duplicate_pad_numbers_are_jumpers no)
		(fp_line
			(start -2.032 0.7112)
			(end 1.651 0.7112)
			(stroke
				(width 0.1524)
				(type default)
			)
			(layer "B.SilkS")
		)
		(fp_line
			(start 1.651 0.7112)
			(end 1.651 -0.7112)
			(stroke
				(width 0.1524)
				(type default)
			)
			(layer "B.SilkS")
		)
		(fp_line
			(start -1.778 0.6858)
			(end -1.778 -0.6858)
			(stroke
				(width 0.1524)
				(type default)
			)
			(layer "B.SilkS")
		)
		(fp_line
			(start 0.299974 0.500126)
			(end -0.199898 0)
			(stroke
				(width 0.1524)
				(type default)
			)
			(layer "B.SilkS")
		)
		(fp_line
			(start -0.199898 0)
			(end 0.299974 -0.500126)
			(stroke
				(width 0.1524)
				(type default)
			)
			(layer "B.SilkS")
		)
		(fp_line
			(start -0.299974 -0.500126)
			(end -0.299974 0.500126)
			(stroke
				(width 0.1524)
				(type default)
			)
			(layer "B.SilkS")
		)
		(fp_line
			(start 0.299974 -0.500126)
			(end 0.299974 0.500126)
			(stroke
				(width 0.1524)
				(type default)
			)
			(layer "B.SilkS")
		)
		(fp_line
			(start -1.905 -0.6858)
			(end -1.905 0.6858)
			(stroke
				(width 0.1524)
				(type default)
			)
			(layer "B.SilkS")
		)
		(fp_line
			(start -1.651 -0.6858)
			(end -1.651 0.6858)
			(stroke
				(width 0.1524)
				(type default)
			)
			(layer "B.SilkS")
		)
		(fp_line
			(start -2.032 -0.7112)
			(end -2.032 0.7112)
			(stroke
				(width 0.1524)
				(type default)
			)
			(layer "B.SilkS")
		)
		(fp_line
			(start 1.651 -0.7112)
			(end -2.032 -0.7112)
			(stroke
				(width 0.1524)
				(type default)
			)
			(layer "B.SilkS")
		)
		(fp_line
			(start -0.899922 0.700024)
			(end 0.899922 0.700024)
			(stroke
				(width 0.1)
				(type default)
			)
			(layer "B.Fab")
		)
		(fp_line
			(start 0.899922 0.700024)
			(end 0.899922 0.175006)
			(stroke
				(width 0.1)
				(type default)
			)
			(layer "B.Fab")
		)
		(fp_line
			(start 0.299974 0.500126)
			(end -0.199898 0)
			(stroke
				(width 0.1)
				(type default)
			)
			(layer "B.Fab")
		)
		(fp_line
			(start -1.35001 0.175006)
			(end -0.899922 0.175006)
			(stroke
				(width 0.1)
				(type default)
			)
			(layer "B.Fab")
		)
		(fp_line
			(start -0.899922 0.175006)
			(end -0.899922 0.700024)
			(stroke
				(width 0.1)
				(type default)
			)
			(layer "B.Fab")
		)
		(fp_line
			(start 0.899922 0.175006)
			(end 1.35001 0.175006)
			(stroke
				(width 0.1)
				(type default)
			)
			(layer "B.Fab")
		)
		(fp_line
			(start 1.35001 0.175006)
			(end 1.35001 -0.225044)
			(stroke
				(width 0.1)
				(type default)
			)
			(layer "B.Fab")
		)
		(fp_line
			(start -0.199898 0)
			(end 0.299974 -0.500126)
			(stroke
				(width 0.1)
				(type default)
			)
			(layer "B.Fab")
		)
		(fp_line
			(start -1.35001 -0.225044)
			(end -1.35001 0.175006)
			(stroke
				(width 0.1)
				(type default)
			)
			(layer "B.Fab")
		)
		(fp_line
			(start -0.899922 -0.225044)
			(end -1.35001 -0.225044)
			(stroke
				(width 0.1)
				(type default)
			)
			(layer "B.Fab")
		)
		(fp_line
			(start 0.899922 -0.225044)
			(end 0.899922 -0.700024)
			(stroke
				(width 0.1)
				(type default)
			)
			(layer "B.Fab")
		)
		(fp_line
			(start 1.35001 -0.225044)
			(end 0.899922 -0.225044)
			(stroke
				(width 0.1)
				(type default)
			)
			(layer "B.Fab")
		)
		(fp_line
			(start -0.299974 -0.500126)
			(end -0.299974 0.500126)
			(stroke
				(width 0.1)
				(type default)
			)
			(layer "B.Fab")
		)
		(fp_line
			(start 0.299974 -0.500126)
			(end 0.299974 0.500126)
			(stroke
				(width 0.1)
				(type default)
			)
			(layer "B.Fab")
		)
		(fp_line
			(start -0.899922 -0.700024)
			(end -0.899922 -0.225044)
			(stroke
				(width 0.1)
				(type default)
			)
			(layer "B.Fab")
		)
		(fp_line
			(start 0.899922 -0.700024)
			(end -0.899922 -0.700024)
			(stroke
				(width 0.1)
				(type default)
			)
			(layer "B.Fab")
		)
		(fp_text user "+"
			(at 2.8956 -0.01905 270)
			(unlocked yes)
			(layer "B.SilkS")
			(effects
				(font
					(size 1.905 1.4224)
					(thickness 0.1524)
				)
				(justify left mirror)
			)
		)
		(fp_text user "-"
			(at -1.8288 -0.24765 270)
			(unlocked yes)
			(layer "B.SilkS")
			(effects
				(font
					(size 1.905 1.4224)
					(thickness 0.1524)
				)
				(justify left mirror)
			)
		)
		(fp_text user "+"
			(at 2.794 -0.19685 270)
			(unlocked yes)
			(layer "B.Fab")
			(effects
				(font
					(size 1.905 1.4224)
					(thickness 0.1524)
				)
				(justify left mirror)
			)
		)
		(fp_text user "-"
			(at -1.8288 -0.24765 270)
			(unlocked yes)
			(layer "B.Fab")
			(effects
				(font
					(size 1.905 1.4224)
					(thickness 0.1524)
				)
				(justify left mirror)
			)
		)
		(pad "1" smd rect
			(at 1.0922 0 270)
			(size 0.8128 0.8636)
			(layers "B.Cu" "B.Mask" "B.Paste")
			(net "P52V_HS2_4287_GATE_R")
		)
		(pad "2" smd rect
			(at -1.0922 0 90)
			(size 0.8128 0.8636)
			(layers "B.Cu" "B.Mask" "B.Paste")
			(net "P52V_HS2_GATE_R1")
		)
	)
	(footprint ""
		(layer "B.Cu")
		(at 278.4094 -61.849)
		(property "Reference" "R150"
			(at 0 0 0)
			(layer "B.SilkS")
			(hide yes)
			(effects
				(font
					(size 1.27 1.27)
				)
				(justify mirror)
			)
		)
		(property "Value" ""
			(at 0 0 0)
			(layer "B.Fab")
			(effects
				(font
					(size 1.27 1.27)
				)
				(justify mirror)
			)
		)
		(duplicate_pad_numbers_are_jumpers no)
		(fp_line
			(start -0.7874 -0.4064)
			(end -0.7874 0.4064)
			(stroke
				(width 0.1524)
				(type default)
			)
			(layer "B.SilkS")
		)
		(fp_line
			(start -0.7874 0.4064)
			(end 0.7874 0.4064)
			(stroke
				(width 0.1524)
				(type default)
			)
			(layer "B.SilkS")
		)
		(fp_line
			(start 0.7874 -0.4064)
			(end -0.7874 -0.4064)
			(stroke
				(width 0.1524)
				(type default)
			)
			(layer "B.SilkS")
		)
		(fp_line
			(start 0.7874 0.4064)
			(end 0.7874 -0.4064)
			(stroke
				(width 0.1524)
				(type default)
			)
			(layer "B.SilkS")
		)
		(fp_line
			(start -0.67945 -0.3048)
			(end -0.67945 0.3048)
			(stroke
				(width 0.1)
				(type default)
			)
			(layer "B.Fab")
		)
		(fp_line
			(start -0.67945 0.3048)
			(end -0.120396 0.3048)
			(stroke
				(width 0.1)
				(type default)
			)
			(layer "B.Fab")
		)
		(fp_line
			(start -0.12065 -0.3048)
			(end -0.67945 -0.3048)
			(stroke
				(width 0.1)
				(type default)
			)
			(layer "B.Fab")
		)
		(fp_line
			(start -0.12065 -0.2794)
			(end -0.12065 -0.3048)
			(stroke
				(width 0.1)
				(type default)
			)
			(layer "B.Fab")
		)
		(fp_line
			(start -0.120396 0.2794)
			(end 0.12065 0.2794)
			(stroke
				(width 0.1)
				(type default)
			)
			(layer "B.Fab")
		)
		(fp_line
			(start -0.120396 0.3048)
			(end -0.120396 0.2794)
			(stroke
				(width 0.1)
				(type default)
			)
			(layer "B.Fab")
		)
		(fp_line
			(start 0.12065 -0.305054)
			(end 0.12065 -0.2794)
			(stroke
				(width 0.1)
				(type default)
			)
			(layer "B.Fab")
		)
		(fp_line
			(start 0.12065 -0.2794)
			(end -0.12065 -0.2794)
			(stroke
				(width 0.1)
				(type default)
			)
			(layer "B.Fab")
		)
		(fp_line
			(start 0.12065 0.2794)
			(end 0.12065 0.3048)
			(stroke
				(width 0.1)
				(type default)
			)
			(layer "B.Fab")
		)
		(fp_line
			(start 0.12065 0.3048)
			(end 0.67945 0.3048)
			(stroke
				(width 0.1)
				(type default)
			)
			(layer "B.Fab")
		)
		(fp_line
			(start 0.67945 -0.305054)
			(end 0.12065 -0.305054)
			(stroke
				(width 0.1)
				(type default)
			)
			(layer "B.Fab")
		)
		(fp_line
			(start 0.67945 0.3048)
			(end 0.67945 -0.305054)
			(stroke
				(width 0.1)
				(type default)
			)
			(layer "B.Fab")
		)
		(pad "1" smd circle
			(at 0.40005 0 180)
			(size 0 0)
			(layers "B.Cu" "B.Mask" "B.Paste")
			(net "P3V3_AUX")
		)
		(pad "2" smd circle
			(at -0.40005 0 180)
			(size 0 0)
			(layers "B.Cu" "B.Mask" "B.Paste")
			(net "P52V_HS1_GPO2")
		)
	)
	(footprint ""
		(layer "B.Cu")
		(at 171.115736 -56.007 -90)
		(property "Reference" "PR6977"
			(at 0 0 90)
			(layer "B.SilkS")
			(hide yes)
			(effects
				(font
					(size 1.27 1.27)
				)
				(justify mirror)
			)
		)
		(property "Value" ""
			(at 0 0 90)
			(layer "B.Fab")
			(effects
				(font
					(size 1.27 1.27)
				)
				(justify mirror)
			)
		)
		(duplicate_pad_numbers_are_jumpers no)
		(fp_line
			(start -1.651 0.8382)
			(end 1.651 0.8382)
			(stroke
				(width 0.1524)
				(type default)
			)
			(layer "B.SilkS")
		)
		(fp_line
			(start 1.651 0.8382)
			(end 1.651 -0.8382)
			(stroke
				(width 0.1524)
				(type default)
			)
			(layer "B.SilkS")
		)
		(fp_line
			(start -1.651 -0.8382)
			(end -1.651 0.8382)
			(stroke
				(width 0.1524)
				(type default)
			)
			(layer "B.SilkS")
		)
		(fp_line
			(start 1.651 -0.8382)
			(end -1.651 -0.8382)
			(stroke
				(width 0.1524)
				(type default)
			)
			(layer "B.SilkS")
		)
		(fp_line
			(start -1.560576 0.7366)
			(end -1.560576 -0.7366)
			(stroke
				(width 0.1)
				(type default)
			)
			(layer "B.Fab")
		)
		(fp_line
			(start -1.524 0.7366)
			(end -1.560576 0.7366)
			(stroke
				(width 0.1)
				(type default)
			)
			(layer "B.Fab")
		)
		(fp_line
			(start 1.524 0.7366)
			(end -1.524 0.7366)
			(stroke
				(width 0.1)
				(type default)
			)
			(layer "B.Fab")
		)
		(fp_line
			(start 1.559814 0.7366)
			(end 1.524 0.7366)
			(stroke
				(width 0.1)
				(type default)
			)
			(layer "B.Fab")
		)
		(fp_line
			(start -1.560576 -0.7366)
			(end -1.524 -0.7366)
			(stroke
				(width 0.1)
				(type default)
			)
			(layer "B.Fab")
		)
		(fp_line
			(start -1.524 -0.7366)
			(end 1.524 -0.7366)
			(stroke
				(width 0.1)
				(type default)
			)
			(layer "B.Fab")
		)
		(fp_line
			(start 1.524 -0.7366)
			(end 1.559814 -0.7366)
			(stroke
				(width 0.1)
				(type default)
			)
			(layer "B.Fab")
		)
		(fp_line
			(start 1.559814 -0.7366)
			(end 1.559814 0.7366)
			(stroke
				(width 0.1)
				(type default)
			)
			(layer "B.Fab")
		)
		(pad "1" smd rect
			(at 0.94996 0 270)
			(size 1.1176 1.3716)
			(layers "B.Cu" "B.Mask" "B.Paste")
			(net "P52V_2")
		)
		(pad "2" smd rect
			(at -0.94996 0 270)
			(size 1.1176 1.3716)
			(layers "B.Cu" "B.Mask" "B.Paste")
			(net "P52V_HS2_OV")
		)
	)
	(footprint ""
		(layer "B.Cu")
		(at 156.637736 -77.216 90)
		(property "Reference" "R5874"
			(at 0 0 90)
			(layer "B.SilkS")
			(hide yes)
			(effects
				(font
					(size 1.27 1.27)
				)
				(justify mirror)
			)
		)
		(property "Value" ""
			(at 0 0 90)
			(layer "B.Fab")
			(effects
				(font
					(size 1.27 1.27)
				)
				(justify mirror)
			)
		)
		(duplicate_pad_numbers_are_jumpers no)
		(fp_line
			(start 0.7874 -0.4064)
			(end -0.7874 -0.4064)
			(stroke
				(width 0.1524)
				(type default)
			)
			(layer "B.SilkS")
		)
		(fp_line
			(start -0.7874 -0.4064)
			(end -0.7874 0.4064)
			(stroke
				(width 0.1524)
				(type default)
			)
			(layer "B.SilkS")
		)
		(fp_line
			(start 0.7874 0.4064)
			(end 0.7874 -0.4064)
			(stroke
				(width 0.1524)
				(type default)
			)
			(layer "B.SilkS")
		)
		(fp_line
			(start -0.7874 0.4064)
			(end 0.7874 0.4064)
			(stroke
				(width 0.1524)
				(type default)
			)
			(layer "B.SilkS")
		)
		(fp_line
			(start 0.67945 -0.305054)
			(end 0.12065 -0.305054)
			(stroke
				(width 0.1)
				(type default)
			)
			(layer "B.Fab")
		)
		(fp_line
			(start 0.12065 -0.305054)
			(end 0.12065 -0.2794)
			(stroke
				(width 0.1)
				(type default)
			)
			(layer "B.Fab")
		)
		(fp_line
			(start -0.12065 -0.3048)
			(end -0.67945 -0.3048)
			(stroke
				(width 0.1)
				(type default)
			)
			(layer "B.Fab")
		)
		(fp_line
			(start -0.67945 -0.3048)
			(end -0.67945 0.3048)
			(stroke
				(width 0.1)
				(type default)
			)
			(layer "B.Fab")
		)
		(fp_line
			(start 0.12065 -0.2794)
			(end -0.12065 -0.2794)
			(stroke
				(width 0.1)
				(type default)
			)
			(layer "B.Fab")
		)
		(fp_line
			(start -0.12065 -0.2794)
			(end -0.12065 -0.3048)
			(stroke
				(width 0.1)
				(type default)
			)
			(layer "B.Fab")
		)
		(fp_line
			(start 0.12065 0.2794)
			(end 0.12065 0.3048)
			(stroke
				(width 0.1)
				(type default)
			)
			(layer "B.Fab")
		)
		(fp_line
			(start -0.120396 0.2794)
			(end 0.12065 0.2794)
			(stroke
				(width 0.1)
				(type default)
			)
			(layer "B.Fab")
		)
		(fp_line
			(start 0.67945 0.3048)
			(end 0.67945 -0.305054)
			(stroke
				(width 0.1)
				(type default)
			)
			(layer "B.Fab")
		)
		(fp_line
			(start 0.12065 0.3048)
			(end 0.67945 0.3048)
			(stroke
				(width 0.1)
				(type default)
			)
			(layer "B.Fab")
		)
		(fp_line
			(start -0.120396 0.3048)
			(end -0.120396 0.2794)
			(stroke
				(width 0.1)
				(type default)
			)
			(layer "B.Fab")
		)
		(fp_line
			(start -0.67945 0.3048)
			(end -0.120396 0.3048)
			(stroke
				(width 0.1)
				(type default)
			)
			(layer "B.Fab")
		)
		(pad "1" smd circle
			(at 0.40005 0 270)
			(size 0 0)
			(layers "B.Cu" "B.Mask" "B.Paste")
			(net "P52V_HS2_INTVCC")
		)
		(pad "2" smd circle
			(at -0.40005 0 270)
			(size 0 0)
			(layers "B.Cu" "B.Mask" "B.Paste")
			(net "P52V_HS2_ADR1")
		)
	)
	(footprint ""
		(layer "B.Cu")
		(at 184.4294 -52.832 90)
		(property "Reference" "PD12"
			(at 7.84733 2.6416 0)
			(unlocked yes)
			(layer "B.SilkS")
			(effects
				(font
					(size 0.7874 0.5842)
					(thickness 0.1524)
				)
				(justify left mirror)
			)
		)
		(property "Value" ""
			(at 0 0 90)
			(layer "B.Fab")
			(effects
				(font
					(size 1.27 1.27)
				)
				(justify mirror)
			)
		)
		(duplicate_pad_numbers_are_jumpers no)
		(fp_line
			(start 4.664456 -3.109976)
			(end -4.743704 -3.109976)
			(stroke
				(width 0.1524)
				(type default)
			)
			(layer "B.SilkS")
		)
		(fp_line
			(start -4.183126 -3.109976)
			(end -4.794504 -3.109976)
			(stroke
				(width 0.1524)
				(type default)
			)
			(layer "B.SilkS")
		)
		(fp_line
			(start -4.511802 -3.109976)
			(end -4.207002 -3.109976)
			(stroke
				(width 0.1524)
				(type default)
			)
			(layer "B.SilkS")
		)
		(fp_line
			(start -4.6101 -3.109976)
			(end -4.283202 -3.109976)
			(stroke
				(width 0.1524)
				(type default)
			)
			(layer "B.SilkS")
		)
		(fp_line
			(start -4.695444 -3.109976)
			(end -4.695444 3.109976)
			(stroke
				(width 0.1524)
				(type default)
			)
			(layer "B.SilkS")
		)
		(fp_line
			(start -4.70535 -3.109976)
			(end -4.70535 3.109976)
			(stroke
				(width 0.1524)
				(type default)
			)
			(layer "B.SilkS")
		)
		(fp_line
			(start -4.70535 -3.109976)
			(end -4.70535 3.109976)
			(stroke
				(width 0.1524)
				(type default)
			)
			(layer "B.SilkS")
		)
		(fp_line
			(start -4.70535 -3.109976)
			(end -4.70535 3.109976)
			(stroke
				(width 0.1524)
				(type default)
			)
			(layer "B.SilkS")
		)
		(fp_line
			(start -4.805426 -3.109976)
			(end -4.805426 3.109976)
			(stroke
				(width 0.1524)
				(type default)
			)
			(layer "B.SilkS")
		)
		(fp_line
			(start -4.932426 -3.109976)
			(end -4.932426 3.109976)
			(stroke
				(width 0.1524)
				(type default)
			)
			(layer "B.SilkS")
		)
		(fp_line
			(start -5.008626 -3.109976)
			(end -5.008626 3.109976)
			(stroke
				(width 0.1524)
				(type default)
			)
			(layer "B.SilkS")
		)
		(fp_line
			(start -5.110226 -3.109976)
			(end -5.110226 3.109976)
			(stroke
				(width 0.1524)
				(type default)
			)
			(layer "B.SilkS")
		)
		(fp_line
			(start -5.211826 -3.109976)
			(end -5.211826 3.109976)
			(stroke
				(width 0.1524)
				(type default)
			)
			(layer "B.SilkS")
		)
		(fp_line
			(start -5.262626 -3.109976)
			(end -5.262626 3.109976)
			(stroke
				(width 0.1524)
				(type default)
			)
			(layer "B.SilkS")
		)
		(fp_line
			(start -5.313426 -3.109976)
			(end -5.313426 3.109976)
			(stroke
				(width 0.1524)
				(type default)
			)
			(layer "B.SilkS")
		)
		(fp_line
			(start -5.4102 -3.109976)
			(end -4.783074 -3.109976)
			(stroke
				(width 0.1524)
				(type default)
			)
			(layer "B.SilkS")
		)
		(fp_line
			(start -5.4102 -1.9304)
			(end -5.4102 -3.109976)
			(stroke
				(width 0.1524)
				(type default)
			)
			(layer "B.SilkS")
		)
		(fp_line
			(start 0.508 -1.016)
			(end -0.762 0)
			(stroke
				(width 0.1524)
				(type default)
			)
			(layer "B.SilkS")
		)
		(fp_line
			(start 1.0668 0)
			(end 0.6096 0)
			(stroke
				(width 0.1524)
				(type default)
			)
			(layer "B.SilkS")
		)
		(fp_line
			(start -0.762 0)
			(end -1.2192 0)
			(stroke
				(width 0.1524)
				(type default)
			)
			(layer "B.SilkS")
		)
		(fp_line
			(start -0.762 0)
			(end 0.508 1.016)
			(stroke
				(width 0.1524)
				(type default)
			)
			(layer "B.SilkS")
		)
		(fp_line
			(start 0.508 1.016)
			(end 0.508 -1.016)
			(stroke
				(width 0.1524)
				(type default)
			)
			(layer "B.SilkS")
		)
		(fp_line
			(start -0.762 1.27)
			(end -0.762 -1.27)
			(stroke
				(width 0.1524)
				(type default)
			)
			(layer "B.SilkS")
		)
		(fp_line
			(start -4.715002 3.035554)
			(end -4.7117 2.984754)
			(stroke
				(width 0.1524)
				(type default)
			)
			(layer "B.SilkS")
		)
		(fp_line
			(start 4.664456 3.109976)
			(end 4.664456 -3.109976)
			(stroke
				(width 0.1524)
				(type default)
			)
			(layer "B.SilkS")
		)
		(fp_line
			(start -4.156202 3.109976)
			(end -4.183126 3.109976)
			(stroke
				(width 0.1524)
				(type default)
			)
			(layer "B.SilkS")
		)
		(fp_line
			(start -4.743704 3.109976)
			(end -4.6101 3.109976)
			(stroke
				(width 0.1524)
				(type default)
			)
			(layer "B.SilkS")
		)
		(fp_line
			(start -4.743704 3.109976)
			(end -5.4102 3.109976)
			(stroke
				(width 0.1524)
				(type default)
			)
			(layer "B.SilkS")
		)
		(fp_line
			(start -4.769104 3.109976)
			(end 4.664456 3.109976)
			(stroke
				(width 0.1524)
				(type default)
			)
			(layer "B.SilkS")
		)
		(fp_line
			(start -4.794504 3.109976)
			(end -3.554984 3.109976)
			(stroke
				(width 0.1524)
				(type default)
			)
			(layer "B.SilkS")
		)
		(fp_line
			(start -5.4102 3.109976)
			(end -5.4102 -1.0668)
			(stroke
				(width 0.1524)
				(type default)
			)
			(layer "B.SilkS")
		)
		(fp_line
			(start 4.065016 -3.109976)
			(end -4.065016 -3.109976)
			(stroke
				(width 0.1)
				(type default)
			)
			(layer "B.Fab")
		)
		(fp_line
			(start -4.065016 -3.109976)
			(end -4.065016 3.109976)
			(stroke
				(width 0.1)
				(type default)
			)
			(layer "B.Fab")
		)
		(fp_line
			(start 4.065016 3.109976)
			(end 4.065016 -3.109976)
			(stroke
				(width 0.1)
				(type default)
			)
			(layer "B.Fab")
		)
		(fp_line
			(start -4.065016 3.109976)
			(end 4.065016 3.109976)
			(stroke
				(width 0.1)
				(type default)
			)
			(layer "B.Fab")
		)
		(fp_text user "-"
			(at -8.001 0.19685 270)
			(unlocked yes)
			(layer "B.SilkS")
			(effects
				(font
					(size 1.905 1.4224)
					(thickness 0.1524)
				)
				(justify left mirror)
			)
		)
		(fp_text user "+"
			(at 5.9944 0.37465 270)
			(unlocked yes)
			(layer "B.SilkS")
			(effects
				(font
					(size 1.905 1.4224)
					(thickness 0.1524)
				)
				(justify left mirror)
			)
		)
		(fp_text user "+"
			(at 4.5974 0.24765 270)
			(unlocked yes)
			(layer "B.Fab")
			(effects
				(font
					(size 1.905 1.4224)
					(thickness 0.1524)
				)
				(justify left mirror)
			)
		)
		(fp_text user "-"
			(at -6.643624 0.40005 270)
			(unlocked yes)
			(layer "B.Fab")
			(effects
				(font
					(size 1.905 1.4224)
					(thickness 0.1524)
				)
				(justify left mirror)
			)
		)
		(pad "A" smd rect
			(at 3.299968 0 90)
			(size 2.413 3.302)
			(layers "B.Cu" "B.Mask" "B.Paste")
			(net "GND")
		)
		(pad "C" smd rect
			(at -3.299968 0 90)
			(size 2.413 3.302)
			(layers "B.Cu" "B.Mask" "B.Paste")
			(net "P52V_2_FUSE_1")
		)
	)
	(footprint ""
		(layer "B.Cu")
		(at 340.5124 -49.7586 90)
		(property "Reference" "PR26"
			(at 0 0 90)
			(layer "B.SilkS")
			(hide yes)
			(effects
				(font
					(size 1.27 1.27)
				)
				(justify mirror)
			)
		)
		(property "Value" ""
			(at 0 0 90)
			(layer "B.Fab")
			(effects
				(font
					(size 1.27 1.27)
				)
				(justify mirror)
			)
		)
		(duplicate_pad_numbers_are_jumpers no)
		(fp_line
			(start 0.7874 -0.4064)
			(end -0.7874 -0.4064)
			(stroke
				(width 0.1524)
				(type default)
			)
			(layer "B.SilkS")
		)
		(fp_line
			(start -0.7874 -0.4064)
			(end -0.7874 0.4064)
			(stroke
				(width 0.1524)
				(type default)
			)
			(layer "B.SilkS")
		)
		(fp_line
			(start 0.7874 0.4064)
			(end 0.7874 -0.4064)
			(stroke
				(width 0.1524)
				(type default)
			)
			(layer "B.SilkS")
		)
		(fp_line
			(start -0.7874 0.4064)
			(end 0.7874 0.4064)
			(stroke
				(width 0.1524)
				(type default)
			)
			(layer "B.SilkS")
		)
		(fp_line
			(start 0.67945 -0.305054)
			(end 0.12065 -0.305054)
			(stroke
				(width 0.1)
				(type default)
			)
			(layer "B.Fab")
		)
		(fp_line
			(start 0.12065 -0.305054)
			(end 0.12065 -0.2794)
			(stroke
				(width 0.1)
				(type default)
			)
			(layer "B.Fab")
		)
		(fp_line
			(start -0.12065 -0.3048)
			(end -0.67945 -0.3048)
			(stroke
				(width 0.1)
				(type default)
			)
			(layer "B.Fab")
		)
		(fp_line
			(start -0.67945 -0.3048)
			(end -0.67945 0.3048)
			(stroke
				(width 0.1)
				(type default)
			)
			(layer "B.Fab")
		)
		(fp_line
			(start 0.12065 -0.2794)
			(end -0.12065 -0.2794)
			(stroke
				(width 0.1)
				(type default)
			)
			(layer "B.Fab")
		)
		(fp_line
			(start -0.12065 -0.2794)
			(end -0.12065 -0.3048)
			(stroke
				(width 0.1)
				(type default)
			)
			(layer "B.Fab")
		)
		(fp_line
			(start 0.12065 0.2794)
			(end 0.12065 0.3048)
			(stroke
				(width 0.1)
				(type default)
			)
			(layer "B.Fab")
		)
		(fp_line
			(start -0.120396 0.2794)
			(end 0.12065 0.2794)
			(stroke
				(width 0.1)
				(type default)
			)
			(layer "B.Fab")
		)
		(fp_line
			(start 0.67945 0.3048)
			(end 0.67945 -0.305054)
			(stroke
				(width 0.1)
				(type default)
			)
			(layer "B.Fab")
		)
		(fp_line
			(start 0.12065 0.3048)
			(end 0.67945 0.3048)
			(stroke
				(width 0.1)
				(type default)
			)
			(layer "B.Fab")
		)
		(fp_line
			(start -0.120396 0.3048)
			(end -0.120396 0.2794)
			(stroke
				(width 0.1)
				(type default)
			)
			(layer "B.Fab")
		)
		(fp_line
			(start -0.67945 0.3048)
			(end -0.120396 0.3048)
			(stroke
				(width 0.1)
				(type default)
			)
			(layer "B.Fab")
		)
		(pad "1" smd rect
			(at 0.40005 0 90)
			(size 0.4572 0.508)
			(layers "B.Cu" "B.Mask" "B.Paste")
			(net "P52V_HS1_GATE_R1")
		)
		(pad "2" smd rect
			(at -0.40005 0 90)
			(size 0.4572 0.508)
			(layers "B.Cu" "B.Mask" "B.Paste")
			(net "P52V_HS1_4287_GATE_R")
		)
	)
	(footprint ""
		(layer "B.Cu")
		(at 449.199 -46.736 180)
		(property "Reference" "C103"
			(at 0 0 0)
			(layer "B.SilkS")
			(hide yes)
			(effects
				(font
					(size 1.27 1.27)
				)
				(justify mirror)
			)
		)
		(property "Value" ""
			(at 0 0 0)
			(layer "B.Fab")
			(effects
				(font
					(size 1.27 1.27)
				)
				(justify mirror)
			)
		)
		(duplicate_pad_numbers_are_jumpers no)
		(fp_line
			(start 0.7874 0.4064)
			(end 0.7874 -0.4064)
			(stroke
				(width 0.1524)
				(type default)
			)
			(layer "B.SilkS")
		)
		(fp_line
			(start 0.7874 -0.4064)
			(end -0.7874 -0.4064)
			(stroke
				(width 0.1524)
				(type default)
			)
			(layer "B.SilkS")
		)
		(fp_line
			(start -0.7874 0.4064)
			(end 0.7874 0.4064)
			(stroke
				(width 0.1524)
				(type default)
			)
			(layer "B.SilkS")
		)
		(fp_line
			(start -0.7874 -0.4064)
			(end -0.7874 0.4064)
			(stroke
				(width 0.1524)
				(type default)
			)
			(layer "B.SilkS")
		)
		(fp_line
			(start 0.67945 0.3048)
			(end 0.67945 -0.305054)
			(stroke
				(width 0.1)
				(type default)
			)
			(layer "B.Fab")
		)
		(fp_line
			(start 0.67945 -0.305054)
			(end 0.12065 -0.305054)
			(stroke
				(width 0.1)
				(type default)
			)
			(layer "B.Fab")
		)
		(fp_line
			(start 0.12065 0.3048)
			(end 0.67945 0.3048)
			(stroke
				(width 0.1)
				(type default)
			)
			(layer "B.Fab")
		)
		(fp_line
			(start 0.12065 0.2794)
			(end 0.12065 0.3048)
			(stroke
				(width 0.1)
				(type default)
			)
			(layer "B.Fab")
		)
		(fp_line
			(start 0.12065 -0.2794)
			(end -0.12065 -0.2794)
			(stroke
				(width 0.1)
				(type default)
			)
			(layer "B.Fab")
		)
		(fp_line
			(start 0.12065 -0.305054)
			(end 0.12065 -0.2794)
			(stroke
				(width 0.1)
				(type default)
			)
			(layer "B.Fab")
		)
		(fp_line
			(start -0.120396 0.3048)
			(end -0.120396 0.2794)
			(stroke
				(width 0.1)
				(type default)
			)
			(layer "B.Fab")
		)
		(fp_line
			(start -0.120396 0.2794)
			(end 0.12065 0.2794)
			(stroke
				(width 0.1)
				(type default)
			)
			(layer "B.Fab")
		)
		(fp_line
			(start -0.12065 -0.2794)
			(end -0.12065 -0.3048)
			(stroke
				(width 0.1)
				(type default)
			)
			(layer "B.Fab")
		)
		(fp_line
			(start -0.12065 -0.3048)
			(end -0.67945 -0.3048)
			(stroke
				(width 0.1)
				(type default)
			)
			(layer "B.Fab")
		)
		(fp_line
			(start -0.67945 0.3048)
			(end -0.120396 0.3048)
			(stroke
				(width 0.1)
				(type default)
			)
			(layer "B.Fab")
		)
		(fp_line
			(start -0.67945 -0.3048)
			(end -0.67945 0.3048)
			(stroke
				(width 0.1)
				(type default)
			)
			(layer "B.Fab")
		)
		(pad "1" smd circle
			(at 0.40005 0)
			(size 0 0)
			(layers "B.Cu" "B.Mask" "B.Paste")
			(net "P3V3_AUX")
		)
		(pad "2" smd circle
			(at -0.40005 0)
			(size 0 0)
			(layers "B.Cu" "B.Mask" "B.Paste")
			(net "GND")
		)
	)
	(footprint ""
		(layer "B.Cu")
		(at 154.351736 -60.198 90)
		(property "Reference" "PJ5"
			(at -2.18567 0.207264 0)
			(unlocked yes)
			(layer "B.SilkS")
			(effects
				(font
					(size 0.7874 0.5842)
					(thickness 0.1524)
				)
				(justify left mirror)
			)
		)
		(property "Value" ""
			(at 0 0 90)
			(layer "B.Fab")
			(effects
				(font
					(size 1.27 1.27)
				)
				(justify mirror)
			)
		)
		(duplicate_pad_numbers_are_jumpers no)
		(pad "1" smd circle
			(at 0.7493 0 180)
			(size 0 0)
			(layers "B.Cu" "B.Mask" "B.Paste")
			(net "GND1_FIELD_SIGNAL")
		)
		(pad "2" smd rect
			(at -0.7493 0)
			(size 0.7112 0.8128)
			(layers "B.Cu" "B.Mask" "B.Paste")
			(net "GND")
		)
		(zone
			(layer "B.Cu")
			(hatch none 0.5)
			(connect_pads
				(clearance 0)
			)
			(min_thickness 0.25)
			(keepout
				(tracks allowed)
				(vias not_allowed)
				(pads allowed)
				(copperpour not_allowed)
				(footprints allowed)
			)
			(placement
				(enabled no)
				(sheetname "")
			)
			(fill
				(thermal_gap 0.5)
				(thermal_bridge_width 0.5)
				(island_removal_mode 0)
			)
			(polygon
				(pts
					(xy 153.945336 -58.9915) (xy 154.762962 -58.9915) (xy 154.762962 -61.3791) (xy 153.945336 -61.3791)
				)
			)
		)
	)
	(footprint ""
		(layer "B.Cu")
		(at 413.639 -35.306)
		(property "Reference" "R5938"
			(at 0 0 0)
			(layer "B.SilkS")
			(hide yes)
			(effects
				(font
					(size 1.27 1.27)
				)
				(justify mirror)
			)
		)
		(property "Value" ""
			(at 0 0 0)
			(layer "B.Fab")
			(effects
				(font
					(size 1.27 1.27)
				)
				(justify mirror)
			)
		)
		(duplicate_pad_numbers_are_jumpers no)
		(fp_line
			(start -0.7874 -0.4064)
			(end -0.7874 0.4064)
			(stroke
				(width 0.1524)
				(type default)
			)
			(layer "B.SilkS")
		)
		(fp_line
			(start -0.7874 0.4064)
			(end 0.7874 0.4064)
			(stroke
				(width 0.1524)
				(type default)
			)
			(layer "B.SilkS")
		)
		(fp_line
			(start 0.7874 -0.4064)
			(end -0.7874 -0.4064)
			(stroke
				(width 0.1524)
				(type default)
			)
			(layer "B.SilkS")
		)
		(fp_line
			(start 0.7874 0.4064)
			(end 0.7874 -0.4064)
			(stroke
				(width 0.1524)
				(type default)
			)
			(layer "B.SilkS")
		)
		(fp_line
			(start -0.67945 -0.3048)
			(end -0.67945 0.3048)
			(stroke
				(width 0.1)
				(type default)
			)
			(layer "B.Fab")
		)
		(fp_line
			(start -0.67945 0.3048)
			(end -0.120396 0.3048)
			(stroke
				(width 0.1)
				(type default)
			)
			(layer "B.Fab")
		)
		(fp_line
			(start -0.12065 -0.3048)
			(end -0.67945 -0.3048)
			(stroke
				(width 0.1)
				(type default)
			)
			(layer "B.Fab")
		)
		(fp_line
			(start -0.12065 -0.2794)
			(end -0.12065 -0.3048)
			(stroke
				(width 0.1)
				(type default)
			)
			(layer "B.Fab")
		)
		(fp_line
			(start -0.120396 0.2794)
			(end 0.12065 0.2794)
			(stroke
				(width 0.1)
				(type default)
			)
			(layer "B.Fab")
		)
		(fp_line
			(start -0.120396 0.3048)
			(end -0.120396 0.2794)
			(stroke
				(width 0.1)
				(type default)
			)
			(layer "B.Fab")
		)
		(fp_line
			(start 0.12065 -0.305054)
			(end 0.12065 -0.2794)
			(stroke
				(width 0.1)
				(type default)
			)
			(layer "B.Fab")
		)
		(fp_line
			(start 0.12065 -0.2794)
			(end -0.12065 -0.2794)
			(stroke
				(width 0.1)
				(type default)
			)
			(layer "B.Fab")
		)
		(fp_line
			(start 0.12065 0.2794)
			(end 0.12065 0.3048)
			(stroke
				(width 0.1)
				(type default)
			)
			(layer "B.Fab")
		)
		(fp_line
			(start 0.12065 0.3048)
			(end 0.67945 0.3048)
			(stroke
				(width 0.1)
				(type default)
			)
			(layer "B.Fab")
		)
		(fp_line
			(start 0.67945 -0.305054)
			(end 0.12065 -0.305054)
			(stroke
				(width 0.1)
				(type default)
			)
			(layer "B.Fab")
		)
		(fp_line
			(start 0.67945 0.3048)
			(end 0.67945 -0.305054)
			(stroke
				(width 0.1)
				(type default)
			)
			(layer "B.Fab")
		)
		(pad "1" smd circle
			(at 0.40005 0 180)
			(size 0 0)
			(layers "B.Cu" "B.Mask" "B.Paste")
			(net "PCA9555_2_A1")
		)
		(pad "2" smd circle
			(at -0.40005 0 180)
			(size 0 0)
			(layers "B.Cu" "B.Mask" "B.Paste")
			(net "GND")
		)
	)
	(footprint ""
		(layer "B.Cu")
		(at 180.086 -52.832)
		(property "Reference" "R5897"
			(at 0 0 0)
			(layer "B.SilkS")
			(hide yes)
			(effects
				(font
					(size 1.27 1.27)
				)
				(justify mirror)
			)
		)
		(property "Value" ""
			(at 0 0 0)
			(layer "B.Fab")
			(effects
				(font
					(size 1.27 1.27)
				)
				(justify mirror)
			)
		)
		(duplicate_pad_numbers_are_jumpers no)
		(fp_line
			(start -0.7874 -0.4064)
			(end -0.7874 0.4064)
			(stroke
				(width 0.1524)
				(type default)
			)
			(layer "B.SilkS")
		)
		(fp_line
			(start -0.7874 0.4064)
			(end 0.7874 0.4064)
			(stroke
				(width 0.1524)
				(type default)
			)
			(layer "B.SilkS")
		)
		(fp_line
			(start 0.7874 -0.4064)
			(end -0.7874 -0.4064)
			(stroke
				(width 0.1524)
				(type default)
			)
			(layer "B.SilkS")
		)
		(fp_line
			(start 0.7874 0.4064)
			(end 0.7874 -0.4064)
			(stroke
				(width 0.1524)
				(type default)
			)
			(layer "B.SilkS")
		)
		(fp_line
			(start -0.67945 -0.3048)
			(end -0.67945 0.3048)
			(stroke
				(width 0.1)
				(type default)
			)
			(layer "B.Fab")
		)
		(fp_line
			(start -0.67945 0.3048)
			(end -0.120396 0.3048)
			(stroke
				(width 0.1)
				(type default)
			)
			(layer "B.Fab")
		)
		(fp_line
			(start -0.12065 -0.3048)
			(end -0.67945 -0.3048)
			(stroke
				(width 0.1)
				(type default)
			)
			(layer "B.Fab")
		)
		(fp_line
			(start -0.12065 -0.2794)
			(end -0.12065 -0.3048)
			(stroke
				(width 0.1)
				(type default)
			)
			(layer "B.Fab")
		)
		(fp_line
			(start -0.120396 0.2794)
			(end 0.12065 0.2794)
			(stroke
				(width 0.1)
				(type default)
			)
			(layer "B.Fab")
		)
		(fp_line
			(start -0.120396 0.3048)
			(end -0.120396 0.2794)
			(stroke
				(width 0.1)
				(type default)
			)
			(layer "B.Fab")
		)
		(fp_line
			(start 0.12065 -0.305054)
			(end 0.12065 -0.2794)
			(stroke
				(width 0.1)
				(type default)
			)
			(layer "B.Fab")
		)
		(fp_line
			(start 0.12065 -0.2794)
			(end -0.12065 -0.2794)
			(stroke
				(width 0.1)
				(type default)
			)
			(layer "B.Fab")
		)
		(fp_line
			(start 0.12065 0.2794)
			(end 0.12065 0.3048)
			(stroke
				(width 0.1)
				(type default)
			)
			(layer "B.Fab")
		)
		(fp_line
			(start 0.12065 0.3048)
			(end 0.67945 0.3048)
			(stroke
				(width 0.1)
				(type default)
			)
			(layer "B.Fab")
		)
		(fp_line
			(start 0.67945 -0.305054)
			(end 0.12065 -0.305054)
			(stroke
				(width 0.1)
				(type default)
			)
			(layer "B.Fab")
		)
		(fp_line
			(start 0.67945 0.3048)
			(end 0.67945 -0.305054)
			(stroke
				(width 0.1)
				(type default)
			)
			(layer "B.Fab")
		)
		(pad "1" smd circle
			(at 0.40005 0 180)
			(size 0 0)
			(layers "B.Cu" "B.Mask" "B.Paste")
			(net "FM_HS2_EN_FUSE")
		)
		(pad "2" smd circle
			(at -0.40005 0 180)
			(size 0 0)
			(layers "B.Cu" "B.Mask" "B.Paste")
			(net "GND")
		)
	)
	(footprint ""
		(layer "B.Cu")
		(at 171.7294 -63.754 90)
		(property "Reference" "PC577"
			(at 0 0 90)
			(layer "B.SilkS")
			(hide yes)
			(effects
				(font
					(size 1.27 1.27)
				)
				(justify mirror)
			)
		)
		(property "Value" ""
			(at 0 0 90)
			(layer "B.Fab")
			(effects
				(font
					(size 1.27 1.27)
				)
				(justify mirror)
			)
		)
		(duplicate_pad_numbers_are_jumpers no)
		(fp_line
			(start 0.7874 -0.4064)
			(end -0.7874 -0.4064)
			(stroke
				(width 0.1524)
				(type default)
			)
			(layer "B.SilkS")
		)
		(fp_line
			(start -0.7874 -0.4064)
			(end -0.7874 0.4064)
			(stroke
				(width 0.1524)
				(type default)
			)
			(layer "B.SilkS")
		)
		(fp_line
			(start 0.7874 0.4064)
			(end 0.7874 -0.4064)
			(stroke
				(width 0.1524)
				(type default)
			)
			(layer "B.SilkS")
		)
		(fp_line
			(start -0.7874 0.4064)
			(end 0.7874 0.4064)
			(stroke
				(width 0.1524)
				(type default)
			)
			(layer "B.SilkS")
		)
		(fp_line
			(start 0.67945 -0.305054)
			(end 0.12065 -0.305054)
			(stroke
				(width 0.1)
				(type default)
			)
			(layer "B.Fab")
		)
		(fp_line
			(start 0.12065 -0.305054)
			(end 0.12065 -0.2794)
			(stroke
				(width 0.1)
				(type default)
			)
			(layer "B.Fab")
		)
		(fp_line
			(start -0.12065 -0.3048)
			(end -0.67945 -0.3048)
			(stroke
				(width 0.1)
				(type default)
			)
			(layer "B.Fab")
		)
		(fp_line
			(start -0.67945 -0.3048)
			(end -0.67945 0.3048)
			(stroke
				(width 0.1)
				(type default)
			)
			(layer "B.Fab")
		)
		(fp_line
			(start 0.12065 -0.2794)
			(end -0.12065 -0.2794)
			(stroke
				(width 0.1)
				(type default)
			)
			(layer "B.Fab")
		)
		(fp_line
			(start -0.12065 -0.2794)
			(end -0.12065 -0.3048)
			(stroke
				(width 0.1)
				(type default)
			)
			(layer "B.Fab")
		)
		(fp_line
			(start 0.12065 0.2794)
			(end 0.12065 0.3048)
			(stroke
				(width 0.1)
				(type default)
			)
			(layer "B.Fab")
		)
		(fp_line
			(start -0.120396 0.2794)
			(end 0.12065 0.2794)
			(stroke
				(width 0.1)
				(type default)
			)
			(layer "B.Fab")
		)
		(fp_line
			(start 0.67945 0.3048)
			(end 0.67945 -0.305054)
			(stroke
				(width 0.1)
				(type default)
			)
			(layer "B.Fab")
		)
		(fp_line
			(start 0.12065 0.3048)
			(end 0.67945 0.3048)
			(stroke
				(width 0.1)
				(type default)
			)
			(layer "B.Fab")
		)
		(fp_line
			(start -0.120396 0.3048)
			(end -0.120396 0.2794)
			(stroke
				(width 0.1)
				(type default)
			)
			(layer "B.Fab")
		)
		(fp_line
			(start -0.67945 0.3048)
			(end -0.120396 0.3048)
			(stroke
				(width 0.1)
				(type default)
			)
			(layer "B.Fab")
		)
		(pad "1" smd circle
			(at 0.40005 0 270)
			(size 0 0)
			(layers "B.Cu" "B.Mask" "B.Paste")
			(net "P52V_HS2_OV")
		)
		(pad "2" smd circle
			(at -0.40005 0 270)
			(size 0 0)
			(layers "B.Cu" "B.Mask" "B.Paste")
			(net "GND1_FIELD_SIGNAL")
		)
	)
	(footprint ""
		(layer "B.Cu")
		(at 175.179736 -56.007 -90)
		(property "Reference" "PR6978"
			(at 0 0 90)
			(layer "B.SilkS")
			(hide yes)
			(effects
				(font
					(size 1.27 1.27)
				)
				(justify mirror)
			)
		)
		(property "Value" ""
			(at 0 0 90)
			(layer "B.Fab")
			(effects
				(font
					(size 1.27 1.27)
				)
				(justify mirror)
			)
		)
		(duplicate_pad_numbers_are_jumpers no)
		(fp_line
			(start -1.651 0.8382)
			(end 1.651 0.8382)
			(stroke
				(width 0.1524)
				(type default)
			)
			(layer "B.SilkS")
		)
		(fp_line
			(start 1.651 0.8382)
			(end 1.651 -0.8382)
			(stroke
				(width 0.1524)
				(type default)
			)
			(layer "B.SilkS")
		)
		(fp_line
			(start -1.651 -0.8382)
			(end -1.651 0.8382)
			(stroke
				(width 0.1524)
				(type default)
			)
			(layer "B.SilkS")
		)
		(fp_line
			(start 1.651 -0.8382)
			(end -1.651 -0.8382)
			(stroke
				(width 0.1524)
				(type default)
			)
			(layer "B.SilkS")
		)
		(fp_line
			(start -1.560576 0.7366)
			(end -1.560576 -0.7366)
			(stroke
				(width 0.1)
				(type default)
			)
			(layer "B.Fab")
		)
		(fp_line
			(start -1.524 0.7366)
			(end -1.560576 0.7366)
			(stroke
				(width 0.1)
				(type default)
			)
			(layer "B.Fab")
		)
		(fp_line
			(start 1.524 0.7366)
			(end -1.524 0.7366)
			(stroke
				(width 0.1)
				(type default)
			)
			(layer "B.Fab")
		)
		(fp_line
			(start 1.559814 0.7366)
			(end 1.524 0.7366)
			(stroke
				(width 0.1)
				(type default)
			)
			(layer "B.Fab")
		)
		(fp_line
			(start -1.560576 -0.7366)
			(end -1.524 -0.7366)
			(stroke
				(width 0.1)
				(type default)
			)
			(layer "B.Fab")
		)
		(fp_line
			(start -1.524 -0.7366)
			(end 1.524 -0.7366)
			(stroke
				(width 0.1)
				(type default)
			)
			(layer "B.Fab")
		)
		(fp_line
			(start 1.524 -0.7366)
			(end 1.559814 -0.7366)
			(stroke
				(width 0.1)
				(type default)
			)
			(layer "B.Fab")
		)
		(fp_line
			(start 1.559814 -0.7366)
			(end 1.559814 0.7366)
			(stroke
				(width 0.1)
				(type default)
			)
			(layer "B.Fab")
		)
		(pad "1" smd rect
			(at 0.94996 0 270)
			(size 1.1176 1.3716)
			(layers "B.Cu" "B.Mask" "B.Paste")
			(net "P52V_2")
		)
		(pad "2" smd rect
			(at -0.94996 0 270)
			(size 1.1176 1.3716)
			(layers "B.Cu" "B.Mask" "B.Paste")
			(net "P52V_HS2_UVLO_EN")
		)
	)
	(footprint ""
		(layer "B.Cu")
		(at 420.116 -35.052)
		(property "Reference" "R5931"
			(at 0 0 0)
			(layer "B.SilkS")
			(hide yes)
			(effects
				(font
					(size 1.27 1.27)
				)
				(justify mirror)
			)
		)
		(property "Value" ""
			(at 0 0 0)
			(layer "B.Fab")
			(effects
				(font
					(size 1.27 1.27)
				)
				(justify mirror)
			)
		)
		(duplicate_pad_numbers_are_jumpers no)
		(fp_line
			(start -0.7874 -0.4064)
			(end -0.7874 0.4064)
			(stroke
				(width 0.1524)
				(type default)
			)
			(layer "B.SilkS")
		)
		(fp_line
			(start -0.7874 0.4064)
			(end 0.7874 0.4064)
			(stroke
				(width 0.1524)
				(type default)
			)
			(layer "B.SilkS")
		)
		(fp_line
			(start 0.7874 -0.4064)
			(end -0.7874 -0.4064)
			(stroke
				(width 0.1524)
				(type default)
			)
			(layer "B.SilkS")
		)
		(fp_line
			(start 0.7874 0.4064)
			(end 0.7874 -0.4064)
			(stroke
				(width 0.1524)
				(type default)
			)
			(layer "B.SilkS")
		)
		(fp_line
			(start -0.67945 -0.3048)
			(end -0.67945 0.3048)
			(stroke
				(width 0.1)
				(type default)
			)
			(layer "B.Fab")
		)
		(fp_line
			(start -0.67945 0.3048)
			(end -0.120396 0.3048)
			(stroke
				(width 0.1)
				(type default)
			)
			(layer "B.Fab")
		)
		(fp_line
			(start -0.12065 -0.3048)
			(end -0.67945 -0.3048)
			(stroke
				(width 0.1)
				(type default)
			)
			(layer "B.Fab")
		)
		(fp_line
			(start -0.12065 -0.2794)
			(end -0.12065 -0.3048)
			(stroke
				(width 0.1)
				(type default)
			)
			(layer "B.Fab")
		)
		(fp_line
			(start -0.120396 0.2794)
			(end 0.12065 0.2794)
			(stroke
				(width 0.1)
				(type default)
			)
			(layer "B.Fab")
		)
		(fp_line
			(start -0.120396 0.3048)
			(end -0.120396 0.2794)
			(stroke
				(width 0.1)
				(type default)
			)
			(layer "B.Fab")
		)
		(fp_line
			(start 0.12065 -0.305054)
			(end 0.12065 -0.2794)
			(stroke
				(width 0.1)
				(type default)
			)
			(layer "B.Fab")
		)
		(fp_line
			(start 0.12065 -0.2794)
			(end -0.12065 -0.2794)
			(stroke
				(width 0.1)
				(type default)
			)
			(layer "B.Fab")
		)
		(fp_line
			(start 0.12065 0.2794)
			(end 0.12065 0.3048)
			(stroke
				(width 0.1)
				(type default)
			)
			(layer "B.Fab")
		)
		(fp_line
			(start 0.12065 0.3048)
			(end 0.67945 0.3048)
			(stroke
				(width 0.1)
				(type default)
			)
			(layer "B.Fab")
		)
		(fp_line
			(start 0.67945 -0.305054)
			(end 0.12065 -0.305054)
			(stroke
				(width 0.1)
				(type default)
			)
			(layer "B.Fab")
		)
		(fp_line
			(start 0.67945 0.3048)
			(end 0.67945 -0.305054)
			(stroke
				(width 0.1)
				(type default)
			)
			(layer "B.Fab")
		)
		(pad "1" smd circle
			(at 0.40005 0 180)
			(size 0 0)
			(layers "B.Cu" "B.Mask" "B.Paste")
			(net "P3V3_AUX")
		)
		(pad "2" smd circle
			(at -0.40005 0 180)
			(size 0 0)
			(layers "B.Cu" "B.Mask" "B.Paste")
			(net "PU_U39_PIN1")
		)
	)
	(footprint ""
		(layer "B.Cu")
		(at 276.3774 -84.201 90)
		(property "Reference" "PR18"
			(at 0 0 90)
			(layer "B.SilkS")
			(hide yes)
			(effects
				(font
					(size 1.27 1.27)
				)
				(justify mirror)
			)
		)
		(property "Value" ""
			(at 0 0 90)
			(layer "B.Fab")
			(effects
				(font
					(size 1.27 1.27)
				)
				(justify mirror)
			)
		)
		(duplicate_pad_numbers_are_jumpers no)
		(fp_line
			(start 1.651 -0.8382)
			(end -1.651 -0.8382)
			(stroke
				(width 0.1524)
				(type default)
			)
			(layer "B.SilkS")
		)
		(fp_line
			(start -1.651 -0.8382)
			(end -1.651 0.8382)
			(stroke
				(width 0.1524)
				(type default)
			)
			(layer "B.SilkS")
		)
		(fp_line
			(start 1.651 0.8382)
			(end 1.651 -0.8382)
			(stroke
				(width 0.1524)
				(type default)
			)
			(layer "B.SilkS")
		)
		(fp_line
			(start -1.651 0.8382)
			(end 1.651 0.8382)
			(stroke
				(width 0.1524)
				(type default)
			)
			(layer "B.SilkS")
		)
		(fp_line
			(start 1.559814 -0.7366)
			(end 1.559814 0.7366)
			(stroke
				(width 0.1)
				(type default)
			)
			(layer "B.Fab")
		)
		(fp_line
			(start 1.524 -0.7366)
			(end 1.559814 -0.7366)
			(stroke
				(width 0.1)
				(type default)
			)
			(layer "B.Fab")
		)
		(fp_line
			(start -1.524 -0.7366)
			(end 1.524 -0.7366)
			(stroke
				(width 0.1)
				(type default)
			)
			(layer "B.Fab")
		)
		(fp_line
			(start -1.560576 -0.7366)
			(end -1.524 -0.7366)
			(stroke
				(width 0.1)
				(type default)
			)
			(layer "B.Fab")
		)
		(fp_line
			(start 1.559814 0.7366)
			(end 1.524 0.7366)
			(stroke
				(width 0.1)
				(type default)
			)
			(layer "B.Fab")
		)
		(fp_line
			(start 1.524 0.7366)
			(end -1.524 0.7366)
			(stroke
				(width 0.1)
				(type default)
			)
			(layer "B.Fab")
		)
		(fp_line
			(start -1.524 0.7366)
			(end -1.560576 0.7366)
			(stroke
				(width 0.1)
				(type default)
			)
			(layer "B.Fab")
		)
		(fp_line
			(start -1.560576 0.7366)
			(end -1.560576 -0.7366)
			(stroke
				(width 0.1)
				(type default)
			)
			(layer "B.Fab")
		)
		(pad "1" smd rect
			(at 0.94996 0 90)
			(size 1.1176 1.3716)
			(layers "B.Cu" "B.Mask" "B.Paste")
			(net "P52V_1")
		)
		(pad "2" smd rect
			(at -0.94996 0 90)
			(size 1.1176 1.3716)
			(layers "B.Cu" "B.Mask" "B.Paste")
			(net "P52V_HS1_ISET")
		)
	)
	(footprint ""
		(layer "B.Cu")
		(at 154.351736 -63.754 90)
		(property "Reference" "PC601"
			(at 0 0 90)
			(layer "B.SilkS")
			(hide yes)
			(effects
				(font
					(size 1.27 1.27)
				)
				(justify mirror)
			)
		)
		(property "Value" ""
			(at 0 0 90)
			(layer "B.Fab")
			(effects
				(font
					(size 1.27 1.27)
				)
				(justify mirror)
			)
		)
		(duplicate_pad_numbers_are_jumpers no)
		(fp_line
			(start 0.7874 -0.4064)
			(end -0.7874 -0.4064)
			(stroke
				(width 0.1524)
				(type default)
			)
			(layer "B.SilkS")
		)
		(fp_line
			(start -0.7874 -0.4064)
			(end -0.7874 0.4064)
			(stroke
				(width 0.1524)
				(type default)
			)
			(layer "B.SilkS")
		)
		(fp_line
			(start 0.7874 0.4064)
			(end 0.7874 -0.4064)
			(stroke
				(width 0.1524)
				(type default)
			)
			(layer "B.SilkS")
		)
		(fp_line
			(start -0.7874 0.4064)
			(end 0.7874 0.4064)
			(stroke
				(width 0.1524)
				(type default)
			)
			(layer "B.SilkS")
		)
		(fp_line
			(start 0.67945 -0.305054)
			(end 0.12065 -0.305054)
			(stroke
				(width 0.1)
				(type default)
			)
			(layer "B.Fab")
		)
		(fp_line
			(start 0.12065 -0.305054)
			(end 0.12065 -0.2794)
			(stroke
				(width 0.1)
				(type default)
			)
			(layer "B.Fab")
		)
		(fp_line
			(start -0.12065 -0.3048)
			(end -0.67945 -0.3048)
			(stroke
				(width 0.1)
				(type default)
			)
			(layer "B.Fab")
		)
		(fp_line
			(start -0.67945 -0.3048)
			(end -0.67945 0.3048)
			(stroke
				(width 0.1)
				(type default)
			)
			(layer "B.Fab")
		)
		(fp_line
			(start 0.12065 -0.2794)
			(end -0.12065 -0.2794)
			(stroke
				(width 0.1)
				(type default)
			)
			(layer "B.Fab")
		)
		(fp_line
			(start -0.12065 -0.2794)
			(end -0.12065 -0.3048)
			(stroke
				(width 0.1)
				(type default)
			)
			(layer "B.Fab")
		)
		(fp_line
			(start 0.12065 0.2794)
			(end 0.12065 0.3048)
			(stroke
				(width 0.1)
				(type default)
			)
			(layer "B.Fab")
		)
		(fp_line
			(start -0.120396 0.2794)
			(end 0.12065 0.2794)
			(stroke
				(width 0.1)
				(type default)
			)
			(layer "B.Fab")
		)
		(fp_line
			(start 0.67945 0.3048)
			(end 0.67945 -0.305054)
			(stroke
				(width 0.1)
				(type default)
			)
			(layer "B.Fab")
		)
		(fp_line
			(start 0.12065 0.3048)
			(end 0.67945 0.3048)
			(stroke
				(width 0.1)
				(type default)
			)
			(layer "B.Fab")
		)
		(fp_line
			(start -0.120396 0.3048)
			(end -0.120396 0.2794)
			(stroke
				(width 0.1)
				(type default)
			)
			(layer "B.Fab")
		)
		(fp_line
			(start -0.67945 0.3048)
			(end -0.120396 0.3048)
			(stroke
				(width 0.1)
				(type default)
			)
			(layer "B.Fab")
		)
		(pad "1" smd circle
			(at 0.40005 0 270)
			(size 0 0)
			(layers "B.Cu" "B.Mask" "B.Paste")
			(net "P52V_HS2_TEMP")
		)
		(pad "2" smd circle
			(at -0.40005 0 270)
			(size 0 0)
			(layers "B.Cu" "B.Mask" "B.Paste")
			(net "GND1_FIELD_SIGNAL")
		)
	)
	(footprint ""
		(layer "B.Cu")
		(at 169.210736 -72.263 180)
		(property "Reference" "R5884"
			(at 0 0 0)
			(layer "B.SilkS")
			(hide yes)
			(effects
				(font
					(size 1.27 1.27)
				)
				(justify mirror)
			)
		)
		(property "Value" ""
			(at 0 0 0)
			(layer "B.Fab")
			(effects
				(font
					(size 1.27 1.27)
				)
				(justify mirror)
			)
		)
		(duplicate_pad_numbers_are_jumpers no)
		(fp_line
			(start 0.7874 0.4064)
			(end 0.7874 -0.4064)
			(stroke
				(width 0.1524)
				(type default)
			)
			(layer "B.SilkS")
		)
		(fp_line
			(start 0.7874 -0.4064)
			(end -0.7874 -0.4064)
			(stroke
				(width 0.1524)
				(type default)
			)
			(layer "B.SilkS")
		)
		(fp_line
			(start -0.7874 0.4064)
			(end 0.7874 0.4064)
			(stroke
				(width 0.1524)
				(type default)
			)
			(layer "B.SilkS")
		)
		(fp_line
			(start -0.7874 -0.4064)
			(end -0.7874 0.4064)
			(stroke
				(width 0.1524)
				(type default)
			)
			(layer "B.SilkS")
		)
		(fp_line
			(start 0.67945 0.3048)
			(end 0.67945 -0.305054)
			(stroke
				(width 0.1)
				(type default)
			)
			(layer "B.Fab")
		)
		(fp_line
			(start 0.67945 -0.305054)
			(end 0.12065 -0.305054)
			(stroke
				(width 0.1)
				(type default)
			)
			(layer "B.Fab")
		)
		(fp_line
			(start 0.12065 0.3048)
			(end 0.67945 0.3048)
			(stroke
				(width 0.1)
				(type default)
			)
			(layer "B.Fab")
		)
		(fp_line
			(start 0.12065 0.2794)
			(end 0.12065 0.3048)
			(stroke
				(width 0.1)
				(type default)
			)
			(layer "B.Fab")
		)
		(fp_line
			(start 0.12065 -0.2794)
			(end -0.12065 -0.2794)
			(stroke
				(width 0.1)
				(type default)
			)
			(layer "B.Fab")
		)
		(fp_line
			(start 0.12065 -0.305054)
			(end 0.12065 -0.2794)
			(stroke
				(width 0.1)
				(type default)
			)
			(layer "B.Fab")
		)
		(fp_line
			(start -0.120396 0.3048)
			(end -0.120396 0.2794)
			(stroke
				(width 0.1)
				(type default)
			)
			(layer "B.Fab")
		)
		(fp_line
			(start -0.120396 0.2794)
			(end 0.12065 0.2794)
			(stroke
				(width 0.1)
				(type default)
			)
			(layer "B.Fab")
		)
		(fp_line
			(start -0.12065 -0.2794)
			(end -0.12065 -0.3048)
			(stroke
				(width 0.1)
				(type default)
			)
			(layer "B.Fab")
		)
		(fp_line
			(start -0.12065 -0.3048)
			(end -0.67945 -0.3048)
			(stroke
				(width 0.1)
				(type default)
			)
			(layer "B.Fab")
		)
		(fp_line
			(start -0.67945 0.3048)
			(end -0.120396 0.3048)
			(stroke
				(width 0.1)
				(type default)
			)
			(layer "B.Fab")
		)
		(fp_line
			(start -0.67945 -0.3048)
			(end -0.67945 0.3048)
			(stroke
				(width 0.1)
				(type default)
			)
			(layer "B.Fab")
		)
		(pad "1" smd circle
			(at 0.40005 0)
			(size 0 0)
			(layers "B.Cu" "B.Mask" "B.Paste")
			(net "P3V3_AUX")
		)
		(pad "2" smd circle
			(at -0.40005 0)
			(size 0 0)
			(layers "B.Cu" "B.Mask" "B.Paste")
			(net "SMB_P52V_PDB_SCL_R2")
		)
	)
	(footprint ""
		(layer "B.Cu")
		(at 175.306736 -80.391 90)
		(property "Reference" "R5880"
			(at 0 0 90)
			(layer "B.SilkS")
			(hide yes)
			(effects
				(font
					(size 1.27 1.27)
				)
				(justify mirror)
			)
		)
		(property "Value" ""
			(at 0 0 90)
			(layer "B.Fab")
			(effects
				(font
					(size 1.27 1.27)
				)
				(justify mirror)
			)
		)
		(duplicate_pad_numbers_are_jumpers no)
		(fp_line
			(start 1.651 -0.8382)
			(end -1.651 -0.8382)
			(stroke
				(width 0.1524)
				(type default)
			)
			(layer "B.SilkS")
		)
		(fp_line
			(start -1.651 -0.8382)
			(end -1.651 0.8382)
			(stroke
				(width 0.1524)
				(type default)
			)
			(layer "B.SilkS")
		)
		(fp_line
			(start 1.651 0.8382)
			(end 1.651 -0.8382)
			(stroke
				(width 0.1524)
				(type default)
			)
			(layer "B.SilkS")
		)
		(fp_line
			(start -1.651 0.8382)
			(end 1.651 0.8382)
			(stroke
				(width 0.1524)
				(type default)
			)
			(layer "B.SilkS")
		)
		(fp_line
			(start 1.559814 -0.7366)
			(end 1.559814 0.7366)
			(stroke
				(width 0.1)
				(type default)
			)
			(layer "B.Fab")
		)
		(fp_line
			(start 1.524 -0.7366)
			(end 1.559814 -0.7366)
			(stroke
				(width 0.1)
				(type default)
			)
			(layer "B.Fab")
		)
		(fp_line
			(start -1.524 -0.7366)
			(end 1.524 -0.7366)
			(stroke
				(width 0.1)
				(type default)
			)
			(layer "B.Fab")
		)
		(fp_line
			(start -1.560576 -0.7366)
			(end -1.524 -0.7366)
			(stroke
				(width 0.1)
				(type default)
			)
			(layer "B.Fab")
		)
		(fp_line
			(start 1.559814 0.7366)
			(end 1.524 0.7366)
			(stroke
				(width 0.1)
				(type default)
			)
			(layer "B.Fab")
		)
		(fp_line
			(start 1.524 0.7366)
			(end -1.524 0.7366)
			(stroke
				(width 0.1)
				(type default)
			)
			(layer "B.Fab")
		)
		(fp_line
			(start -1.524 0.7366)
			(end -1.560576 0.7366)
			(stroke
				(width 0.1)
				(type default)
			)
			(layer "B.Fab")
		)
		(fp_line
			(start -1.560576 0.7366)
			(end -1.560576 -0.7366)
			(stroke
				(width 0.1)
				(type default)
			)
			(layer "B.Fab")
		)
		(pad "1" smd rect
			(at 0.94996 0 90)
			(size 1.1176 1.3716)
			(layers "B.Cu" "B.Mask" "B.Paste")
			(net "P52V_HS2")
		)
		(pad "2" smd rect
			(at -0.94996 0 90)
			(size 1.1176 1.3716)
			(layers "B.Cu" "B.Mask" "B.Paste")
			(net "PWRGD_P52V_HS2_PG")
		)
	)
	(footprint ""
		(layer "B.Cu")
		(at 263.2964 -77.978 90)
		(property "Reference" "PR5"
			(at 0 0 90)
			(layer "B.SilkS")
			(hide yes)
			(effects
				(font
					(size 1.27 1.27)
				)
				(justify mirror)
			)
		)
		(property "Value" ""
			(at 0 0 90)
			(layer "B.Fab")
			(effects
				(font
					(size 1.27 1.27)
				)
				(justify mirror)
			)
		)
		(duplicate_pad_numbers_are_jumpers no)
		(fp_line
			(start 2.234946 -0.9271)
			(end -2.234946 -0.9271)
			(stroke
				(width 0.1524)
				(type default)
			)
			(layer "B.SilkS")
		)
		(fp_line
			(start -2.234946 -0.9271)
			(end -2.234946 0.9271)
			(stroke
				(width 0.1524)
				(type default)
			)
			(layer "B.SilkS")
		)
		(fp_line
			(start 2.234946 0.9271)
			(end 2.234946 -0.9271)
			(stroke
				(width 0.1524)
				(type default)
			)
			(layer "B.SilkS")
		)
		(fp_line
			(start -2.234946 0.9271)
			(end 2.234946 0.9271)
			(stroke
				(width 0.1524)
				(type default)
			)
			(layer "B.SilkS")
		)
		(fp_line
			(start 1.575054 -0.824992)
			(end 1.575054 0.824992)
			(stroke
				(width 0.1)
				(type default)
			)
			(layer "B.Fab")
		)
		(fp_line
			(start -1.575054 -0.824992)
			(end 1.575054 -0.824992)
			(stroke
				(width 0.1)
				(type default)
			)
			(layer "B.Fab")
		)
		(fp_line
			(start 1.575054 0.824992)
			(end -1.575054 0.824992)
			(stroke
				(width 0.1)
				(type default)
			)
			(layer "B.Fab")
		)
		(fp_line
			(start -1.575054 0.824992)
			(end -1.575054 -0.824992)
			(stroke
				(width 0.1)
				(type default)
			)
			(layer "B.Fab")
		)
		(pad "1" smd rect
			(at 1.599946 0 270)
			(size 1.016 1.6002)
			(layers "B.Cu" "B.Mask" "B.Paste")
			(net "P52V_1")
		)
		(pad "2" smd rect
			(at -1.599946 0 270)
			(size 1.016 1.6002)
			(layers "B.Cu" "B.Mask" "B.Paste")
			(net "P52V_HS1_VCC")
		)
	)
	(footprint ""
		(layer "B.Cu")
		(at 187.8584 -40.259 90)
		(property "Reference" "FS6"
			(at -6.477 2.99593 270)
			(unlocked yes)
			(layer "B.SilkS")
			(effects
				(font
					(size 0.7874 0.5842)
					(thickness 0.1524)
				)
				(justify left mirror)
			)
		)
		(property "Value" ""
			(at 0 0 90)
			(layer "B.Fab")
			(effects
				(font
					(size 1.27 1.27)
				)
				(justify mirror)
			)
		)
		(duplicate_pad_numbers_are_jumpers no)
		(fp_line
			(start 6.427724 -1.8415)
			(end 6.427724 1.8415)
			(stroke
				(width 0.1524)
				(type default)
			)
			(layer "B.SilkS")
		)
		(fp_line
			(start -6.427724 -1.8415)
			(end 6.427724 -1.8415)
			(stroke
				(width 0.1524)
				(type default)
			)
			(layer "B.SilkS")
		)
		(fp_line
			(start 6.427724 1.8415)
			(end -6.427724 1.8415)
			(stroke
				(width 0.1524)
				(type default)
			)
			(layer "B.SilkS")
		)
		(fp_line
			(start -6.427724 1.8415)
			(end -6.427724 -1.8415)
			(stroke
				(width 0.1524)
				(type default)
			)
			(layer "B.SilkS")
		)
		(fp_line
			(start 5.225034 -1.610106)
			(end -5.225034 -1.610106)
			(stroke
				(width 0.1)
				(type default)
			)
			(layer "B.Fab")
		)
		(fp_line
			(start -5.225034 -1.610106)
			(end -5.225034 1.610106)
			(stroke
				(width 0.1)
				(type default)
			)
			(layer "B.Fab")
		)
		(fp_line
			(start 5.225034 1.610106)
			(end 5.225034 -1.610106)
			(stroke
				(width 0.1)
				(type default)
			)
			(layer "B.Fab")
		)
		(fp_line
			(start -5.225034 1.610106)
			(end 5.225034 1.610106)
			(stroke
				(width 0.1)
				(type default)
			)
			(layer "B.Fab")
		)
		(pad "1" smd rect
			(at 4.675124 0 270)
			(size 3.2512 3.429)
			(layers "B.Cu" "B.Mask" "B.Paste")
			(net "P52V_2_FUSE_1")
		)
		(pad "2" smd rect
			(at -4.675124 0 270)
			(size 3.2512 3.429)
			(layers "B.Cu" "B.Mask" "B.Paste")
			(net "P52V_2")
		)
	)
	(footprint ""
		(layer "B.Cu")
		(at 286.2834 -63.246 90)
		(property "Reference" "PR33"
			(at 0 0 90)
			(layer "B.SilkS")
			(hide yes)
			(effects
				(font
					(size 1.27 1.27)
				)
				(justify mirror)
			)
		)
		(property "Value" ""
			(at 0 0 90)
			(layer "B.Fab")
			(effects
				(font
					(size 1.27 1.27)
				)
				(justify mirror)
			)
		)
		(duplicate_pad_numbers_are_jumpers no)
		(fp_line
			(start 0.7874 -0.4064)
			(end -0.7874 -0.4064)
			(stroke
				(width 0.1524)
				(type default)
			)
			(layer "B.SilkS")
		)
		(fp_line
			(start -0.7874 -0.4064)
			(end -0.7874 0.4064)
			(stroke
				(width 0.1524)
				(type default)
			)
			(layer "B.SilkS")
		)
		(fp_line
			(start 0.7874 0.4064)
			(end 0.7874 -0.4064)
			(stroke
				(width 0.1524)
				(type default)
			)
			(layer "B.SilkS")
		)
		(fp_line
			(start -0.7874 0.4064)
			(end 0.7874 0.4064)
			(stroke
				(width 0.1524)
				(type default)
			)
			(layer "B.SilkS")
		)
		(fp_line
			(start 0.67945 -0.305054)
			(end 0.12065 -0.305054)
			(stroke
				(width 0.1)
				(type default)
			)
			(layer "B.Fab")
		)
		(fp_line
			(start 0.12065 -0.305054)
			(end 0.12065 -0.2794)
			(stroke
				(width 0.1)
				(type default)
			)
			(layer "B.Fab")
		)
		(fp_line
			(start -0.12065 -0.3048)
			(end -0.67945 -0.3048)
			(stroke
				(width 0.1)
				(type default)
			)
			(layer "B.Fab")
		)
		(fp_line
			(start -0.67945 -0.3048)
			(end -0.67945 0.3048)
			(stroke
				(width 0.1)
				(type default)
			)
			(layer "B.Fab")
		)
		(fp_line
			(start 0.12065 -0.2794)
			(end -0.12065 -0.2794)
			(stroke
				(width 0.1)
				(type default)
			)
			(layer "B.Fab")
		)
		(fp_line
			(start -0.12065 -0.2794)
			(end -0.12065 -0.3048)
			(stroke
				(width 0.1)
				(type default)
			)
			(layer "B.Fab")
		)
		(fp_line
			(start 0.12065 0.2794)
			(end 0.12065 0.3048)
			(stroke
				(width 0.1)
				(type default)
			)
			(layer "B.Fab")
		)
		(fp_line
			(start -0.120396 0.2794)
			(end 0.12065 0.2794)
			(stroke
				(width 0.1)
				(type default)
			)
			(layer "B.Fab")
		)
		(fp_line
			(start 0.67945 0.3048)
			(end 0.67945 -0.305054)
			(stroke
				(width 0.1)
				(type default)
			)
			(layer "B.Fab")
		)
		(fp_line
			(start 0.12065 0.3048)
			(end 0.67945 0.3048)
			(stroke
				(width 0.1)
				(type default)
			)
			(layer "B.Fab")
		)
		(fp_line
			(start -0.120396 0.3048)
			(end -0.120396 0.2794)
			(stroke
				(width 0.1)
				(type default)
			)
			(layer "B.Fab")
		)
		(fp_line
			(start -0.67945 0.3048)
			(end -0.120396 0.3048)
			(stroke
				(width 0.1)
				(type default)
			)
			(layer "B.Fab")
		)
		(pad "1" smd circle
			(at 0.40005 0 270)
			(size 0 0)
			(layers "B.Cu" "B.Mask" "B.Paste")
			(net "HS1_TMR1")
		)
		(pad "2" smd circle
			(at -0.40005 0 270)
			(size 0 0)
			(layers "B.Cu" "B.Mask" "B.Paste")
			(net "HS1_TMR2")
		)
	)
	(footprint ""
		(layer "B.Cu")
		(at 168.829736 -66.675)
		(property "Reference" "PR7026"
			(at 0 0 0)
			(layer "B.SilkS")
			(hide yes)
			(effects
				(font
					(size 1.27 1.27)
				)
				(justify mirror)
			)
		)
		(property "Value" ""
			(at 0 0 0)
			(layer "B.Fab")
			(effects
				(font
					(size 1.27 1.27)
				)
				(justify mirror)
			)
		)
		(duplicate_pad_numbers_are_jumpers no)
		(fp_line
			(start -0.7874 -0.4064)
			(end -0.7874 0.4064)
			(stroke
				(width 0.1524)
				(type default)
			)
			(layer "B.SilkS")
		)
		(fp_line
			(start -0.7874 0.4064)
			(end 0.7874 0.4064)
			(stroke
				(width 0.1524)
				(type default)
			)
			(layer "B.SilkS")
		)
		(fp_line
			(start 0.7874 -0.4064)
			(end -0.7874 -0.4064)
			(stroke
				(width 0.1524)
				(type default)
			)
			(layer "B.SilkS")
		)
		(fp_line
			(start 0.7874 0.4064)
			(end 0.7874 -0.4064)
			(stroke
				(width 0.1524)
				(type default)
			)
			(layer "B.SilkS")
		)
		(fp_line
			(start -0.67945 -0.3048)
			(end -0.67945 0.3048)
			(stroke
				(width 0.1)
				(type default)
			)
			(layer "B.Fab")
		)
		(fp_line
			(start -0.67945 0.3048)
			(end -0.120396 0.3048)
			(stroke
				(width 0.1)
				(type default)
			)
			(layer "B.Fab")
		)
		(fp_line
			(start -0.12065 -0.3048)
			(end -0.67945 -0.3048)
			(stroke
				(width 0.1)
				(type default)
			)
			(layer "B.Fab")
		)
		(fp_line
			(start -0.12065 -0.2794)
			(end -0.12065 -0.3048)
			(stroke
				(width 0.1)
				(type default)
			)
			(layer "B.Fab")
		)
		(fp_line
			(start -0.120396 0.2794)
			(end 0.12065 0.2794)
			(stroke
				(width 0.1)
				(type default)
			)
			(layer "B.Fab")
		)
		(fp_line
			(start -0.120396 0.3048)
			(end -0.120396 0.2794)
			(stroke
				(width 0.1)
				(type default)
			)
			(layer "B.Fab")
		)
		(fp_line
			(start 0.12065 -0.305054)
			(end 0.12065 -0.2794)
			(stroke
				(width 0.1)
				(type default)
			)
			(layer "B.Fab")
		)
		(fp_line
			(start 0.12065 -0.2794)
			(end -0.12065 -0.2794)
			(stroke
				(width 0.1)
				(type default)
			)
			(layer "B.Fab")
		)
		(fp_line
			(start 0.12065 0.2794)
			(end 0.12065 0.3048)
			(stroke
				(width 0.1)
				(type default)
			)
			(layer "B.Fab")
		)
		(fp_line
			(start 0.12065 0.3048)
			(end 0.67945 0.3048)
			(stroke
				(width 0.1)
				(type default)
			)
			(layer "B.Fab")
		)
		(fp_line
			(start 0.67945 -0.305054)
			(end 0.12065 -0.305054)
			(stroke
				(width 0.1)
				(type default)
			)
			(layer "B.Fab")
		)
		(fp_line
			(start 0.67945 0.3048)
			(end 0.67945 -0.305054)
			(stroke
				(width 0.1)
				(type default)
			)
			(layer "B.Fab")
		)
		(pad "1" smd circle
			(at 0.40005 0 180)
			(size 0 0)
			(layers "B.Cu" "B.Mask" "B.Paste")
			(net "P52V_HS2_ISET")
		)
		(pad "2" smd circle
			(at -0.40005 0 180)
			(size 0 0)
			(layers "B.Cu" "B.Mask" "B.Paste")
			(net "P52V_HS2_VCAP")
		)
	)
	(footprint ""
		(layer "B.Cu")
		(at 26.015188 -153.501344)
		(property "Reference" ""
			(at 0 0 0)
			(layer "B.SilkS")
			(hide yes)
			(effects
				(font
					(size 1.27 1.27)
				)
				(justify mirror)
			)
		)
		(property "Value" ""
			(at 0 0 0)
			(layer "B.Fab")
			(effects
				(font
					(size 1.27 1.27)
				)
				(justify mirror)
			)
		)
		(duplicate_pad_numbers_are_jumpers no)
		(pad "1" smd circle
			(at 0 0 180)
			(size 0.9906 0.9906)
			(layers "B.Cu" "B.Mask" "B.Paste")
			(net "Net_243")
		)
		(zone
			(layer "B.Cu")
			(hatch none 0.5)
			(connect_pads
				(clearance 0)
			)
			(min_thickness 0.25)
			(keepout
				(tracks not_allowed)
				(vias allowed)
				(pads allowed)
				(copperpour not_allowed)
				(footprints allowed)
			)
			(placement
				(enabled no)
				(sheetname "")
			)
			(fill
				(thermal_gap 0.5)
				(thermal_bridge_width 0.5)
				(island_removal_mode 0)
			)
			(polygon
				(pts
					(arc
						(start 27.640788 -153.501344)
						(mid 24.389588 -153.501344)
						(end 27.640788 -153.501344)
					)
				)
			)
		)
	)
	(footprint ""
		(layer "B.Cu")
		(at 436.3085 -152.304496)
		(property "Reference" ""
			(at 0 0 0)
			(layer "B.SilkS")
			(hide yes)
			(effects
				(font
					(size 1.27 1.27)
				)
				(justify mirror)
			)
		)
		(property "Value" ""
			(at 0 0 0)
			(layer "B.Fab")
			(effects
				(font
					(size 1.27 1.27)
				)
				(justify mirror)
			)
		)
		(duplicate_pad_numbers_are_jumpers no)
		(pad "1" smd circle
			(at 0 0 180)
			(size 0.9906 0.9906)
			(layers "B.Cu" "B.Mask" "B.Paste")
			(net "Net_244")
		)
		(zone
			(layer "B.Cu")
			(hatch none 0.5)
			(connect_pads
				(clearance 0)
			)
			(min_thickness 0.25)
			(keepout
				(tracks not_allowed)
				(vias allowed)
				(pads allowed)
				(copperpour not_allowed)
				(footprints allowed)
			)
			(placement
				(enabled no)
				(sheetname "")
			)
			(fill
				(thermal_gap 0.5)
				(thermal_bridge_width 0.5)
				(island_removal_mode 0)
			)
			(polygon
				(pts
					(arc
						(start 437.9341 -152.304496)
						(mid 434.6829 -152.304496)
						(end 437.9341 -152.304496)
					)
				)
			)
		)
	)
	(footprint ""
		(layer "B.Cu")
		(at 277.3934 -71.882)
		(property "Reference" "PR6934"
			(at 0 0 0)
			(layer "B.SilkS")
			(hide yes)
			(effects
				(font
					(size 1.27 1.27)
				)
				(justify mirror)
			)
		)
		(property "Value" ""
			(at 0 0 0)
			(layer "B.Fab")
			(effects
				(font
					(size 1.27 1.27)
				)
				(justify mirror)
			)
		)
		(duplicate_pad_numbers_are_jumpers no)
		(fp_line
			(start -0.7874 -0.4064)
			(end -0.7874 0.4064)
			(stroke
				(width 0.1524)
				(type default)
			)
			(layer "B.SilkS")
		)
		(fp_line
			(start -0.7874 0.4064)
			(end 0.7874 0.4064)
			(stroke
				(width 0.1524)
				(type default)
			)
			(layer "B.SilkS")
		)
		(fp_line
			(start 0.7874 -0.4064)
			(end -0.7874 -0.4064)
			(stroke
				(width 0.1524)
				(type default)
			)
			(layer "B.SilkS")
		)
		(fp_line
			(start 0.7874 0.4064)
			(end 0.7874 -0.4064)
			(stroke
				(width 0.1524)
				(type default)
			)
			(layer "B.SilkS")
		)
		(fp_line
			(start -0.67945 -0.3048)
			(end -0.67945 0.3048)
			(stroke
				(width 0.1)
				(type default)
			)
			(layer "B.Fab")
		)
		(fp_line
			(start -0.67945 0.3048)
			(end -0.120396 0.3048)
			(stroke
				(width 0.1)
				(type default)
			)
			(layer "B.Fab")
		)
		(fp_line
			(start -0.12065 -0.3048)
			(end -0.67945 -0.3048)
			(stroke
				(width 0.1)
				(type default)
			)
			(layer "B.Fab")
		)
		(fp_line
			(start -0.12065 -0.2794)
			(end -0.12065 -0.3048)
			(stroke
				(width 0.1)
				(type default)
			)
			(layer "B.Fab")
		)
		(fp_line
			(start -0.120396 0.2794)
			(end 0.12065 0.2794)
			(stroke
				(width 0.1)
				(type default)
			)
			(layer "B.Fab")
		)
		(fp_line
			(start -0.120396 0.3048)
			(end -0.120396 0.2794)
			(stroke
				(width 0.1)
				(type default)
			)
			(layer "B.Fab")
		)
		(fp_line
			(start 0.12065 -0.305054)
			(end 0.12065 -0.2794)
			(stroke
				(width 0.1)
				(type default)
			)
			(layer "B.Fab")
		)
		(fp_line
			(start 0.12065 -0.2794)
			(end -0.12065 -0.2794)
			(stroke
				(width 0.1)
				(type default)
			)
			(layer "B.Fab")
		)
		(fp_line
			(start 0.12065 0.2794)
			(end 0.12065 0.3048)
			(stroke
				(width 0.1)
				(type default)
			)
			(layer "B.Fab")
		)
		(fp_line
			(start 0.12065 0.3048)
			(end 0.67945 0.3048)
			(stroke
				(width 0.1)
				(type default)
			)
			(layer "B.Fab")
		)
		(fp_line
			(start 0.67945 -0.305054)
			(end 0.12065 -0.305054)
			(stroke
				(width 0.1)
				(type default)
			)
			(layer "B.Fab")
		)
		(fp_line
			(start 0.67945 0.3048)
			(end 0.67945 -0.305054)
			(stroke
				(width 0.1)
				(type default)
			)
			(layer "B.Fab")
		)
		(pad "1" smd circle
			(at 0.40005 0 180)
			(size 0 0)
			(layers "B.Cu" "B.Mask" "B.Paste")
			(net "P52V_HS1_ISTART")
		)
		(pad "2" smd circle
			(at -0.40005 0 180)
			(size 0 0)
			(layers "B.Cu" "B.Mask" "B.Paste")
			(net "P52V_HS1_VCAP")
		)
	)
	(footprint ""
		(layer "B.Cu")
		(at 341.4014 -40.7162)
		(property "Reference" "PC583"
			(at 0 0 0)
			(layer "B.SilkS")
			(hide yes)
			(effects
				(font
					(size 1.27 1.27)
				)
				(justify mirror)
			)
		)
		(property "Value" ""
			(at 0 0 0)
			(layer "B.Fab")
			(effects
				(font
					(size 1.27 1.27)
				)
				(justify mirror)
			)
		)
		(duplicate_pad_numbers_are_jumpers no)
		(fp_line
			(start -1.2954 -0.5842)
			(end -1.2954 0.5842)
			(stroke
				(width 0.1524)
				(type default)
			)
			(layer "B.SilkS")
		)
		(fp_line
			(start -1.2954 0.5842)
			(end 1.2954 0.5842)
			(stroke
				(width 0.1524)
				(type default)
			)
			(layer "B.SilkS")
		)
		(fp_line
			(start 1.2954 -0.5842)
			(end -1.2954 -0.5842)
			(stroke
				(width 0.1524)
				(type default)
			)
			(layer "B.SilkS")
		)
		(fp_line
			(start 1.2954 0.5842)
			(end 1.2954 -0.5842)
			(stroke
				(width 0.1524)
				(type default)
			)
			(layer "B.SilkS")
		)
		(fp_line
			(start -1.1938 -0.4064)
			(end -1.1938 0.4064)
			(stroke
				(width 0.1)
				(type default)
			)
			(layer "B.Fab")
		)
		(fp_line
			(start -1.1938 0.4064)
			(end -0.8636 0.4064)
			(stroke
				(width 0.1)
				(type default)
			)
			(layer "B.Fab")
		)
		(fp_line
			(start -0.8636 -0.4572)
			(end -0.8636 -0.4064)
			(stroke
				(width 0.1)
				(type default)
			)
			(layer "B.Fab")
		)
		(fp_line
			(start -0.8636 -0.4064)
			(end -1.1938 -0.4064)
			(stroke
				(width 0.1)
				(type default)
			)
			(layer "B.Fab")
		)
		(fp_line
			(start -0.8636 0.4064)
			(end -0.8636 0.4572)
			(stroke
				(width 0.1)
				(type default)
			)
			(layer "B.Fab")
		)
		(fp_line
			(start -0.8636 0.4572)
			(end 0.8636 0.4572)
			(stroke
				(width 0.1)
				(type default)
			)
			(layer "B.Fab")
		)
		(fp_line
			(start 0.8636 -0.4572)
			(end -0.8636 -0.4572)
			(stroke
				(width 0.1)
				(type default)
			)
			(layer "B.Fab")
		)
		(fp_line
			(start 0.8636 -0.4064)
			(end 0.8636 -0.4572)
			(stroke
				(width 0.1)
				(type default)
			)
			(layer "B.Fab")
		)
		(fp_line
			(start 0.8636 0.4064)
			(end 1.1938 0.4064)
			(stroke
				(width 0.1)
				(type default)
			)
			(layer "B.Fab")
		)
		(fp_line
			(start 0.8636 0.4572)
			(end 0.8636 0.4064)
			(stroke
				(width 0.1)
				(type default)
			)
			(layer "B.Fab")
		)
		(fp_line
			(start 1.1938 -0.4064)
			(end 0.8636 -0.4064)
			(stroke
				(width 0.1)
				(type default)
			)
			(layer "B.Fab")
		)
		(fp_line
			(start 1.1938 0.4064)
			(end 1.1938 -0.4064)
			(stroke
				(width 0.1)
				(type default)
			)
			(layer "B.Fab")
		)
		(pad "1" smd rect
			(at 0.7366 0 270)
			(size 0.7112 0.8128)
			(layers "B.Cu" "B.Mask" "B.Paste")
			(net "GND")
		)
		(pad "2" smd rect
			(at -0.7366 0 270)
			(size 0.7112 0.8128)
			(layers "B.Cu" "B.Mask" "B.Paste")
			(net "P52V_HS1_GATE2_R1")
		)
	)
	(footprint ""
		(layer "B.Cu")
		(at 284.2514 -63.119)
		(property "Reference" "PC83"
			(at 0 0 0)
			(layer "B.SilkS")
			(hide yes)
			(effects
				(font
					(size 1.27 1.27)
				)
				(justify mirror)
			)
		)
		(property "Value" ""
			(at 0 0 0)
			(layer "B.Fab")
			(effects
				(font
					(size 1.27 1.27)
				)
				(justify mirror)
			)
		)
		(duplicate_pad_numbers_are_jumpers no)
		(fp_line
			(start -1.2954 -0.5842)
			(end -1.2954 0.5842)
			(stroke
				(width 0.1524)
				(type default)
			)
			(layer "B.SilkS")
		)
		(fp_line
			(start -1.2954 0.5842)
			(end 1.2954 0.5842)
			(stroke
				(width 0.1524)
				(type default)
			)
			(layer "B.SilkS")
		)
		(fp_line
			(start 1.2954 -0.5842)
			(end -1.2954 -0.5842)
			(stroke
				(width 0.1524)
				(type default)
			)
			(layer "B.SilkS")
		)
		(fp_line
			(start 1.2954 0.5842)
			(end 1.2954 -0.5842)
			(stroke
				(width 0.1524)
				(type default)
			)
			(layer "B.SilkS")
		)
		(fp_line
			(start -1.1938 -0.4064)
			(end -1.1938 0.4064)
			(stroke
				(width 0.1)
				(type default)
			)
			(layer "B.Fab")
		)
		(fp_line
			(start -1.1938 0.4064)
			(end -0.8636 0.4064)
			(stroke
				(width 0.1)
				(type default)
			)
			(layer "B.Fab")
		)
		(fp_line
			(start -0.8636 -0.4572)
			(end -0.8636 -0.4064)
			(stroke
				(width 0.1)
				(type default)
			)
			(layer "B.Fab")
		)
		(fp_line
			(start -0.8636 -0.4064)
			(end -1.1938 -0.4064)
			(stroke
				(width 0.1)
				(type default)
			)
			(layer "B.Fab")
		)
		(fp_line
			(start -0.8636 0.4064)
			(end -0.8636 0.4572)
			(stroke
				(width 0.1)
				(type default)
			)
			(layer "B.Fab")
		)
		(fp_line
			(start -0.8636 0.4572)
			(end 0.8636 0.4572)
			(stroke
				(width 0.1)
				(type default)
			)
			(layer "B.Fab")
		)
		(fp_line
			(start 0.8636 -0.4572)
			(end -0.8636 -0.4572)
			(stroke
				(width 0.1)
				(type default)
			)
			(layer "B.Fab")
		)
		(fp_line
			(start 0.8636 -0.4064)
			(end 0.8636 -0.4572)
			(stroke
				(width 0.1)
				(type default)
			)
			(layer "B.Fab")
		)
		(fp_line
			(start 0.8636 0.4064)
			(end 1.1938 0.4064)
			(stroke
				(width 0.1)
				(type default)
			)
			(layer "B.Fab")
		)
		(fp_line
			(start 0.8636 0.4572)
			(end 0.8636 0.4064)
			(stroke
				(width 0.1)
				(type default)
			)
			(layer "B.Fab")
		)
		(fp_line
			(start 1.1938 -0.4064)
			(end 0.8636 -0.4064)
			(stroke
				(width 0.1)
				(type default)
			)
			(layer "B.Fab")
		)
		(fp_line
			(start 1.1938 0.4064)
			(end 1.1938 -0.4064)
			(stroke
				(width 0.1)
				(type default)
			)
			(layer "B.Fab")
		)
		(pad "1" smd rect
			(at 0.7366 0 270)
			(size 0.7112 0.8128)
			(layers "B.Cu" "B.Mask" "B.Paste")
			(net "HS1_TMR2")
		)
		(pad "2" smd rect
			(at -0.7366 0 270)
			(size 0.7112 0.8128)
			(layers "B.Cu" "B.Mask" "B.Paste")
			(net "GND_FIELD_SIGNAL")
		)
	)
	(footprint ""
		(layer "B.Cu")
		(at 169.210736 -73.279 180)
		(property "Reference" "R5885"
			(at 0 0 0)
			(layer "B.SilkS")
			(hide yes)
			(effects
				(font
					(size 1.27 1.27)
				)
				(justify mirror)
			)
		)
		(property "Value" ""
			(at 0 0 0)
			(layer "B.Fab")
			(effects
				(font
					(size 1.27 1.27)
				)
				(justify mirror)
			)
		)
		(duplicate_pad_numbers_are_jumpers no)
		(fp_line
			(start 0.7874 0.4064)
			(end 0.7874 -0.4064)
			(stroke
				(width 0.1524)
				(type default)
			)
			(layer "B.SilkS")
		)
		(fp_line
			(start 0.7874 -0.4064)
			(end -0.7874 -0.4064)
			(stroke
				(width 0.1524)
				(type default)
			)
			(layer "B.SilkS")
		)
		(fp_line
			(start -0.7874 0.4064)
			(end 0.7874 0.4064)
			(stroke
				(width 0.1524)
				(type default)
			)
			(layer "B.SilkS")
		)
		(fp_line
			(start -0.7874 -0.4064)
			(end -0.7874 0.4064)
			(stroke
				(width 0.1524)
				(type default)
			)
			(layer "B.SilkS")
		)
		(fp_line
			(start 0.67945 0.3048)
			(end 0.67945 -0.305054)
			(stroke
				(width 0.1)
				(type default)
			)
			(layer "B.Fab")
		)
		(fp_line
			(start 0.67945 -0.305054)
			(end 0.12065 -0.305054)
			(stroke
				(width 0.1)
				(type default)
			)
			(layer "B.Fab")
		)
		(fp_line
			(start 0.12065 0.3048)
			(end 0.67945 0.3048)
			(stroke
				(width 0.1)
				(type default)
			)
			(layer "B.Fab")
		)
		(fp_line
			(start 0.12065 0.2794)
			(end 0.12065 0.3048)
			(stroke
				(width 0.1)
				(type default)
			)
			(layer "B.Fab")
		)
		(fp_line
			(start 0.12065 -0.2794)
			(end -0.12065 -0.2794)
			(stroke
				(width 0.1)
				(type default)
			)
			(layer "B.Fab")
		)
		(fp_line
			(start 0.12065 -0.305054)
			(end 0.12065 -0.2794)
			(stroke
				(width 0.1)
				(type default)
			)
			(layer "B.Fab")
		)
		(fp_line
			(start -0.120396 0.3048)
			(end -0.120396 0.2794)
			(stroke
				(width 0.1)
				(type default)
			)
			(layer "B.Fab")
		)
		(fp_line
			(start -0.120396 0.2794)
			(end 0.12065 0.2794)
			(stroke
				(width 0.1)
				(type default)
			)
			(layer "B.Fab")
		)
		(fp_line
			(start -0.12065 -0.2794)
			(end -0.12065 -0.3048)
			(stroke
				(width 0.1)
				(type default)
			)
			(layer "B.Fab")
		)
		(fp_line
			(start -0.12065 -0.3048)
			(end -0.67945 -0.3048)
			(stroke
				(width 0.1)
				(type default)
			)
			(layer "B.Fab")
		)
		(fp_line
			(start -0.67945 0.3048)
			(end -0.120396 0.3048)
			(stroke
				(width 0.1)
				(type default)
			)
			(layer "B.Fab")
		)
		(fp_line
			(start -0.67945 -0.3048)
			(end -0.67945 0.3048)
			(stroke
				(width 0.1)
				(type default)
			)
			(layer "B.Fab")
		)
		(pad "1" smd circle
			(at 0.40005 0)
			(size 0 0)
			(layers "B.Cu" "B.Mask" "B.Paste")
			(net "P3V3_AUX")
		)
		(pad "2" smd circle
			(at -0.40005 0)
			(size 0 0)
			(layers "B.Cu" "B.Mask" "B.Paste")
			(net "SMB_P52V_PDB_SDA")
		)
	)
	(footprint ""
		(layer "B.Cu")
		(at 255.778 -52.832 90)
		(property "Reference" "PD7"
			(at 5.08 2.64033 270)
			(unlocked yes)
			(layer "B.SilkS")
			(effects
				(font
					(size 0.7874 0.5842)
					(thickness 0.1524)
				)
				(justify left mirror)
			)
		)
		(property "Value" ""
			(at 0 0 90)
			(layer "B.Fab")
			(effects
				(font
					(size 1.27 1.27)
				)
				(justify mirror)
			)
		)
		(duplicate_pad_numbers_are_jumpers no)
		(fp_line
			(start 4.664456 -3.109976)
			(end -4.743704 -3.109976)
			(stroke
				(width 0.1524)
				(type default)
			)
			(layer "B.SilkS")
		)
		(fp_line
			(start -4.183126 -3.109976)
			(end -4.794504 -3.109976)
			(stroke
				(width 0.1524)
				(type default)
			)
			(layer "B.SilkS")
		)
		(fp_line
			(start -4.511802 -3.109976)
			(end -4.207002 -3.109976)
			(stroke
				(width 0.1524)
				(type default)
			)
			(layer "B.SilkS")
		)
		(fp_line
			(start -4.6101 -3.109976)
			(end -4.283202 -3.109976)
			(stroke
				(width 0.1524)
				(type default)
			)
			(layer "B.SilkS")
		)
		(fp_line
			(start -4.695444 -3.109976)
			(end -4.695444 3.109976)
			(stroke
				(width 0.1524)
				(type default)
			)
			(layer "B.SilkS")
		)
		(fp_line
			(start -4.70535 -3.109976)
			(end -4.70535 3.109976)
			(stroke
				(width 0.1524)
				(type default)
			)
			(layer "B.SilkS")
		)
		(fp_line
			(start -4.70535 -3.109976)
			(end -4.70535 3.109976)
			(stroke
				(width 0.1524)
				(type default)
			)
			(layer "B.SilkS")
		)
		(fp_line
			(start -4.70535 -3.109976)
			(end -4.70535 3.109976)
			(stroke
				(width 0.1524)
				(type default)
			)
			(layer "B.SilkS")
		)
		(fp_line
			(start -4.805426 -3.109976)
			(end -4.805426 3.109976)
			(stroke
				(width 0.1524)
				(type default)
			)
			(layer "B.SilkS")
		)
		(fp_line
			(start -4.932426 -3.109976)
			(end -4.932426 3.109976)
			(stroke
				(width 0.1524)
				(type default)
			)
			(layer "B.SilkS")
		)
		(fp_line
			(start -5.008626 -3.109976)
			(end -5.008626 3.109976)
			(stroke
				(width 0.1524)
				(type default)
			)
			(layer "B.SilkS")
		)
		(fp_line
			(start -5.110226 -3.109976)
			(end -5.110226 3.109976)
			(stroke
				(width 0.1524)
				(type default)
			)
			(layer "B.SilkS")
		)
		(fp_line
			(start -5.211826 -3.109976)
			(end -5.211826 3.109976)
			(stroke
				(width 0.1524)
				(type default)
			)
			(layer "B.SilkS")
		)
		(fp_line
			(start -5.262626 -3.109976)
			(end -5.262626 3.109976)
			(stroke
				(width 0.1524)
				(type default)
			)
			(layer "B.SilkS")
		)
		(fp_line
			(start -5.313426 -3.109976)
			(end -5.313426 1.0414)
			(stroke
				(width 0.1524)
				(type default)
			)
			(layer "B.SilkS")
		)
		(fp_line
			(start -5.4102 -3.109976)
			(end -4.783074 -3.109976)
			(stroke
				(width 0.1524)
				(type default)
			)
			(layer "B.SilkS")
		)
		(fp_line
			(start 0.508 -1.016)
			(end -0.762 0)
			(stroke
				(width 0.1524)
				(type default)
			)
			(layer "B.SilkS")
		)
		(fp_line
			(start 1.0668 0)
			(end 0.6096 0)
			(stroke
				(width 0.1524)
				(type default)
			)
			(layer "B.SilkS")
		)
		(fp_line
			(start -0.762 0)
			(end -1.2192 0)
			(stroke
				(width 0.1524)
				(type default)
			)
			(layer "B.SilkS")
		)
		(fp_line
			(start -0.762 0)
			(end 0.508 1.016)
			(stroke
				(width 0.1524)
				(type default)
			)
			(layer "B.SilkS")
		)
		(fp_line
			(start 0.508 1.016)
			(end 0.508 -1.016)
			(stroke
				(width 0.1524)
				(type default)
			)
			(layer "B.SilkS")
		)
		(fp_line
			(start -5.4102 1.0668)
			(end -5.4102 -3.109976)
			(stroke
				(width 0.1524)
				(type default)
			)
			(layer "B.SilkS")
		)
		(fp_line
			(start -0.762 1.27)
			(end -0.762 -1.27)
			(stroke
				(width 0.1524)
				(type default)
			)
			(layer "B.SilkS")
		)
		(fp_line
			(start -5.313426 2.032)
			(end -5.313426 3.109976)
			(stroke
				(width 0.1524)
				(type default)
			)
			(layer "B.SilkS")
		)
		(fp_line
			(start -4.715002 3.035554)
			(end -4.7117 2.984754)
			(stroke
				(width 0.1524)
				(type default)
			)
			(layer "B.SilkS")
		)
		(fp_line
			(start 4.664456 3.109976)
			(end 4.664456 -3.109976)
			(stroke
				(width 0.1524)
				(type default)
			)
			(layer "B.SilkS")
		)
		(fp_line
			(start -4.156202 3.109976)
			(end -4.183126 3.109976)
			(stroke
				(width 0.1524)
				(type default)
			)
			(layer "B.SilkS")
		)
		(fp_line
			(start -4.743704 3.109976)
			(end -4.6101 3.109976)
			(stroke
				(width 0.1524)
				(type default)
			)
			(layer "B.SilkS")
		)
		(fp_line
			(start -4.743704 3.109976)
			(end -5.4102 3.109976)
			(stroke
				(width 0.1524)
				(type default)
			)
			(layer "B.SilkS")
		)
		(fp_line
			(start -4.769104 3.109976)
			(end 4.664456 3.109976)
			(stroke
				(width 0.1524)
				(type default)
			)
			(layer "B.SilkS")
		)
		(fp_line
			(start -4.794504 3.109976)
			(end -3.554984 3.109976)
			(stroke
				(width 0.1524)
				(type default)
			)
			(layer "B.SilkS")
		)
		(fp_line
			(start -5.4102 3.109976)
			(end -5.4102 1.9558)
			(stroke
				(width 0.1524)
				(type default)
			)
			(layer "B.SilkS")
		)
		(fp_line
			(start 4.065016 -3.109976)
			(end -4.065016 -3.109976)
			(stroke
				(width 0.1)
				(type default)
			)
			(layer "B.Fab")
		)
		(fp_line
			(start -4.065016 -3.109976)
			(end -4.065016 3.109976)
			(stroke
				(width 0.1)
				(type default)
			)
			(layer "B.Fab")
		)
		(fp_line
			(start 4.065016 3.109976)
			(end 4.065016 -3.109976)
			(stroke
				(width 0.1)
				(type default)
			)
			(layer "B.Fab")
		)
		(fp_line
			(start -4.065016 3.109976)
			(end 4.065016 3.109976)
			(stroke
				(width 0.1)
				(type default)
			)
			(layer "B.Fab")
		)
		(fp_text user "+"
			(at 6.1976 0.37465 270)
			(unlocked yes)
			(layer "B.SilkS")
			(effects
				(font
					(size 1.905 1.4224)
					(thickness 0.1524)
				)
				(justify left mirror)
			)
		)
		(fp_text user "-"
			(at -7.405624 0.65405 270)
			(unlocked yes)
			(layer "B.SilkS")
			(effects
				(font
					(size 1.905 1.4224)
					(thickness 0.1524)
				)
				(justify left mirror)
			)
		)
		(fp_text user "+"
			(at 4.5974 0.24765 270)
			(unlocked yes)
			(layer "B.Fab")
			(effects
				(font
					(size 1.905 1.4224)
					(thickness 0.1524)
				)
				(justify left mirror)
			)
		)
		(fp_text user "-"
			(at -6.643624 0.40005 270)
			(unlocked yes)
			(layer "B.Fab")
			(effects
				(font
					(size 1.905 1.4224)
					(thickness 0.1524)
				)
				(justify left mirror)
			)
		)
		(pad "A" smd rect
			(at 3.299968 0 90)
			(size 2.413 3.302)
			(layers "B.Cu" "B.Mask" "B.Paste")
			(net "GND")
		)
		(pad "C" smd rect
			(at -3.299968 0 90)
			(size 2.413 3.302)
			(layers "B.Cu" "B.Mask" "B.Paste")
			(net "P52V_1_FUSE_1")
		)
	)
	(footprint ""
		(layer "B.Cu")
		(at 271.4244 -76.454)
		(property "Reference" "PC589"
			(at 0 0 0)
			(layer "B.SilkS")
			(hide yes)
			(effects
				(font
					(size 1.27 1.27)
				)
				(justify mirror)
			)
		)
		(property "Value" ""
			(at 0 0 0)
			(layer "B.Fab")
			(effects
				(font
					(size 1.27 1.27)
				)
				(justify mirror)
			)
		)
		(duplicate_pad_numbers_are_jumpers no)
		(fp_line
			(start -0.7874 -0.4064)
			(end -0.7874 0.4064)
			(stroke
				(width 0.1524)
				(type default)
			)
			(layer "B.SilkS")
		)
		(fp_line
			(start -0.7874 0.4064)
			(end 0.7874 0.4064)
			(stroke
				(width 0.1524)
				(type default)
			)
			(layer "B.SilkS")
		)
		(fp_line
			(start 0.7874 -0.4064)
			(end -0.7874 -0.4064)
			(stroke
				(width 0.1524)
				(type default)
			)
			(layer "B.SilkS")
		)
		(fp_line
			(start 0.7874 0.4064)
			(end 0.7874 -0.4064)
			(stroke
				(width 0.1524)
				(type default)
			)
			(layer "B.SilkS")
		)
		(fp_line
			(start -0.67945 -0.3048)
			(end -0.67945 0.3048)
			(stroke
				(width 0.1)
				(type default)
			)
			(layer "B.Fab")
		)
		(fp_line
			(start -0.67945 0.3048)
			(end -0.120396 0.3048)
			(stroke
				(width 0.1)
				(type default)
			)
			(layer "B.Fab")
		)
		(fp_line
			(start -0.12065 -0.3048)
			(end -0.67945 -0.3048)
			(stroke
				(width 0.1)
				(type default)
			)
			(layer "B.Fab")
		)
		(fp_line
			(start -0.12065 -0.2794)
			(end -0.12065 -0.3048)
			(stroke
				(width 0.1)
				(type default)
			)
			(layer "B.Fab")
		)
		(fp_line
			(start -0.120396 0.2794)
			(end 0.12065 0.2794)
			(stroke
				(width 0.1)
				(type default)
			)
			(layer "B.Fab")
		)
		(fp_line
			(start -0.120396 0.3048)
			(end -0.120396 0.2794)
			(stroke
				(width 0.1)
				(type default)
			)
			(layer "B.Fab")
		)
		(fp_line
			(start 0.12065 -0.305054)
			(end 0.12065 -0.2794)
			(stroke
				(width 0.1)
				(type default)
			)
			(layer "B.Fab")
		)
		(fp_line
			(start 0.12065 -0.2794)
			(end -0.12065 -0.2794)
			(stroke
				(width 0.1)
				(type default)
			)
			(layer "B.Fab")
		)
		(fp_line
			(start 0.12065 0.2794)
			(end 0.12065 0.3048)
			(stroke
				(width 0.1)
				(type default)
			)
			(layer "B.Fab")
		)
		(fp_line
			(start 0.12065 0.3048)
			(end 0.67945 0.3048)
			(stroke
				(width 0.1)
				(type default)
			)
			(layer "B.Fab")
		)
		(fp_line
			(start 0.67945 -0.305054)
			(end 0.12065 -0.305054)
			(stroke
				(width 0.1)
				(type default)
			)
			(layer "B.Fab")
		)
		(fp_line
			(start 0.67945 0.3048)
			(end 0.67945 -0.305054)
			(stroke
				(width 0.1)
				(type default)
			)
			(layer "B.Fab")
		)
		(pad "1" smd circle
			(at 0.40005 0 180)
			(size 0 0)
			(layers "B.Cu" "B.Mask" "B.Paste")
			(net "P52V_HS1_TEMPP")
		)
		(pad "2" smd circle
			(at -0.40005 0 180)
			(size 0 0)
			(layers "B.Cu" "B.Mask" "B.Paste")
			(net "P52V_HS1_TEMPN")
		)
	)
	(footprint ""
		(layer "B.Cu")
		(at 341.5792 -49.9364 -90)
		(property "Reference" "PR220"
			(at 0 0 90)
			(layer "B.SilkS")
			(hide yes)
			(effects
				(font
					(size 1.27 1.27)
				)
				(justify mirror)
			)
		)
		(property "Value" ""
			(at 0 0 90)
			(layer "B.Fab")
			(effects
				(font
					(size 1.27 1.27)
				)
				(justify mirror)
			)
		)
		(duplicate_pad_numbers_are_jumpers no)
		(fp_line
			(start -1.2954 0.5842)
			(end 1.2954 0.5842)
			(stroke
				(width 0.1524)
				(type default)
			)
			(layer "B.SilkS")
		)
		(fp_line
			(start 1.2954 0.5842)
			(end 1.2954 -0.5842)
			(stroke
				(width 0.1524)
				(type default)
			)
			(layer "B.SilkS")
		)
		(fp_line
			(start -1.2954 -0.5842)
			(end -1.2954 0.5842)
			(stroke
				(width 0.1524)
				(type default)
			)
			(layer "B.SilkS")
		)
		(fp_line
			(start 1.2954 -0.5842)
			(end -1.2954 -0.5842)
			(stroke
				(width 0.1524)
				(type default)
			)
			(layer "B.SilkS")
		)
		(fp_line
			(start -0.8636 0.4572)
			(end 0.8636 0.4572)
			(stroke
				(width 0.1)
				(type default)
			)
			(layer "B.Fab")
		)
		(fp_line
			(start 0.8636 0.4572)
			(end 0.8636 0.4318)
			(stroke
				(width 0.1)
				(type default)
			)
			(layer "B.Fab")
		)
		(fp_line
			(start 0.8636 0.4318)
			(end 0.8636 0.4064)
			(stroke
				(width 0.1)
				(type default)
			)
			(layer "B.Fab")
		)
		(fp_line
			(start -1.1938 0.4064)
			(end -0.8636 0.4064)
			(stroke
				(width 0.1)
				(type default)
			)
			(layer "B.Fab")
		)
		(fp_line
			(start -0.8636 0.4064)
			(end -0.8636 0.4572)
			(stroke
				(width 0.1)
				(type default)
			)
			(layer "B.Fab")
		)
		(fp_line
			(start 0.8636 0.4064)
			(end 1.1938 0.4064)
			(stroke
				(width 0.1)
				(type default)
			)
			(layer "B.Fab")
		)
		(fp_line
			(start 1.1938 0.4064)
			(end 1.1938 -0.406654)
			(stroke
				(width 0.1)
				(type default)
			)
			(layer "B.Fab")
		)
		(fp_line
			(start -1.1938 -0.406654)
			(end -1.1938 0.4064)
			(stroke
				(width 0.1)
				(type default)
			)
			(layer "B.Fab")
		)
		(fp_line
			(start -0.8636 -0.406654)
			(end -1.1938 -0.406654)
			(stroke
				(width 0.1)
				(type default)
			)
			(layer "B.Fab")
		)
		(fp_line
			(start 0.8636 -0.406654)
			(end 0.8636 -0.4572)
			(stroke
				(width 0.1)
				(type default)
			)
			(layer "B.Fab")
		)
		(fp_line
			(start 1.1938 -0.406654)
			(end 0.8636 -0.406654)
			(stroke
				(width 0.1)
				(type default)
			)
			(layer "B.Fab")
		)
		(fp_line
			(start -0.8636 -0.4572)
			(end -0.8636 -0.406654)
			(stroke
				(width 0.1)
				(type default)
			)
			(layer "B.Fab")
		)
		(fp_line
			(start 0.8636 -0.4572)
			(end -0.8636 -0.4572)
			(stroke
				(width 0.1)
				(type default)
			)
			(layer "B.Fab")
		)
		(pad "1" smd rect
			(at 0.7366 0 180)
			(size 0.7112 0.8128)
			(layers "B.Cu" "B.Mask" "B.Paste")
			(net "P52V_HS1_4287_GATE_R")
		)
		(pad "2" smd rect
			(at -0.7366 0 180)
			(size 0.7112 0.8128)
			(layers "B.Cu" "B.Mask" "B.Paste")
			(net "P52V_HS1_GATE_RC")
		)
	)
	(footprint ""
		(layer "B.Cu")
		(at 341.63 -36.068 90)
		(property "Reference" "PC581"
			(at 0 0 90)
			(layer "B.SilkS")
			(hide yes)
			(effects
				(font
					(size 1.27 1.27)
				)
				(justify mirror)
			)
		)
		(property "Value" ""
			(at 0 0 90)
			(layer "B.Fab")
			(effects
				(font
					(size 1.27 1.27)
				)
				(justify mirror)
			)
		)
		(duplicate_pad_numbers_are_jumpers no)
		(fp_line
			(start 1.2954 -0.5842)
			(end -1.2954 -0.5842)
			(stroke
				(width 0.1524)
				(type default)
			)
			(layer "B.SilkS")
		)
		(fp_line
			(start -1.2954 -0.5842)
			(end -1.2954 0.5842)
			(stroke
				(width 0.1524)
				(type default)
			)
			(layer "B.SilkS")
		)
		(fp_line
			(start 1.2954 0.5842)
			(end 1.2954 -0.5842)
			(stroke
				(width 0.1524)
				(type default)
			)
			(layer "B.SilkS")
		)
		(fp_line
			(start -1.2954 0.5842)
			(end 1.2954 0.5842)
			(stroke
				(width 0.1524)
				(type default)
			)
			(layer "B.SilkS")
		)
		(fp_line
			(start 0.8636 -0.4572)
			(end -0.8636 -0.4572)
			(stroke
				(width 0.1)
				(type default)
			)
			(layer "B.Fab")
		)
		(fp_line
			(start -0.8636 -0.4572)
			(end -0.8636 -0.4064)
			(stroke
				(width 0.1)
				(type default)
			)
			(layer "B.Fab")
		)
		(fp_line
			(start 1.1938 -0.4064)
			(end 0.8636 -0.4064)
			(stroke
				(width 0.1)
				(type default)
			)
			(layer "B.Fab")
		)
		(fp_line
			(start 0.8636 -0.4064)
			(end 0.8636 -0.4572)
			(stroke
				(width 0.1)
				(type default)
			)
			(layer "B.Fab")
		)
		(fp_line
			(start -0.8636 -0.4064)
			(end -1.1938 -0.4064)
			(stroke
				(width 0.1)
				(type default)
			)
			(layer "B.Fab")
		)
		(fp_line
			(start -1.1938 -0.4064)
			(end -1.1938 0.4064)
			(stroke
				(width 0.1)
				(type default)
			)
			(layer "B.Fab")
		)
		(fp_line
			(start 1.1938 0.4064)
			(end 1.1938 -0.4064)
			(stroke
				(width 0.1)
				(type default)
			)
			(layer "B.Fab")
		)
		(fp_line
			(start 0.8636 0.4064)
			(end 1.1938 0.4064)
			(stroke
				(width 0.1)
				(type default)
			)
			(layer "B.Fab")
		)
		(fp_line
			(start -0.8636 0.4064)
			(end -0.8636 0.4572)
			(stroke
				(width 0.1)
				(type default)
			)
			(layer "B.Fab")
		)
		(fp_line
			(start -1.1938 0.4064)
			(end -0.8636 0.4064)
			(stroke
				(width 0.1)
				(type default)
			)
			(layer "B.Fab")
		)
		(fp_line
			(start 0.8636 0.4572)
			(end 0.8636 0.4064)
			(stroke
				(width 0.1)
				(type default)
			)
			(layer "B.Fab")
		)
		(fp_line
			(start -0.8636 0.4572)
			(end 0.8636 0.4572)
			(stroke
				(width 0.1)
				(type default)
			)
			(layer "B.Fab")
		)
		(pad "1" smd rect
			(at 0.7366 0)
			(size 0.7112 0.8128)
			(layers "B.Cu" "B.Mask" "B.Paste")
			(net "P52V_HS1_4287_GATE2_R")
		)
		(pad "2" smd rect
			(at -0.7366 0)
			(size 0.7112 0.8128)
			(layers "B.Cu" "B.Mask" "B.Paste")
			(net "P52V_HS1")
		)
	)
	(footprint ""
		(layer "B.Cu")
		(at 285.9024 -70.739 180)
		(property "Reference" "PR209"
			(at 0 0 0)
			(layer "B.SilkS")
			(hide yes)
			(effects
				(font
					(size 1.27 1.27)
				)
				(justify mirror)
			)
		)
		(property "Value" ""
			(at 0 0 0)
			(layer "B.Fab")
			(effects
				(font
					(size 1.27 1.27)
				)
				(justify mirror)
			)
		)
		(duplicate_pad_numbers_are_jumpers no)
		(fp_line
			(start 0.7874 0.4064)
			(end 0.7874 -0.4064)
			(stroke
				(width 0.1524)
				(type default)
			)
			(layer "B.SilkS")
		)
		(fp_line
			(start 0.7874 -0.4064)
			(end -0.7874 -0.4064)
			(stroke
				(width 0.1524)
				(type default)
			)
			(layer "B.SilkS")
		)
		(fp_line
			(start -0.7874 0.4064)
			(end 0.7874 0.4064)
			(stroke
				(width 0.1524)
				(type default)
			)
			(layer "B.SilkS")
		)
		(fp_line
			(start -0.7874 -0.4064)
			(end -0.7874 0.4064)
			(stroke
				(width 0.1524)
				(type default)
			)
			(layer "B.SilkS")
		)
		(fp_line
			(start 0.67945 0.3048)
			(end 0.67945 -0.305054)
			(stroke
				(width 0.1)
				(type default)
			)
			(layer "B.Fab")
		)
		(fp_line
			(start 0.67945 -0.305054)
			(end 0.12065 -0.305054)
			(stroke
				(width 0.1)
				(type default)
			)
			(layer "B.Fab")
		)
		(fp_line
			(start 0.12065 0.3048)
			(end 0.67945 0.3048)
			(stroke
				(width 0.1)
				(type default)
			)
			(layer "B.Fab")
		)
		(fp_line
			(start 0.12065 0.2794)
			(end 0.12065 0.3048)
			(stroke
				(width 0.1)
				(type default)
			)
			(layer "B.Fab")
		)
		(fp_line
			(start 0.12065 -0.2794)
			(end -0.12065 -0.2794)
			(stroke
				(width 0.1)
				(type default)
			)
			(layer "B.Fab")
		)
		(fp_line
			(start 0.12065 -0.305054)
			(end 0.12065 -0.2794)
			(stroke
				(width 0.1)
				(type default)
			)
			(layer "B.Fab")
		)
		(fp_line
			(start -0.120396 0.3048)
			(end -0.120396 0.2794)
			(stroke
				(width 0.1)
				(type default)
			)
			(layer "B.Fab")
		)
		(fp_line
			(start -0.120396 0.2794)
			(end 0.12065 0.2794)
			(stroke
				(width 0.1)
				(type default)
			)
			(layer "B.Fab")
		)
		(fp_line
			(start -0.12065 -0.2794)
			(end -0.12065 -0.3048)
			(stroke
				(width 0.1)
				(type default)
			)
			(layer "B.Fab")
		)
		(fp_line
			(start -0.12065 -0.3048)
			(end -0.67945 -0.3048)
			(stroke
				(width 0.1)
				(type default)
			)
			(layer "B.Fab")
		)
		(fp_line
			(start -0.67945 0.3048)
			(end -0.120396 0.3048)
			(stroke
				(width 0.1)
				(type default)
			)
			(layer "B.Fab")
		)
		(fp_line
			(start -0.67945 -0.3048)
			(end -0.67945 0.3048)
			(stroke
				(width 0.1)
				(type default)
			)
			(layer "B.Fab")
		)
		(pad "1" smd circle
			(at 0.40005 0)
			(size 0 0)
			(layers "B.Cu" "B.Mask" "B.Paste")
			(net "GND_FIELD_SIGNAL")
		)
		(pad "2" smd circle
			(at -0.40005 0)
			(size 0 0)
			(layers "B.Cu" "B.Mask" "B.Paste")
			(net "P52V_HS1_CS")
		)
	)
	(footprint ""
		(layer "B.Cu")
		(at 267.9954 -77.978 -90)
		(property "Reference" "PC587"
			(at 0 0 90)
			(layer "B.SilkS")
			(hide yes)
			(effects
				(font
					(size 1.27 1.27)
				)
				(justify mirror)
			)
		)
		(property "Value" ""
			(at 0 0 90)
			(layer "B.Fab")
			(effects
				(font
					(size 1.27 1.27)
				)
				(justify mirror)
			)
		)
		(duplicate_pad_numbers_are_jumpers no)
		(fp_line
			(start -2.2098 0.9398)
			(end 2.2098 0.9398)
			(stroke
				(width 0.1524)
				(type default)
			)
			(layer "B.SilkS")
		)
		(fp_line
			(start 2.2098 0.9398)
			(end 2.2098 -0.9398)
			(stroke
				(width 0.1524)
				(type default)
			)
			(layer "B.SilkS")
		)
		(fp_line
			(start -2.2098 -0.9398)
			(end -2.2098 0.9398)
			(stroke
				(width 0.1524)
				(type default)
			)
			(layer "B.SilkS")
		)
		(fp_line
			(start 2.2098 -0.9398)
			(end -2.2098 -0.9398)
			(stroke
				(width 0.1524)
				(type default)
			)
			(layer "B.SilkS")
		)
		(fp_line
			(start -1.6764 0.9398)
			(end -1.6764 -0.9398)
			(stroke
				(width 0.1)
				(type default)
			)
			(layer "B.Fab")
		)
		(fp_line
			(start 1.6764 0.9398)
			(end -1.6764 0.9398)
			(stroke
				(width 0.1)
				(type default)
			)
			(layer "B.Fab")
		)
		(fp_line
			(start -1.6764 -0.9398)
			(end 1.6764 -0.9398)
			(stroke
				(width 0.1)
				(type default)
			)
			(layer "B.Fab")
		)
		(fp_line
			(start 1.6764 -0.9398)
			(end 1.6764 0.9398)
			(stroke
				(width 0.1)
				(type default)
			)
			(layer "B.Fab")
		)
		(pad "1" smd rect
			(at 1.4732 0 270)
			(size 1.1684 1.5748)
			(layers "B.Cu" "B.Mask" "B.Paste")
			(net "P52V_HS1_VCC")
		)
		(pad "2" smd rect
			(at -1.4732 0 270)
			(size 1.1684 1.5748)
			(layers "B.Cu" "B.Mask" "B.Paste")
			(net "GND_FIELD_SIGNAL")
		)
	)
	(footprint ""
		(layer "B.Cu")
		(at 169.1894 -76.327)
		(property "Reference" "PR7034"
			(at 0 0 0)
			(layer "B.SilkS")
			(hide yes)
			(effects
				(font
					(size 1.27 1.27)
				)
				(justify mirror)
			)
		)
		(property "Value" ""
			(at 0 0 0)
			(layer "B.Fab")
			(effects
				(font
					(size 1.27 1.27)
				)
				(justify mirror)
			)
		)
		(duplicate_pad_numbers_are_jumpers no)
		(fp_line
			(start -0.7874 -0.4064)
			(end -0.7874 0.4064)
			(stroke
				(width 0.1524)
				(type default)
			)
			(layer "B.SilkS")
		)
		(fp_line
			(start -0.7874 0.4064)
			(end 0.7874 0.4064)
			(stroke
				(width 0.1524)
				(type default)
			)
			(layer "B.SilkS")
		)
		(fp_line
			(start 0.7874 -0.4064)
			(end -0.7874 -0.4064)
			(stroke
				(width 0.1524)
				(type default)
			)
			(layer "B.SilkS")
		)
		(fp_line
			(start 0.7874 0.4064)
			(end 0.7874 -0.4064)
			(stroke
				(width 0.1524)
				(type default)
			)
			(layer "B.SilkS")
		)
		(fp_line
			(start -0.67945 -0.3048)
			(end -0.67945 0.3048)
			(stroke
				(width 0.1)
				(type default)
			)
			(layer "B.Fab")
		)
		(fp_line
			(start -0.67945 0.3048)
			(end -0.120396 0.3048)
			(stroke
				(width 0.1)
				(type default)
			)
			(layer "B.Fab")
		)
		(fp_line
			(start -0.12065 -0.3048)
			(end -0.67945 -0.3048)
			(stroke
				(width 0.1)
				(type default)
			)
			(layer "B.Fab")
		)
		(fp_line
			(start -0.12065 -0.2794)
			(end -0.12065 -0.3048)
			(stroke
				(width 0.1)
				(type default)
			)
			(layer "B.Fab")
		)
		(fp_line
			(start -0.120396 0.2794)
			(end 0.12065 0.2794)
			(stroke
				(width 0.1)
				(type default)
			)
			(layer "B.Fab")
		)
		(fp_line
			(start -0.120396 0.3048)
			(end -0.120396 0.2794)
			(stroke
				(width 0.1)
				(type default)
			)
			(layer "B.Fab")
		)
		(fp_line
			(start 0.12065 -0.305054)
			(end 0.12065 -0.2794)
			(stroke
				(width 0.1)
				(type default)
			)
			(layer "B.Fab")
		)
		(fp_line
			(start 0.12065 -0.2794)
			(end -0.12065 -0.2794)
			(stroke
				(width 0.1)
				(type default)
			)
			(layer "B.Fab")
		)
		(fp_line
			(start 0.12065 0.2794)
			(end 0.12065 0.3048)
			(stroke
				(width 0.1)
				(type default)
			)
			(layer "B.Fab")
		)
		(fp_line
			(start 0.12065 0.3048)
			(end 0.67945 0.3048)
			(stroke
				(width 0.1)
				(type default)
			)
			(layer "B.Fab")
		)
		(fp_line
			(start 0.67945 -0.305054)
			(end 0.12065 -0.305054)
			(stroke
				(width 0.1)
				(type default)
			)
			(layer "B.Fab")
		)
		(fp_line
			(start 0.67945 0.3048)
			(end 0.67945 -0.305054)
			(stroke
				(width 0.1)
				(type default)
			)
			(layer "B.Fab")
		)
		(pad "1" smd circle
			(at 0.40005 0 180)
			(size 0 0)
			(layers "B.Cu" "B.Mask" "B.Paste")
			(net "P52V_HS2_MCB")
		)
		(pad "2" smd circle
			(at -0.40005 0 180)
			(size 0 0)
			(layers "B.Cu" "B.Mask" "B.Paste")
			(net "GND1_FIELD_SIGNAL")
		)
	)
	(footprint ""
		(layer "B.Cu")
		(at 104.013 -43.053)
		(property "Reference" "PC598"
			(at 0 0 0)
			(layer "B.SilkS")
			(hide yes)
			(effects
				(font
					(size 1.27 1.27)
				)
				(justify mirror)
			)
		)
		(property "Value" ""
			(at 0 0 0)
			(layer "B.Fab")
			(effects
				(font
					(size 1.27 1.27)
				)
				(justify mirror)
			)
		)
		(duplicate_pad_numbers_are_jumpers no)
		(fp_line
			(start -1.2954 -0.5842)
			(end -1.2954 0.5842)
			(stroke
				(width 0.1524)
				(type default)
			)
			(layer "B.SilkS")
		)
		(fp_line
			(start -1.2954 0.5842)
			(end 1.2954 0.5842)
			(stroke
				(width 0.1524)
				(type default)
			)
			(layer "B.SilkS")
		)
		(fp_line
			(start 1.2954 -0.5842)
			(end -1.2954 -0.5842)
			(stroke
				(width 0.1524)
				(type default)
			)
			(layer "B.SilkS")
		)
		(fp_line
			(start 1.2954 0.5842)
			(end 1.2954 -0.5842)
			(stroke
				(width 0.1524)
				(type default)
			)
			(layer "B.SilkS")
		)
		(fp_line
			(start -1.1938 -0.4064)
			(end -1.1938 0.4064)
			(stroke
				(width 0.1)
				(type default)
			)
			(layer "B.Fab")
		)
		(fp_line
			(start -1.1938 0.4064)
			(end -0.8636 0.4064)
			(stroke
				(width 0.1)
				(type default)
			)
			(layer "B.Fab")
		)
		(fp_line
			(start -0.8636 -0.4572)
			(end -0.8636 -0.4064)
			(stroke
				(width 0.1)
				(type default)
			)
			(layer "B.Fab")
		)
		(fp_line
			(start -0.8636 -0.4064)
			(end -1.1938 -0.4064)
			(stroke
				(width 0.1)
				(type default)
			)
			(layer "B.Fab")
		)
		(fp_line
			(start -0.8636 0.4064)
			(end -0.8636 0.4572)
			(stroke
				(width 0.1)
				(type default)
			)
			(layer "B.Fab")
		)
		(fp_line
			(start -0.8636 0.4572)
			(end 0.8636 0.4572)
			(stroke
				(width 0.1)
				(type default)
			)
			(layer "B.Fab")
		)
		(fp_line
			(start 0.8636 -0.4572)
			(end -0.8636 -0.4572)
			(stroke
				(width 0.1)
				(type default)
			)
			(layer "B.Fab")
		)
		(fp_line
			(start 0.8636 -0.4064)
			(end 0.8636 -0.4572)
			(stroke
				(width 0.1)
				(type default)
			)
			(layer "B.Fab")
		)
		(fp_line
			(start 0.8636 0.4064)
			(end 1.1938 0.4064)
			(stroke
				(width 0.1)
				(type default)
			)
			(layer "B.Fab")
		)
		(fp_line
			(start 0.8636 0.4572)
			(end 0.8636 0.4064)
			(stroke
				(width 0.1)
				(type default)
			)
			(layer "B.Fab")
		)
		(fp_line
			(start 1.1938 -0.4064)
			(end 0.8636 -0.4064)
			(stroke
				(width 0.1)
				(type default)
			)
			(layer "B.Fab")
		)
		(fp_line
			(start 1.1938 0.4064)
			(end 1.1938 -0.4064)
			(stroke
				(width 0.1)
				(type default)
			)
			(layer "B.Fab")
		)
		(pad "1" smd rect
			(at 0.7366 0 270)
			(size 0.7112 0.8128)
			(layers "B.Cu" "B.Mask" "B.Paste")
			(net "P52V_HS2_4287_GATE2_RC")
		)
		(pad "2" smd rect
			(at -0.7366 0 270)
			(size 0.7112 0.8128)
			(layers "B.Cu" "B.Mask" "B.Paste")
			(net "P52V_HS2")
		)
	)
	(footprint ""
		(layer "B.Cu")
		(at 279.2984 -72.39 180)
		(property "Reference" "PR20"
			(at 0 0 0)
			(layer "B.SilkS")
			(hide yes)
			(effects
				(font
					(size 1.27 1.27)
				)
				(justify mirror)
			)
		)
		(property "Value" ""
			(at 0 0 0)
			(layer "B.Fab")
			(effects
				(font
					(size 1.27 1.27)
				)
				(justify mirror)
			)
		)
		(duplicate_pad_numbers_are_jumpers no)
		(fp_line
			(start 0.7874 0.4064)
			(end 0.7874 -0.4064)
			(stroke
				(width 0.1524)
				(type default)
			)
			(layer "B.SilkS")
		)
		(fp_line
			(start 0.7874 -0.4064)
			(end -0.7874 -0.4064)
			(stroke
				(width 0.1524)
				(type default)
			)
			(layer "B.SilkS")
		)
		(fp_line
			(start -0.7874 0.4064)
			(end 0.7874 0.4064)
			(stroke
				(width 0.1524)
				(type default)
			)
			(layer "B.SilkS")
		)
		(fp_line
			(start -0.7874 -0.4064)
			(end -0.7874 0.4064)
			(stroke
				(width 0.1524)
				(type default)
			)
			(layer "B.SilkS")
		)
		(fp_line
			(start 0.67945 0.3048)
			(end 0.67945 -0.305054)
			(stroke
				(width 0.1)
				(type default)
			)
			(layer "B.Fab")
		)
		(fp_line
			(start 0.67945 -0.305054)
			(end 0.12065 -0.305054)
			(stroke
				(width 0.1)
				(type default)
			)
			(layer "B.Fab")
		)
		(fp_line
			(start 0.12065 0.3048)
			(end 0.67945 0.3048)
			(stroke
				(width 0.1)
				(type default)
			)
			(layer "B.Fab")
		)
		(fp_line
			(start 0.12065 0.2794)
			(end 0.12065 0.3048)
			(stroke
				(width 0.1)
				(type default)
			)
			(layer "B.Fab")
		)
		(fp_line
			(start 0.12065 -0.2794)
			(end -0.12065 -0.2794)
			(stroke
				(width 0.1)
				(type default)
			)
			(layer "B.Fab")
		)
		(fp_line
			(start 0.12065 -0.305054)
			(end 0.12065 -0.2794)
			(stroke
				(width 0.1)
				(type default)
			)
			(layer "B.Fab")
		)
		(fp_line
			(start -0.120396 0.3048)
			(end -0.120396 0.2794)
			(stroke
				(width 0.1)
				(type default)
			)
			(layer "B.Fab")
		)
		(fp_line
			(start -0.120396 0.2794)
			(end 0.12065 0.2794)
			(stroke
				(width 0.1)
				(type default)
			)
			(layer "B.Fab")
		)
		(fp_line
			(start -0.12065 -0.2794)
			(end -0.12065 -0.3048)
			(stroke
				(width 0.1)
				(type default)
			)
			(layer "B.Fab")
		)
		(fp_line
			(start -0.12065 -0.3048)
			(end -0.67945 -0.3048)
			(stroke
				(width 0.1)
				(type default)
			)
			(layer "B.Fab")
		)
		(fp_line
			(start -0.67945 0.3048)
			(end -0.120396 0.3048)
			(stroke
				(width 0.1)
				(type default)
			)
			(layer "B.Fab")
		)
		(fp_line
			(start -0.67945 -0.3048)
			(end -0.67945 0.3048)
			(stroke
				(width 0.1)
				(type default)
			)
			(layer "B.Fab")
		)
		(pad "1" smd circle
			(at 0.40005 0)
			(size 0 0)
			(layers "B.Cu" "B.Mask" "B.Paste")
			(net "P52V_HS1_ISTART")
		)
		(pad "2" smd circle
			(at -0.40005 0)
			(size 0 0)
			(layers "B.Cu" "B.Mask" "B.Paste")
			(net "GND_FIELD_SIGNAL")
		)
	)
	(footprint ""
		(layer "B.Cu")
		(at 290.9824 -60.833 90)
		(property "Reference" "R159"
			(at 0 0 90)
			(layer "B.SilkS")
			(hide yes)
			(effects
				(font
					(size 1.27 1.27)
				)
				(justify mirror)
			)
		)
		(property "Value" ""
			(at 0 0 90)
			(layer "B.Fab")
			(effects
				(font
					(size 1.27 1.27)
				)
				(justify mirror)
			)
		)
		(duplicate_pad_numbers_are_jumpers no)
		(fp_line
			(start 0.7874 -0.4064)
			(end -0.7874 -0.4064)
			(stroke
				(width 0.1524)
				(type default)
			)
			(layer "B.SilkS")
		)
		(fp_line
			(start -0.7874 -0.4064)
			(end -0.7874 0.4064)
			(stroke
				(width 0.1524)
				(type default)
			)
			(layer "B.SilkS")
		)
		(fp_line
			(start 0.7874 0.4064)
			(end 0.7874 -0.4064)
			(stroke
				(width 0.1524)
				(type default)
			)
			(layer "B.SilkS")
		)
		(fp_line
			(start -0.7874 0.4064)
			(end 0.7874 0.4064)
			(stroke
				(width 0.1524)
				(type default)
			)
			(layer "B.SilkS")
		)
		(fp_line
			(start 0.67945 -0.305054)
			(end 0.12065 -0.305054)
			(stroke
				(width 0.1)
				(type default)
			)
			(layer "B.Fab")
		)
		(fp_line
			(start 0.12065 -0.305054)
			(end 0.12065 -0.2794)
			(stroke
				(width 0.1)
				(type default)
			)
			(layer "B.Fab")
		)
		(fp_line
			(start -0.12065 -0.3048)
			(end -0.67945 -0.3048)
			(stroke
				(width 0.1)
				(type default)
			)
			(layer "B.Fab")
		)
		(fp_line
			(start -0.67945 -0.3048)
			(end -0.67945 0.3048)
			(stroke
				(width 0.1)
				(type default)
			)
			(layer "B.Fab")
		)
		(fp_line
			(start 0.12065 -0.2794)
			(end -0.12065 -0.2794)
			(stroke
				(width 0.1)
				(type default)
			)
			(layer "B.Fab")
		)
		(fp_line
			(start -0.12065 -0.2794)
			(end -0.12065 -0.3048)
			(stroke
				(width 0.1)
				(type default)
			)
			(layer "B.Fab")
		)
		(fp_line
			(start 0.12065 0.2794)
			(end 0.12065 0.3048)
			(stroke
				(width 0.1)
				(type default)
			)
			(layer "B.Fab")
		)
		(fp_line
			(start -0.120396 0.2794)
			(end 0.12065 0.2794)
			(stroke
				(width 0.1)
				(type default)
			)
			(layer "B.Fab")
		)
		(fp_line
			(start 0.67945 0.3048)
			(end 0.67945 -0.305054)
			(stroke
				(width 0.1)
				(type default)
			)
			(layer "B.Fab")
		)
		(fp_line
			(start 0.12065 0.3048)
			(end 0.67945 0.3048)
			(stroke
				(width 0.1)
				(type default)
			)
			(layer "B.Fab")
		)
		(fp_line
			(start -0.120396 0.3048)
			(end -0.120396 0.2794)
			(stroke
				(width 0.1)
				(type default)
			)
			(layer "B.Fab")
		)
		(fp_line
			(start -0.67945 0.3048)
			(end -0.120396 0.3048)
			(stroke
				(width 0.1)
				(type default)
			)
			(layer "B.Fab")
		)
		(pad "1" smd circle
			(at 0.40005 0 270)
			(size 0 0)
			(layers "B.Cu" "B.Mask" "B.Paste")
			(net "P52V_HS1_ADR1")
		)
		(pad "2" smd circle
			(at -0.40005 0 270)
			(size 0 0)
			(layers "B.Cu" "B.Mask" "B.Paste")
			(net "GND_FIELD_SIGNAL")
		)
	)
	(footprint ""
		(layer "B.Cu")
		(at 155.621736 -77.216 90)
		(property "Reference" "R5873"
			(at 0 0 90)
			(layer "B.SilkS")
			(hide yes)
			(effects
				(font
					(size 1.27 1.27)
				)
				(justify mirror)
			)
		)
		(property "Value" ""
			(at 0 0 90)
			(layer "B.Fab")
			(effects
				(font
					(size 1.27 1.27)
				)
				(justify mirror)
			)
		)
		(duplicate_pad_numbers_are_jumpers no)
		(fp_line
			(start 0.7874 -0.4064)
			(end -0.7874 -0.4064)
			(stroke
				(width 0.1524)
				(type default)
			)
			(layer "B.SilkS")
		)
		(fp_line
			(start -0.7874 -0.4064)
			(end -0.7874 0.4064)
			(stroke
				(width 0.1524)
				(type default)
			)
			(layer "B.SilkS")
		)
		(fp_line
			(start 0.7874 0.4064)
			(end 0.7874 -0.4064)
			(stroke
				(width 0.1524)
				(type default)
			)
			(layer "B.SilkS")
		)
		(fp_line
			(start -0.7874 0.4064)
			(end 0.7874 0.4064)
			(stroke
				(width 0.1524)
				(type default)
			)
			(layer "B.SilkS")
		)
		(fp_line
			(start 0.67945 -0.305054)
			(end 0.12065 -0.305054)
			(stroke
				(width 0.1)
				(type default)
			)
			(layer "B.Fab")
		)
		(fp_line
			(start 0.12065 -0.305054)
			(end 0.12065 -0.2794)
			(stroke
				(width 0.1)
				(type default)
			)
			(layer "B.Fab")
		)
		(fp_line
			(start -0.12065 -0.3048)
			(end -0.67945 -0.3048)
			(stroke
				(width 0.1)
				(type default)
			)
			(layer "B.Fab")
		)
		(fp_line
			(start -0.67945 -0.3048)
			(end -0.67945 0.3048)
			(stroke
				(width 0.1)
				(type default)
			)
			(layer "B.Fab")
		)
		(fp_line
			(start 0.12065 -0.2794)
			(end -0.12065 -0.2794)
			(stroke
				(width 0.1)
				(type default)
			)
			(layer "B.Fab")
		)
		(fp_line
			(start -0.12065 -0.2794)
			(end -0.12065 -0.3048)
			(stroke
				(width 0.1)
				(type default)
			)
			(layer "B.Fab")
		)
		(fp_line
			(start 0.12065 0.2794)
			(end 0.12065 0.3048)
			(stroke
				(width 0.1)
				(type default)
			)
			(layer "B.Fab")
		)
		(fp_line
			(start -0.120396 0.2794)
			(end 0.12065 0.2794)
			(stroke
				(width 0.1)
				(type default)
			)
			(layer "B.Fab")
		)
		(fp_line
			(start 0.67945 0.3048)
			(end 0.67945 -0.305054)
			(stroke
				(width 0.1)
				(type default)
			)
			(layer "B.Fab")
		)
		(fp_line
			(start 0.12065 0.3048)
			(end 0.67945 0.3048)
			(stroke
				(width 0.1)
				(type default)
			)
			(layer "B.Fab")
		)
		(fp_line
			(start -0.120396 0.3048)
			(end -0.120396 0.2794)
			(stroke
				(width 0.1)
				(type default)
			)
			(layer "B.Fab")
		)
		(fp_line
			(start -0.67945 0.3048)
			(end -0.120396 0.3048)
			(stroke
				(width 0.1)
				(type default)
			)
			(layer "B.Fab")
		)
		(pad "1" smd circle
			(at 0.40005 0 270)
			(size 0 0)
			(layers "B.Cu" "B.Mask" "B.Paste")
			(net "P52V_HS2_INTVCC")
		)
		(pad "2" smd circle
			(at -0.40005 0 270)
			(size 0 0)
			(layers "B.Cu" "B.Mask" "B.Paste")
			(net "P52V_HS2_ADR0")
		)
	)
	(footprint ""
		(layer "B.Cu")
		(at 161.717736 -67.183)
		(property "Reference" "R5871"
			(at 0 0 0)
			(layer "B.SilkS")
			(hide yes)
			(effects
				(font
					(size 1.27 1.27)
				)
				(justify mirror)
			)
		)
		(property "Value" ""
			(at 0 0 0)
			(layer "B.Fab")
			(effects
				(font
					(size 1.27 1.27)
				)
				(justify mirror)
			)
		)
		(duplicate_pad_numbers_are_jumpers no)
		(fp_line
			(start -0.7874 -0.4064)
			(end -0.7874 0.4064)
			(stroke
				(width 0.1524)
				(type default)
			)
			(layer "B.SilkS")
		)
		(fp_line
			(start -0.7874 0.4064)
			(end 0.7874 0.4064)
			(stroke
				(width 0.1524)
				(type default)
			)
			(layer "B.SilkS")
		)
		(fp_line
			(start 0.7874 -0.4064)
			(end -0.7874 -0.4064)
			(stroke
				(width 0.1524)
				(type default)
			)
			(layer "B.SilkS")
		)
		(fp_line
			(start 0.7874 0.4064)
			(end 0.7874 -0.4064)
			(stroke
				(width 0.1524)
				(type default)
			)
			(layer "B.SilkS")
		)
		(fp_line
			(start -0.67945 -0.3048)
			(end -0.67945 0.3048)
			(stroke
				(width 0.1)
				(type default)
			)
			(layer "B.Fab")
		)
		(fp_line
			(start -0.67945 0.3048)
			(end -0.120396 0.3048)
			(stroke
				(width 0.1)
				(type default)
			)
			(layer "B.Fab")
		)
		(fp_line
			(start -0.12065 -0.3048)
			(end -0.67945 -0.3048)
			(stroke
				(width 0.1)
				(type default)
			)
			(layer "B.Fab")
		)
		(fp_line
			(start -0.12065 -0.2794)
			(end -0.12065 -0.3048)
			(stroke
				(width 0.1)
				(type default)
			)
			(layer "B.Fab")
		)
		(fp_line
			(start -0.120396 0.2794)
			(end 0.12065 0.2794)
			(stroke
				(width 0.1)
				(type default)
			)
			(layer "B.Fab")
		)
		(fp_line
			(start -0.120396 0.3048)
			(end -0.120396 0.2794)
			(stroke
				(width 0.1)
				(type default)
			)
			(layer "B.Fab")
		)
		(fp_line
			(start 0.12065 -0.305054)
			(end 0.12065 -0.2794)
			(stroke
				(width 0.1)
				(type default)
			)
			(layer "B.Fab")
		)
		(fp_line
			(start 0.12065 -0.2794)
			(end -0.12065 -0.2794)
			(stroke
				(width 0.1)
				(type default)
			)
			(layer "B.Fab")
		)
		(fp_line
			(start 0.12065 0.2794)
			(end 0.12065 0.3048)
			(stroke
				(width 0.1)
				(type default)
			)
			(layer "B.Fab")
		)
		(fp_line
			(start 0.12065 0.3048)
			(end 0.67945 0.3048)
			(stroke
				(width 0.1)
				(type default)
			)
			(layer "B.Fab")
		)
		(fp_line
			(start 0.67945 -0.305054)
			(end 0.12065 -0.305054)
			(stroke
				(width 0.1)
				(type default)
			)
			(layer "B.Fab")
		)
		(fp_line
			(start 0.67945 0.3048)
			(end 0.67945 -0.305054)
			(stroke
				(width 0.1)
				(type default)
			)
			(layer "B.Fab")
		)
		(pad "1" smd circle
			(at 0.40005 0 180)
			(size 0 0)
			(layers "B.Cu" "B.Mask" "B.Paste")
			(net "SMB_P52V_PDB_SDA")
		)
		(pad "2" smd circle
			(at -0.40005 0 180)
			(size 0 0)
			(layers "B.Cu" "B.Mask" "B.Paste")
			(net "SMB_P52V_HS2_SDAI")
		)
	)
	(footprint ""
		(layer "B.Cu")
		(at 413.639 -37.973)
		(property "Reference" "R5937"
			(at 0 0 0)
			(layer "B.SilkS")
			(hide yes)
			(effects
				(font
					(size 1.27 1.27)
				)
				(justify mirror)
			)
		)
		(property "Value" ""
			(at 0 0 0)
			(layer "B.Fab")
			(effects
				(font
					(size 1.27 1.27)
				)
				(justify mirror)
			)
		)
		(duplicate_pad_numbers_are_jumpers no)
		(fp_line
			(start -0.7874 -0.4064)
			(end -0.7874 0.4064)
			(stroke
				(width 0.1524)
				(type default)
			)
			(layer "B.SilkS")
		)
		(fp_line
			(start -0.7874 0.4064)
			(end 0.7874 0.4064)
			(stroke
				(width 0.1524)
				(type default)
			)
			(layer "B.SilkS")
		)
		(fp_line
			(start 0.7874 -0.4064)
			(end -0.7874 -0.4064)
			(stroke
				(width 0.1524)
				(type default)
			)
			(layer "B.SilkS")
		)
		(fp_line
			(start 0.7874 0.4064)
			(end 0.7874 -0.4064)
			(stroke
				(width 0.1524)
				(type default)
			)
			(layer "B.SilkS")
		)
		(fp_line
			(start -0.67945 -0.3048)
			(end -0.67945 0.3048)
			(stroke
				(width 0.1)
				(type default)
			)
			(layer "B.Fab")
		)
		(fp_line
			(start -0.67945 0.3048)
			(end -0.120396 0.3048)
			(stroke
				(width 0.1)
				(type default)
			)
			(layer "B.Fab")
		)
		(fp_line
			(start -0.12065 -0.3048)
			(end -0.67945 -0.3048)
			(stroke
				(width 0.1)
				(type default)
			)
			(layer "B.Fab")
		)
		(fp_line
			(start -0.12065 -0.2794)
			(end -0.12065 -0.3048)
			(stroke
				(width 0.1)
				(type default)
			)
			(layer "B.Fab")
		)
		(fp_line
			(start -0.120396 0.2794)
			(end 0.12065 0.2794)
			(stroke
				(width 0.1)
				(type default)
			)
			(layer "B.Fab")
		)
		(fp_line
			(start -0.120396 0.3048)
			(end -0.120396 0.2794)
			(stroke
				(width 0.1)
				(type default)
			)
			(layer "B.Fab")
		)
		(fp_line
			(start 0.12065 -0.305054)
			(end 0.12065 -0.2794)
			(stroke
				(width 0.1)
				(type default)
			)
			(layer "B.Fab")
		)
		(fp_line
			(start 0.12065 -0.2794)
			(end -0.12065 -0.2794)
			(stroke
				(width 0.1)
				(type default)
			)
			(layer "B.Fab")
		)
		(fp_line
			(start 0.12065 0.2794)
			(end 0.12065 0.3048)
			(stroke
				(width 0.1)
				(type default)
			)
			(layer "B.Fab")
		)
		(fp_line
			(start 0.12065 0.3048)
			(end 0.67945 0.3048)
			(stroke
				(width 0.1)
				(type default)
			)
			(layer "B.Fab")
		)
		(fp_line
			(start 0.67945 -0.305054)
			(end 0.12065 -0.305054)
			(stroke
				(width 0.1)
				(type default)
			)
			(layer "B.Fab")
		)
		(fp_line
			(start 0.67945 0.3048)
			(end 0.67945 -0.305054)
			(stroke
				(width 0.1)
				(type default)
			)
			(layer "B.Fab")
		)
		(pad "1" smd circle
			(at 0.40005 0 180)
			(size 0 0)
			(layers "B.Cu" "B.Mask" "B.Paste")
			(net "PCA9555_2_A2")
		)
		(pad "2" smd circle
			(at -0.40005 0 180)
			(size 0 0)
			(layers "B.Cu" "B.Mask" "B.Paste")
			(net "GND")
		)
	)
	(footprint ""
		(layer "B.Cu")
		(at 269.9004 -76.454 -90)
		(property "Reference" "PC10"
			(at 0 0 90)
			(layer "B.SilkS")
			(hide yes)
			(effects
				(font
					(size 1.27 1.27)
				)
				(justify mirror)
			)
		)
		(property "Value" ""
			(at 0 0 90)
			(layer "B.Fab")
			(effects
				(font
					(size 1.27 1.27)
				)
				(justify mirror)
			)
		)
		(duplicate_pad_numbers_are_jumpers no)
		(fp_line
			(start -0.7874 0.4064)
			(end 0.7874 0.4064)
			(stroke
				(width 0.1524)
				(type default)
			)
			(layer "B.SilkS")
		)
		(fp_line
			(start 0.7874 0.4064)
			(end 0.7874 -0.4064)
			(stroke
				(width 0.1524)
				(type default)
			)
			(layer "B.SilkS")
		)
		(fp_line
			(start -0.7874 -0.4064)
			(end -0.7874 0.4064)
			(stroke
				(width 0.1524)
				(type default)
			)
			(layer "B.SilkS")
		)
		(fp_line
			(start 0.7874 -0.4064)
			(end -0.7874 -0.4064)
			(stroke
				(width 0.1524)
				(type default)
			)
			(layer "B.SilkS")
		)
		(fp_line
			(start -0.67945 0.3048)
			(end -0.120396 0.3048)
			(stroke
				(width 0.1)
				(type default)
			)
			(layer "B.Fab")
		)
		(fp_line
			(start -0.120396 0.3048)
			(end -0.120396 0.2794)
			(stroke
				(width 0.1)
				(type default)
			)
			(layer "B.Fab")
		)
		(fp_line
			(start 0.12065 0.3048)
			(end 0.67945 0.3048)
			(stroke
				(width 0.1)
				(type default)
			)
			(layer "B.Fab")
		)
		(fp_line
			(start 0.67945 0.3048)
			(end 0.67945 -0.305054)
			(stroke
				(width 0.1)
				(type default)
			)
			(layer "B.Fab")
		)
		(fp_line
			(start -0.120396 0.2794)
			(end 0.12065 0.2794)
			(stroke
				(width 0.1)
				(type default)
			)
			(layer "B.Fab")
		)
		(fp_line
			(start 0.12065 0.2794)
			(end 0.12065 0.3048)
			(stroke
				(width 0.1)
				(type default)
			)
			(layer "B.Fab")
		)
		(fp_line
			(start -0.12065 -0.2794)
			(end -0.12065 -0.3048)
			(stroke
				(width 0.1)
				(type default)
			)
			(layer "B.Fab")
		)
		(fp_line
			(start 0.12065 -0.2794)
			(end -0.12065 -0.2794)
			(stroke
				(width 0.1)
				(type default)
			)
			(layer "B.Fab")
		)
		(fp_line
			(start -0.67945 -0.3048)
			(end -0.67945 0.3048)
			(stroke
				(width 0.1)
				(type default)
			)
			(layer "B.Fab")
		)
		(fp_line
			(start -0.12065 -0.3048)
			(end -0.67945 -0.3048)
			(stroke
				(width 0.1)
				(type default)
			)
			(layer "B.Fab")
		)
		(fp_line
			(start 0.12065 -0.305054)
			(end 0.12065 -0.2794)
			(stroke
				(width 0.1)
				(type default)
			)
			(layer "B.Fab")
		)
		(fp_line
			(start 0.67945 -0.305054)
			(end 0.12065 -0.305054)
			(stroke
				(width 0.1)
				(type default)
			)
			(layer "B.Fab")
		)
		(pad "1" smd circle
			(at 0.40005 0 90)
			(size 0 0)
			(layers "B.Cu" "B.Mask" "B.Paste")
			(net "P52V_HS1_VREG")
		)
		(pad "2" smd circle
			(at -0.40005 0 90)
			(size 0 0)
			(layers "B.Cu" "B.Mask" "B.Paste")
			(net "GND_FIELD_SIGNAL")
		)
	)
	(footprint ""
		(layer "B.Cu")
		(at 163.368736 -77.089 180)
		(property "Reference" "PC602"
			(at 0 0 0)
			(layer "B.SilkS")
			(hide yes)
			(effects
				(font
					(size 1.27 1.27)
				)
				(justify mirror)
			)
		)
		(property "Value" ""
			(at 0 0 0)
			(layer "B.Fab")
			(effects
				(font
					(size 1.27 1.27)
				)
				(justify mirror)
			)
		)
		(duplicate_pad_numbers_are_jumpers no)
		(fp_line
			(start 1.2954 0.5842)
			(end 1.2954 -0.5842)
			(stroke
				(width 0.1524)
				(type default)
			)
			(layer "B.SilkS")
		)
		(fp_line
			(start 1.2954 -0.5842)
			(end -1.2954 -0.5842)
			(stroke
				(width 0.1524)
				(type default)
			)
			(layer "B.SilkS")
		)
		(fp_line
			(start -1.2954 0.5842)
			(end 1.2954 0.5842)
			(stroke
				(width 0.1524)
				(type default)
			)
			(layer "B.SilkS")
		)
		(fp_line
			(start -1.2954 -0.5842)
			(end -1.2954 0.5842)
			(stroke
				(width 0.1524)
				(type default)
			)
			(layer "B.SilkS")
		)
		(fp_line
			(start 1.1938 0.4064)
			(end 1.1938 -0.4064)
			(stroke
				(width 0.1)
				(type default)
			)
			(layer "B.Fab")
		)
		(fp_line
			(start 1.1938 -0.4064)
			(end 0.8636 -0.4064)
			(stroke
				(width 0.1)
				(type default)
			)
			(layer "B.Fab")
		)
		(fp_line
			(start 0.8636 0.4572)
			(end 0.8636 0.4064)
			(stroke
				(width 0.1)
				(type default)
			)
			(layer "B.Fab")
		)
		(fp_line
			(start 0.8636 0.4064)
			(end 1.1938 0.4064)
			(stroke
				(width 0.1)
				(type default)
			)
			(layer "B.Fab")
		)
		(fp_line
			(start 0.8636 -0.4064)
			(end 0.8636 -0.4572)
			(stroke
				(width 0.1)
				(type default)
			)
			(layer "B.Fab")
		)
		(fp_line
			(start 0.8636 -0.4572)
			(end -0.8636 -0.4572)
			(stroke
				(width 0.1)
				(type default)
			)
			(layer "B.Fab")
		)
		(fp_line
			(start -0.8636 0.4572)
			(end 0.8636 0.4572)
			(stroke
				(width 0.1)
				(type default)
			)
			(layer "B.Fab")
		)
		(fp_line
			(start -0.8636 0.4064)
			(end -0.8636 0.4572)
			(stroke
				(width 0.1)
				(type default)
			)
			(layer "B.Fab")
		)
		(fp_line
			(start -0.8636 -0.4064)
			(end -1.1938 -0.4064)
			(stroke
				(width 0.1)
				(type default)
			)
			(layer "B.Fab")
		)
		(fp_line
			(start -0.8636 -0.4572)
			(end -0.8636 -0.4064)
			(stroke
				(width 0.1)
				(type default)
			)
			(layer "B.Fab")
		)
		(fp_line
			(start -1.1938 0.4064)
			(end -0.8636 0.4064)
			(stroke
				(width 0.1)
				(type default)
			)
			(layer "B.Fab")
		)
		(fp_line
			(start -1.1938 -0.4064)
			(end -1.1938 0.4064)
			(stroke
				(width 0.1)
				(type default)
			)
			(layer "B.Fab")
		)
		(pad "1" smd rect
			(at 0.7366 0 90)
			(size 0.7112 0.8128)
			(layers "B.Cu" "B.Mask" "B.Paste")
			(net "HS2_TMR2")
		)
		(pad "2" smd rect
			(at -0.7366 0 90)
			(size 0.7112 0.8128)
			(layers "B.Cu" "B.Mask" "B.Paste")
			(net "GND1_FIELD_SIGNAL")
		)
	)
	(footprint ""
		(layer "B.Cu")
		(at 286.2834 -65.278 90)
		(property "Reference" "PR210"
			(at 0 0 90)
			(layer "B.SilkS")
			(hide yes)
			(effects
				(font
					(size 1.27 1.27)
				)
				(justify mirror)
			)
		)
		(property "Value" ""
			(at 0 0 90)
			(layer "B.Fab")
			(effects
				(font
					(size 1.27 1.27)
				)
				(justify mirror)
			)
		)
		(duplicate_pad_numbers_are_jumpers no)
		(fp_line
			(start 0.7874 -0.4064)
			(end -0.7874 -0.4064)
			(stroke
				(width 0.1524)
				(type default)
			)
			(layer "B.SilkS")
		)
		(fp_line
			(start -0.7874 -0.4064)
			(end -0.7874 0.4064)
			(stroke
				(width 0.1524)
				(type default)
			)
			(layer "B.SilkS")
		)
		(fp_line
			(start 0.7874 0.4064)
			(end 0.7874 -0.4064)
			(stroke
				(width 0.1524)
				(type default)
			)
			(layer "B.SilkS")
		)
		(fp_line
			(start -0.7874 0.4064)
			(end 0.7874 0.4064)
			(stroke
				(width 0.1524)
				(type default)
			)
			(layer "B.SilkS")
		)
		(fp_line
			(start 0.67945 -0.305054)
			(end 0.12065 -0.305054)
			(stroke
				(width 0.1)
				(type default)
			)
			(layer "B.Fab")
		)
		(fp_line
			(start 0.12065 -0.305054)
			(end 0.12065 -0.2794)
			(stroke
				(width 0.1)
				(type default)
			)
			(layer "B.Fab")
		)
		(fp_line
			(start -0.12065 -0.3048)
			(end -0.67945 -0.3048)
			(stroke
				(width 0.1)
				(type default)
			)
			(layer "B.Fab")
		)
		(fp_line
			(start -0.67945 -0.3048)
			(end -0.67945 0.3048)
			(stroke
				(width 0.1)
				(type default)
			)
			(layer "B.Fab")
		)
		(fp_line
			(start 0.12065 -0.2794)
			(end -0.12065 -0.2794)
			(stroke
				(width 0.1)
				(type default)
			)
			(layer "B.Fab")
		)
		(fp_line
			(start -0.12065 -0.2794)
			(end -0.12065 -0.3048)
			(stroke
				(width 0.1)
				(type default)
			)
			(layer "B.Fab")
		)
		(fp_line
			(start 0.12065 0.2794)
			(end 0.12065 0.3048)
			(stroke
				(width 0.1)
				(type default)
			)
			(layer "B.Fab")
		)
		(fp_line
			(start -0.120396 0.2794)
			(end 0.12065 0.2794)
			(stroke
				(width 0.1)
				(type default)
			)
			(layer "B.Fab")
		)
		(fp_line
			(start 0.67945 0.3048)
			(end 0.67945 -0.305054)
			(stroke
				(width 0.1)
				(type default)
			)
			(layer "B.Fab")
		)
		(fp_line
			(start 0.12065 0.3048)
			(end 0.67945 0.3048)
			(stroke
				(width 0.1)
				(type default)
			)
			(layer "B.Fab")
		)
		(fp_line
			(start -0.120396 0.3048)
			(end -0.120396 0.2794)
			(stroke
				(width 0.1)
				(type default)
			)
			(layer "B.Fab")
		)
		(fp_line
			(start -0.67945 0.3048)
			(end -0.120396 0.3048)
			(stroke
				(width 0.1)
				(type default)
			)
			(layer "B.Fab")
		)
		(pad "1" smd circle
			(at 0.40005 0 270)
			(size 0 0)
			(layers "B.Cu" "B.Mask" "B.Paste")
			(net "P52V_HS1_TMR")
		)
		(pad "2" smd circle
			(at -0.40005 0 270)
			(size 0 0)
			(layers "B.Cu" "B.Mask" "B.Paste")
			(net "HS1_TMR1")
		)
	)
	(footprint ""
		(layer "B.Cu")
		(at 337.3374 -50.6476 90)
		(property "Reference" "R5862"
			(at 0 0 90)
			(layer "B.SilkS")
			(hide yes)
			(effects
				(font
					(size 1.27 1.27)
				)
				(justify mirror)
			)
		)
		(property "Value" ""
			(at 0 0 90)
			(layer "B.Fab")
			(effects
				(font
					(size 1.27 1.27)
				)
				(justify mirror)
			)
		)
		(duplicate_pad_numbers_are_jumpers no)
		(fp_line
			(start 0.7874 -0.4064)
			(end -0.7874 -0.4064)
			(stroke
				(width 0.1524)
				(type default)
			)
			(layer "B.SilkS")
		)
		(fp_line
			(start -0.7874 -0.4064)
			(end -0.7874 0.4064)
			(stroke
				(width 0.1524)
				(type default)
			)
			(layer "B.SilkS")
		)
		(fp_line
			(start 0.7874 0.4064)
			(end 0.7874 -0.4064)
			(stroke
				(width 0.1524)
				(type default)
			)
			(layer "B.SilkS")
		)
		(fp_line
			(start -0.7874 0.4064)
			(end 0.7874 0.4064)
			(stroke
				(width 0.1524)
				(type default)
			)
			(layer "B.SilkS")
		)
		(fp_line
			(start 0.67945 -0.305054)
			(end 0.12065 -0.305054)
			(stroke
				(width 0.1)
				(type default)
			)
			(layer "B.Fab")
		)
		(fp_line
			(start 0.12065 -0.305054)
			(end 0.12065 -0.2794)
			(stroke
				(width 0.1)
				(type default)
			)
			(layer "B.Fab")
		)
		(fp_line
			(start -0.12065 -0.3048)
			(end -0.67945 -0.3048)
			(stroke
				(width 0.1)
				(type default)
			)
			(layer "B.Fab")
		)
		(fp_line
			(start -0.67945 -0.3048)
			(end -0.67945 0.3048)
			(stroke
				(width 0.1)
				(type default)
			)
			(layer "B.Fab")
		)
		(fp_line
			(start 0.12065 -0.2794)
			(end -0.12065 -0.2794)
			(stroke
				(width 0.1)
				(type default)
			)
			(layer "B.Fab")
		)
		(fp_line
			(start -0.12065 -0.2794)
			(end -0.12065 -0.3048)
			(stroke
				(width 0.1)
				(type default)
			)
			(layer "B.Fab")
		)
		(fp_line
			(start 0.12065 0.2794)
			(end 0.12065 0.3048)
			(stroke
				(width 0.1)
				(type default)
			)
			(layer "B.Fab")
		)
		(fp_line
			(start -0.120396 0.2794)
			(end 0.12065 0.2794)
			(stroke
				(width 0.1)
				(type default)
			)
			(layer "B.Fab")
		)
		(fp_line
			(start 0.67945 0.3048)
			(end 0.67945 -0.305054)
			(stroke
				(width 0.1)
				(type default)
			)
			(layer "B.Fab")
		)
		(fp_line
			(start 0.12065 0.3048)
			(end 0.67945 0.3048)
			(stroke
				(width 0.1)
				(type default)
			)
			(layer "B.Fab")
		)
		(fp_line
			(start -0.120396 0.3048)
			(end -0.120396 0.2794)
			(stroke
				(width 0.1)
				(type default)
			)
			(layer "B.Fab")
		)
		(fp_line
			(start -0.67945 0.3048)
			(end -0.120396 0.3048)
			(stroke
				(width 0.1)
				(type default)
			)
			(layer "B.Fab")
		)
		(pad "1" smd circle
			(at 0.40005 0 270)
			(size 0 0)
			(layers "B.Cu" "B.Mask" "B.Paste")
			(net "P52V_HS1_GATE1_R")
		)
		(pad "2" smd circle
			(at -0.40005 0 270)
			(size 0 0)
			(layers "B.Cu" "B.Mask" "B.Paste")
			(net "P52V_HS1_4287_GATE_R")
		)
	)
	(footprint ""
		(layer "B.Cu")
		(at 297.3324 -76.962)
		(property "Reference" "PR25"
			(at 0 0 0)
			(layer "B.SilkS")
			(hide yes)
			(effects
				(font
					(size 1.27 1.27)
				)
				(justify mirror)
			)
		)
		(property "Value" ""
			(at 0 0 0)
			(layer "B.Fab")
			(effects
				(font
					(size 1.27 1.27)
				)
				(justify mirror)
			)
		)
		(duplicate_pad_numbers_are_jumpers no)
		(fp_line
			(start -1.651 -0.8382)
			(end -1.651 0.8382)
			(stroke
				(width 0.1524)
				(type default)
			)
			(layer "B.SilkS")
		)
		(fp_line
			(start -1.651 0.8382)
			(end 1.651 0.8382)
			(stroke
				(width 0.1524)
				(type default)
			)
			(layer "B.SilkS")
		)
		(fp_line
			(start 1.651 -0.8382)
			(end -1.651 -0.8382)
			(stroke
				(width 0.1524)
				(type default)
			)
			(layer "B.SilkS")
		)
		(fp_line
			(start 1.651 0.8382)
			(end 1.651 -0.8382)
			(stroke
				(width 0.1524)
				(type default)
			)
			(layer "B.SilkS")
		)
		(fp_line
			(start -1.560576 -0.7366)
			(end -1.524 -0.7366)
			(stroke
				(width 0.1)
				(type default)
			)
			(layer "B.Fab")
		)
		(fp_line
			(start -1.560576 0.7366)
			(end -1.560576 -0.7366)
			(stroke
				(width 0.1)
				(type default)
			)
			(layer "B.Fab")
		)
		(fp_line
			(start -1.524 -0.7366)
			(end 1.524 -0.7366)
			(stroke
				(width 0.1)
				(type default)
			)
			(layer "B.Fab")
		)
		(fp_line
			(start -1.524 0.7366)
			(end -1.560576 0.7366)
			(stroke
				(width 0.1)
				(type default)
			)
			(layer "B.Fab")
		)
		(fp_line
			(start 1.524 -0.7366)
			(end 1.559814 -0.7366)
			(stroke
				(width 0.1)
				(type default)
			)
			(layer "B.Fab")
		)
		(fp_line
			(start 1.524 0.7366)
			(end -1.524 0.7366)
			(stroke
				(width 0.1)
				(type default)
			)
			(layer "B.Fab")
		)
		(fp_line
			(start 1.559814 -0.7366)
			(end 1.559814 0.7366)
			(stroke
				(width 0.1)
				(type default)
			)
			(layer "B.Fab")
		)
		(fp_line
			(start 1.559814 0.7366)
			(end 1.524 0.7366)
			(stroke
				(width 0.1)
				(type default)
			)
			(layer "B.Fab")
		)
		(pad "1" smd rect
			(at 0.94996 0)
			(size 1.1176 1.3716)
			(layers "B.Cu" "B.Mask" "B.Paste")
			(net "P52V_HS1")
		)
		(pad "2" smd rect
			(at -0.94996 0)
			(size 1.1176 1.3716)
			(layers "B.Cu" "B.Mask" "B.Paste")
			(net "P52V_HS1_VDSFB")
		)
	)
	(footprint ""
		(layer "B.Cu")
		(at 416.833558 -32.767016 -90)
		(property "Reference" "R5924"
			(at 0 0 90)
			(layer "B.SilkS")
			(hide yes)
			(effects
				(font
					(size 1.27 1.27)
				)
				(justify mirror)
			)
		)
		(property "Value" ""
			(at 0 0 90)
			(layer "B.Fab")
			(effects
				(font
					(size 1.27 1.27)
				)
				(justify mirror)
			)
		)
		(duplicate_pad_numbers_are_jumpers no)
		(fp_line
			(start -0.7874 0.4064)
			(end 0.7874 0.4064)
			(stroke
				(width 0.1524)
				(type default)
			)
			(layer "B.SilkS")
		)
		(fp_line
			(start 0.7874 0.4064)
			(end 0.7874 -0.4064)
			(stroke
				(width 0.1524)
				(type default)
			)
			(layer "B.SilkS")
		)
		(fp_line
			(start -0.7874 -0.4064)
			(end -0.7874 0.4064)
			(stroke
				(width 0.1524)
				(type default)
			)
			(layer "B.SilkS")
		)
		(fp_line
			(start 0.7874 -0.4064)
			(end -0.7874 -0.4064)
			(stroke
				(width 0.1524)
				(type default)
			)
			(layer "B.SilkS")
		)
		(fp_line
			(start -0.67945 0.3048)
			(end -0.120396 0.3048)
			(stroke
				(width 0.1)
				(type default)
			)
			(layer "B.Fab")
		)
		(fp_line
			(start -0.120396 0.3048)
			(end -0.120396 0.2794)
			(stroke
				(width 0.1)
				(type default)
			)
			(layer "B.Fab")
		)
		(fp_line
			(start 0.12065 0.3048)
			(end 0.67945 0.3048)
			(stroke
				(width 0.1)
				(type default)
			)
			(layer "B.Fab")
		)
		(fp_line
			(start 0.67945 0.3048)
			(end 0.67945 -0.305054)
			(stroke
				(width 0.1)
				(type default)
			)
			(layer "B.Fab")
		)
		(fp_line
			(start -0.120396 0.2794)
			(end 0.12065 0.2794)
			(stroke
				(width 0.1)
				(type default)
			)
			(layer "B.Fab")
		)
		(fp_line
			(start 0.12065 0.2794)
			(end 0.12065 0.3048)
			(stroke
				(width 0.1)
				(type default)
			)
			(layer "B.Fab")
		)
		(fp_line
			(start -0.12065 -0.2794)
			(end -0.12065 -0.3048)
			(stroke
				(width 0.1)
				(type default)
			)
			(layer "B.Fab")
		)
		(fp_line
			(start 0.12065 -0.2794)
			(end -0.12065 -0.2794)
			(stroke
				(width 0.1)
				(type default)
			)
			(layer "B.Fab")
		)
		(fp_line
			(start -0.67945 -0.3048)
			(end -0.67945 0.3048)
			(stroke
				(width 0.1)
				(type default)
			)
			(layer "B.Fab")
		)
		(fp_line
			(start -0.12065 -0.3048)
			(end -0.67945 -0.3048)
			(stroke
				(width 0.1)
				(type default)
			)
			(layer "B.Fab")
		)
		(fp_line
			(start 0.12065 -0.305054)
			(end 0.12065 -0.2794)
			(stroke
				(width 0.1)
				(type default)
			)
			(layer "B.Fab")
		)
		(fp_line
			(start 0.67945 -0.305054)
			(end 0.12065 -0.305054)
			(stroke
				(width 0.1)
				(type default)
			)
			(layer "B.Fab")
		)
		(pad "1" smd circle
			(at 0.40005 0 90)
			(size 0 0)
			(layers "B.Cu" "B.Mask" "B.Paste")
			(net "P12V_LED_ISET")
		)
		(pad "2" smd circle
			(at -0.40005 0 90)
			(size 0 0)
			(layers "B.Cu" "B.Mask" "B.Paste")
			(net "P12V_LED_ISET_R")
		)
	)
	(footprint ""
		(layer "B.Cu")
		(at 178.2064 -61.468)
		(property "Reference" "PC607"
			(at 0 0 0)
			(layer "B.SilkS")
			(hide yes)
			(effects
				(font
					(size 1.27 1.27)
				)
				(justify mirror)
			)
		)
		(property "Value" ""
			(at 0 0 0)
			(layer "B.Fab")
			(effects
				(font
					(size 1.27 1.27)
				)
				(justify mirror)
			)
		)
		(duplicate_pad_numbers_are_jumpers no)
		(fp_line
			(start -2.2098 -0.9398)
			(end -2.2098 0.9398)
			(stroke
				(width 0.1524)
				(type default)
			)
			(layer "B.SilkS")
		)
		(fp_line
			(start -2.2098 0.9398)
			(end 2.2098 0.9398)
			(stroke
				(width 0.1524)
				(type default)
			)
			(layer "B.SilkS")
		)
		(fp_line
			(start 2.2098 -0.9398)
			(end -2.2098 -0.9398)
			(stroke
				(width 0.1524)
				(type default)
			)
			(layer "B.SilkS")
		)
		(fp_line
			(start 2.2098 0.9398)
			(end 2.2098 -0.9398)
			(stroke
				(width 0.1524)
				(type default)
			)
			(layer "B.SilkS")
		)
		(fp_line
			(start -1.6764 -0.9398)
			(end 1.6764 -0.9398)
			(stroke
				(width 0.1)
				(type default)
			)
			(layer "B.Fab")
		)
		(fp_line
			(start -1.6764 0.9398)
			(end -1.6764 -0.9398)
			(stroke
				(width 0.1)
				(type default)
			)
			(layer "B.Fab")
		)
		(fp_line
			(start 1.6764 -0.9398)
			(end 1.6764 0.9398)
			(stroke
				(width 0.1)
				(type default)
			)
			(layer "B.Fab")
		)
		(fp_line
			(start 1.6764 0.9398)
			(end -1.6764 0.9398)
			(stroke
				(width 0.1)
				(type default)
			)
			(layer "B.Fab")
		)
		(pad "1" smd rect
			(at 1.4732 0)
			(size 1.1684 1.5748)
			(layers "B.Cu" "B.Mask" "B.Paste")
			(net "P52V_HS2_VCC")
		)
		(pad "2" smd rect
			(at -1.4732 0)
			(size 1.1684 1.5748)
			(layers "B.Cu" "B.Mask" "B.Paste")
			(net "GND1_FIELD_SIGNAL")
		)
	)
	(footprint ""
		(layer "B.Cu")
		(at 271.1704 -63.5)
		(property "Reference" "PR6935"
			(at 0 0 0)
			(layer "B.SilkS")
			(hide yes)
			(effects
				(font
					(size 1.27 1.27)
				)
				(justify mirror)
			)
		)
		(property "Value" ""
			(at 0 0 0)
			(layer "B.Fab")
			(effects
				(font
					(size 1.27 1.27)
				)
				(justify mirror)
			)
		)
		(duplicate_pad_numbers_are_jumpers no)
		(fp_line
			(start -0.7874 -0.4064)
			(end -0.7874 0.4064)
			(stroke
				(width 0.1524)
				(type default)
			)
			(layer "B.SilkS")
		)
		(fp_line
			(start -0.7874 0.4064)
			(end 0.7874 0.4064)
			(stroke
				(width 0.1524)
				(type default)
			)
			(layer "B.SilkS")
		)
		(fp_line
			(start 0.7874 -0.4064)
			(end -0.7874 -0.4064)
			(stroke
				(width 0.1524)
				(type default)
			)
			(layer "B.SilkS")
		)
		(fp_line
			(start 0.7874 0.4064)
			(end 0.7874 -0.4064)
			(stroke
				(width 0.1524)
				(type default)
			)
			(layer "B.SilkS")
		)
		(fp_line
			(start -0.67945 -0.3048)
			(end -0.67945 0.3048)
			(stroke
				(width 0.1)
				(type default)
			)
			(layer "B.Fab")
		)
		(fp_line
			(start -0.67945 0.3048)
			(end -0.120396 0.3048)
			(stroke
				(width 0.1)
				(type default)
			)
			(layer "B.Fab")
		)
		(fp_line
			(start -0.12065 -0.3048)
			(end -0.67945 -0.3048)
			(stroke
				(width 0.1)
				(type default)
			)
			(layer "B.Fab")
		)
		(fp_line
			(start -0.12065 -0.2794)
			(end -0.12065 -0.3048)
			(stroke
				(width 0.1)
				(type default)
			)
			(layer "B.Fab")
		)
		(fp_line
			(start -0.120396 0.2794)
			(end 0.12065 0.2794)
			(stroke
				(width 0.1)
				(type default)
			)
			(layer "B.Fab")
		)
		(fp_line
			(start -0.120396 0.3048)
			(end -0.120396 0.2794)
			(stroke
				(width 0.1)
				(type default)
			)
			(layer "B.Fab")
		)
		(fp_line
			(start 0.12065 -0.305054)
			(end 0.12065 -0.2794)
			(stroke
				(width 0.1)
				(type default)
			)
			(layer "B.Fab")
		)
		(fp_line
			(start 0.12065 -0.2794)
			(end -0.12065 -0.2794)
			(stroke
				(width 0.1)
				(type default)
			)
			(layer "B.Fab")
		)
		(fp_line
			(start 0.12065 0.2794)
			(end 0.12065 0.3048)
			(stroke
				(width 0.1)
				(type default)
			)
			(layer "B.Fab")
		)
		(fp_line
			(start 0.12065 0.3048)
			(end 0.67945 0.3048)
			(stroke
				(width 0.1)
				(type default)
			)
			(layer "B.Fab")
		)
		(fp_line
			(start 0.67945 -0.305054)
			(end 0.12065 -0.305054)
			(stroke
				(width 0.1)
				(type default)
			)
			(layer "B.Fab")
		)
		(fp_line
			(start 0.67945 0.3048)
			(end 0.67945 -0.305054)
			(stroke
				(width 0.1)
				(type default)
			)
			(layer "B.Fab")
		)
		(pad "1" smd circle
			(at 0.40005 0 180)
			(size 0 0)
			(layers "B.Cu" "B.Mask" "B.Paste")
			(net "PWRGD_P52V_HS1_PG")
		)
		(pad "2" smd circle
			(at -0.40005 0 180)
			(size 0 0)
			(layers "B.Cu" "B.Mask" "B.Paste")
			(net "P52V_HS1_PWRGIN")
		)
	)
	(footprint ""
		(layer "B.Cu")
		(at 278.4094 -63.881 180)
		(property "Reference" "PR35"
			(at 0 0 0)
			(layer "B.SilkS")
			(hide yes)
			(effects
				(font
					(size 1.27 1.27)
				)
				(justify mirror)
			)
		)
		(property "Value" ""
			(at 0 0 0)
			(layer "B.Fab")
			(effects
				(font
					(size 1.27 1.27)
				)
				(justify mirror)
			)
		)
		(duplicate_pad_numbers_are_jumpers no)
		(fp_line
			(start 0.7874 0.4064)
			(end 0.7874 -0.4064)
			(stroke
				(width 0.1524)
				(type default)
			)
			(layer "B.SilkS")
		)
		(fp_line
			(start 0.7874 -0.4064)
			(end -0.7874 -0.4064)
			(stroke
				(width 0.1524)
				(type default)
			)
			(layer "B.SilkS")
		)
		(fp_line
			(start -0.7874 0.4064)
			(end 0.7874 0.4064)
			(stroke
				(width 0.1524)
				(type default)
			)
			(layer "B.SilkS")
		)
		(fp_line
			(start -0.7874 -0.4064)
			(end -0.7874 0.4064)
			(stroke
				(width 0.1524)
				(type default)
			)
			(layer "B.SilkS")
		)
		(fp_line
			(start 0.67945 0.3048)
			(end 0.67945 -0.305054)
			(stroke
				(width 0.1)
				(type default)
			)
			(layer "B.Fab")
		)
		(fp_line
			(start 0.67945 -0.305054)
			(end 0.12065 -0.305054)
			(stroke
				(width 0.1)
				(type default)
			)
			(layer "B.Fab")
		)
		(fp_line
			(start 0.12065 0.3048)
			(end 0.67945 0.3048)
			(stroke
				(width 0.1)
				(type default)
			)
			(layer "B.Fab")
		)
		(fp_line
			(start 0.12065 0.2794)
			(end 0.12065 0.3048)
			(stroke
				(width 0.1)
				(type default)
			)
			(layer "B.Fab")
		)
		(fp_line
			(start 0.12065 -0.2794)
			(end -0.12065 -0.2794)
			(stroke
				(width 0.1)
				(type default)
			)
			(layer "B.Fab")
		)
		(fp_line
			(start 0.12065 -0.305054)
			(end 0.12065 -0.2794)
			(stroke
				(width 0.1)
				(type default)
			)
			(layer "B.Fab")
		)
		(fp_line
			(start -0.120396 0.3048)
			(end -0.120396 0.2794)
			(stroke
				(width 0.1)
				(type default)
			)
			(layer "B.Fab")
		)
		(fp_line
			(start -0.120396 0.2794)
			(end 0.12065 0.2794)
			(stroke
				(width 0.1)
				(type default)
			)
			(layer "B.Fab")
		)
		(fp_line
			(start -0.12065 -0.2794)
			(end -0.12065 -0.3048)
			(stroke
				(width 0.1)
				(type default)
			)
			(layer "B.Fab")
		)
		(fp_line
			(start -0.12065 -0.3048)
			(end -0.67945 -0.3048)
			(stroke
				(width 0.1)
				(type default)
			)
			(layer "B.Fab")
		)
		(fp_line
			(start -0.67945 0.3048)
			(end -0.120396 0.3048)
			(stroke
				(width 0.1)
				(type default)
			)
			(layer "B.Fab")
		)
		(fp_line
			(start -0.67945 -0.3048)
			(end -0.67945 0.3048)
			(stroke
				(width 0.1)
				(type default)
			)
			(layer "B.Fab")
		)
		(pad "1" smd circle
			(at 0.40005 0)
			(size 0 0)
			(layers "B.Cu" "B.Mask" "B.Paste")
			(net "P52V_HS1_MCB")
		)
		(pad "2" smd circle
			(at -0.40005 0)
			(size 0 0)
			(layers "B.Cu" "B.Mask" "B.Paste")
			(net "GND_FIELD_SIGNAL")
		)
	)
	(footprint ""
		(layer "B.Cu")
		(at 162.860736 -75.692 180)
		(property "Reference" "PC604"
			(at 0 0 0)
			(layer "B.SilkS")
			(hide yes)
			(effects
				(font
					(size 1.27 1.27)
				)
				(justify mirror)
			)
		)
		(property "Value" ""
			(at 0 0 0)
			(layer "B.Fab")
			(effects
				(font
					(size 1.27 1.27)
				)
				(justify mirror)
			)
		)
		(duplicate_pad_numbers_are_jumpers no)
		(fp_line
			(start 0.7874 0.4064)
			(end 0.7874 -0.4064)
			(stroke
				(width 0.1524)
				(type default)
			)
			(layer "B.SilkS")
		)
		(fp_line
			(start 0.7874 -0.4064)
			(end -0.7874 -0.4064)
			(stroke
				(width 0.1524)
				(type default)
			)
			(layer "B.SilkS")
		)
		(fp_line
			(start -0.7874 0.4064)
			(end 0.7874 0.4064)
			(stroke
				(width 0.1524)
				(type default)
			)
			(layer "B.SilkS")
		)
		(fp_line
			(start -0.7874 -0.4064)
			(end -0.7874 0.4064)
			(stroke
				(width 0.1524)
				(type default)
			)
			(layer "B.SilkS")
		)
		(fp_line
			(start 0.67945 0.3048)
			(end 0.67945 -0.305054)
			(stroke
				(width 0.1)
				(type default)
			)
			(layer "B.Fab")
		)
		(fp_line
			(start 0.67945 -0.305054)
			(end 0.12065 -0.305054)
			(stroke
				(width 0.1)
				(type default)
			)
			(layer "B.Fab")
		)
		(fp_line
			(start 0.12065 0.3048)
			(end 0.67945 0.3048)
			(stroke
				(width 0.1)
				(type default)
			)
			(layer "B.Fab")
		)
		(fp_line
			(start 0.12065 0.2794)
			(end 0.12065 0.3048)
			(stroke
				(width 0.1)
				(type default)
			)
			(layer "B.Fab")
		)
		(fp_line
			(start 0.12065 -0.2794)
			(end -0.12065 -0.2794)
			(stroke
				(width 0.1)
				(type default)
			)
			(layer "B.Fab")
		)
		(fp_line
			(start 0.12065 -0.305054)
			(end 0.12065 -0.2794)
			(stroke
				(width 0.1)
				(type default)
			)
			(layer "B.Fab")
		)
		(fp_line
			(start -0.120396 0.3048)
			(end -0.120396 0.2794)
			(stroke
				(width 0.1)
				(type default)
			)
			(layer "B.Fab")
		)
		(fp_line
			(start -0.120396 0.2794)
			(end 0.12065 0.2794)
			(stroke
				(width 0.1)
				(type default)
			)
			(layer "B.Fab")
		)
		(fp_line
			(start -0.12065 -0.2794)
			(end -0.12065 -0.3048)
			(stroke
				(width 0.1)
				(type default)
			)
			(layer "B.Fab")
		)
		(fp_line
			(start -0.12065 -0.3048)
			(end -0.67945 -0.3048)
			(stroke
				(width 0.1)
				(type default)
			)
			(layer "B.Fab")
		)
		(fp_line
			(start -0.67945 0.3048)
			(end -0.120396 0.3048)
			(stroke
				(width 0.1)
				(type default)
			)
			(layer "B.Fab")
		)
		(fp_line
			(start -0.67945 -0.3048)
			(end -0.67945 0.3048)
			(stroke
				(width 0.1)
				(type default)
			)
			(layer "B.Fab")
		)
		(pad "1" smd circle
			(at 0.40005 0)
			(size 0 0)
			(layers "B.Cu" "B.Mask" "B.Paste")
			(net "HS2_TMR1")
		)
		(pad "2" smd circle
			(at -0.40005 0)
			(size 0 0)
			(layers "B.Cu" "B.Mask" "B.Paste")
			(net "GND1_FIELD_SIGNAL")
		)
	)
	(footprint ""
		(layer "B.Cu")
		(at 169.1894 -77.343)
		(property "Reference" "R5890"
			(at 0 0 0)
			(layer "B.SilkS")
			(hide yes)
			(effects
				(font
					(size 1.27 1.27)
				)
				(justify mirror)
			)
		)
		(property "Value" ""
			(at 0 0 0)
			(layer "B.Fab")
			(effects
				(font
					(size 1.27 1.27)
				)
				(justify mirror)
			)
		)
		(duplicate_pad_numbers_are_jumpers no)
		(fp_line
			(start -0.7874 -0.4064)
			(end -0.7874 0.4064)
			(stroke
				(width 0.1524)
				(type default)
			)
			(layer "B.SilkS")
		)
		(fp_line
			(start -0.7874 0.4064)
			(end 0.7874 0.4064)
			(stroke
				(width 0.1524)
				(type default)
			)
			(layer "B.SilkS")
		)
		(fp_line
			(start 0.7874 -0.4064)
			(end -0.7874 -0.4064)
			(stroke
				(width 0.1524)
				(type default)
			)
			(layer "B.SilkS")
		)
		(fp_line
			(start 0.7874 0.4064)
			(end 0.7874 -0.4064)
			(stroke
				(width 0.1524)
				(type default)
			)
			(layer "B.SilkS")
		)
		(fp_line
			(start -0.67945 -0.3048)
			(end -0.67945 0.3048)
			(stroke
				(width 0.1)
				(type default)
			)
			(layer "B.Fab")
		)
		(fp_line
			(start -0.67945 0.3048)
			(end -0.120396 0.3048)
			(stroke
				(width 0.1)
				(type default)
			)
			(layer "B.Fab")
		)
		(fp_line
			(start -0.12065 -0.3048)
			(end -0.67945 -0.3048)
			(stroke
				(width 0.1)
				(type default)
			)
			(layer "B.Fab")
		)
		(fp_line
			(start -0.12065 -0.2794)
			(end -0.12065 -0.3048)
			(stroke
				(width 0.1)
				(type default)
			)
			(layer "B.Fab")
		)
		(fp_line
			(start -0.120396 0.2794)
			(end 0.12065 0.2794)
			(stroke
				(width 0.1)
				(type default)
			)
			(layer "B.Fab")
		)
		(fp_line
			(start -0.120396 0.3048)
			(end -0.120396 0.2794)
			(stroke
				(width 0.1)
				(type default)
			)
			(layer "B.Fab")
		)
		(fp_line
			(start 0.12065 -0.305054)
			(end 0.12065 -0.2794)
			(stroke
				(width 0.1)
				(type default)
			)
			(layer "B.Fab")
		)
		(fp_line
			(start 0.12065 -0.2794)
			(end -0.12065 -0.2794)
			(stroke
				(width 0.1)
				(type default)
			)
			(layer "B.Fab")
		)
		(fp_line
			(start 0.12065 0.2794)
			(end 0.12065 0.3048)
			(stroke
				(width 0.1)
				(type default)
			)
			(layer "B.Fab")
		)
		(fp_line
			(start 0.12065 0.3048)
			(end 0.67945 0.3048)
			(stroke
				(width 0.1)
				(type default)
			)
			(layer "B.Fab")
		)
		(fp_line
			(start 0.67945 -0.305054)
			(end 0.12065 -0.305054)
			(stroke
				(width 0.1)
				(type default)
			)
			(layer "B.Fab")
		)
		(fp_line
			(start 0.67945 0.3048)
			(end 0.67945 -0.305054)
			(stroke
				(width 0.1)
				(type default)
			)
			(layer "B.Fab")
		)
		(pad "1" smd circle
			(at 0.40005 0 180)
			(size 0 0)
			(layers "B.Cu" "B.Mask" "B.Paste")
			(net "P52V_HS2_GPO1")
		)
		(pad "2" smd circle
			(at -0.40005 0 180)
			(size 0 0)
			(layers "B.Cu" "B.Mask" "B.Paste")
			(net "P52V_HS2_FLT")
		)
	)
	(footprint ""
		(layer "B.Cu")
		(at 272.3134 -62.357 180)
		(property "Reference" "R149"
			(at 0 0 0)
			(layer "B.SilkS")
			(hide yes)
			(effects
				(font
					(size 1.27 1.27)
				)
				(justify mirror)
			)
		)
		(property "Value" ""
			(at 0 0 0)
			(layer "B.Fab")
			(effects
				(font
					(size 1.27 1.27)
				)
				(justify mirror)
			)
		)
		(duplicate_pad_numbers_are_jumpers no)
		(fp_line
			(start 0.7874 0.4064)
			(end 0.7874 -0.4064)
			(stroke
				(width 0.1524)
				(type default)
			)
			(layer "B.SilkS")
		)
		(fp_line
			(start 0.7874 -0.4064)
			(end -0.7874 -0.4064)
			(stroke
				(width 0.1524)
				(type default)
			)
			(layer "B.SilkS")
		)
		(fp_line
			(start -0.7874 0.4064)
			(end 0.7874 0.4064)
			(stroke
				(width 0.1524)
				(type default)
			)
			(layer "B.SilkS")
		)
		(fp_line
			(start -0.7874 -0.4064)
			(end -0.7874 0.4064)
			(stroke
				(width 0.1524)
				(type default)
			)
			(layer "B.SilkS")
		)
		(fp_line
			(start 0.67945 0.3048)
			(end 0.67945 -0.305054)
			(stroke
				(width 0.1)
				(type default)
			)
			(layer "B.Fab")
		)
		(fp_line
			(start 0.67945 -0.305054)
			(end 0.12065 -0.305054)
			(stroke
				(width 0.1)
				(type default)
			)
			(layer "B.Fab")
		)
		(fp_line
			(start 0.12065 0.3048)
			(end 0.67945 0.3048)
			(stroke
				(width 0.1)
				(type default)
			)
			(layer "B.Fab")
		)
		(fp_line
			(start 0.12065 0.2794)
			(end 0.12065 0.3048)
			(stroke
				(width 0.1)
				(type default)
			)
			(layer "B.Fab")
		)
		(fp_line
			(start 0.12065 -0.2794)
			(end -0.12065 -0.2794)
			(stroke
				(width 0.1)
				(type default)
			)
			(layer "B.Fab")
		)
		(fp_line
			(start 0.12065 -0.305054)
			(end 0.12065 -0.2794)
			(stroke
				(width 0.1)
				(type default)
			)
			(layer "B.Fab")
		)
		(fp_line
			(start -0.120396 0.3048)
			(end -0.120396 0.2794)
			(stroke
				(width 0.1)
				(type default)
			)
			(layer "B.Fab")
		)
		(fp_line
			(start -0.120396 0.2794)
			(end 0.12065 0.2794)
			(stroke
				(width 0.1)
				(type default)
			)
			(layer "B.Fab")
		)
		(fp_line
			(start -0.12065 -0.2794)
			(end -0.12065 -0.3048)
			(stroke
				(width 0.1)
				(type default)
			)
			(layer "B.Fab")
		)
		(fp_line
			(start -0.12065 -0.3048)
			(end -0.67945 -0.3048)
			(stroke
				(width 0.1)
				(type default)
			)
			(layer "B.Fab")
		)
		(fp_line
			(start -0.67945 0.3048)
			(end -0.120396 0.3048)
			(stroke
				(width 0.1)
				(type default)
			)
			(layer "B.Fab")
		)
		(fp_line
			(start -0.67945 -0.3048)
			(end -0.67945 0.3048)
			(stroke
				(width 0.1)
				(type default)
			)
			(layer "B.Fab")
		)
		(pad "1" smd circle
			(at 0.40005 0)
			(size 0 0)
			(layers "B.Cu" "B.Mask" "B.Paste")
			(net "PWRGD_P52V_HS1_PG")
		)
		(pad "2" smd circle
			(at -0.40005 0)
			(size 0 0)
			(layers "B.Cu" "B.Mask" "B.Paste")
			(net "GND_FIELD_SIGNAL")
		)
	)
	(footprint ""
		(layer "B.Cu")
		(at 161.336736 -76.962 -90)
		(property "Reference" "PR7009"
			(at 0 0 90)
			(layer "B.SilkS")
			(hide yes)
			(effects
				(font
					(size 1.27 1.27)
				)
				(justify mirror)
			)
		)
		(property "Value" ""
			(at 0 0 90)
			(layer "B.Fab")
			(effects
				(font
					(size 1.27 1.27)
				)
				(justify mirror)
			)
		)
		(duplicate_pad_numbers_are_jumpers no)
		(fp_line
			(start -0.7874 0.4064)
			(end 0.7874 0.4064)
			(stroke
				(width 0.1524)
				(type default)
			)
			(layer "B.SilkS")
		)
		(fp_line
			(start 0.7874 0.4064)
			(end 0.7874 -0.4064)
			(stroke
				(width 0.1524)
				(type default)
			)
			(layer "B.SilkS")
		)
		(fp_line
			(start -0.7874 -0.4064)
			(end -0.7874 0.4064)
			(stroke
				(width 0.1524)
				(type default)
			)
			(layer "B.SilkS")
		)
		(fp_line
			(start 0.7874 -0.4064)
			(end -0.7874 -0.4064)
			(stroke
				(width 0.1524)
				(type default)
			)
			(layer "B.SilkS")
		)
		(fp_line
			(start -0.67945 0.3048)
			(end -0.120396 0.3048)
			(stroke
				(width 0.1)
				(type default)
			)
			(layer "B.Fab")
		)
		(fp_line
			(start -0.120396 0.3048)
			(end -0.120396 0.2794)
			(stroke
				(width 0.1)
				(type default)
			)
			(layer "B.Fab")
		)
		(fp_line
			(start 0.12065 0.3048)
			(end 0.67945 0.3048)
			(stroke
				(width 0.1)
				(type default)
			)
			(layer "B.Fab")
		)
		(fp_line
			(start 0.67945 0.3048)
			(end 0.67945 -0.305054)
			(stroke
				(width 0.1)
				(type default)
			)
			(layer "B.Fab")
		)
		(fp_line
			(start -0.120396 0.2794)
			(end 0.12065 0.2794)
			(stroke
				(width 0.1)
				(type default)
			)
			(layer "B.Fab")
		)
		(fp_line
			(start 0.12065 0.2794)
			(end 0.12065 0.3048)
			(stroke
				(width 0.1)
				(type default)
			)
			(layer "B.Fab")
		)
		(fp_line
			(start -0.12065 -0.2794)
			(end -0.12065 -0.3048)
			(stroke
				(width 0.1)
				(type default)
			)
			(layer "B.Fab")
		)
		(fp_line
			(start 0.12065 -0.2794)
			(end -0.12065 -0.2794)
			(stroke
				(width 0.1)
				(type default)
			)
			(layer "B.Fab")
		)
		(fp_line
			(start -0.67945 -0.3048)
			(end -0.67945 0.3048)
			(stroke
				(width 0.1)
				(type default)
			)
			(layer "B.Fab")
		)
		(fp_line
			(start -0.12065 -0.3048)
			(end -0.67945 -0.3048)
			(stroke
				(width 0.1)
				(type default)
			)
			(layer "B.Fab")
		)
		(fp_line
			(start 0.12065 -0.305054)
			(end 0.12065 -0.2794)
			(stroke
				(width 0.1)
				(type default)
			)
			(layer "B.Fab")
		)
		(fp_line
			(start 0.67945 -0.305054)
			(end 0.12065 -0.305054)
			(stroke
				(width 0.1)
				(type default)
			)
			(layer "B.Fab")
		)
		(pad "1" smd circle
			(at 0.40005 0 90)
			(size 0 0)
			(layers "B.Cu" "B.Mask" "B.Paste")
			(net "HS2_TMR1")
		)
		(pad "2" smd circle
			(at -0.40005 0 90)
			(size 0 0)
			(layers "B.Cu" "B.Mask" "B.Paste")
			(net "HS2_TMR2")
		)
	)
	(footprint ""
		(layer "B.Cu")
		(at 106.045 -54.991 -90)
		(property "Reference" "PR7002"
			(at 0 0 90)
			(layer "B.SilkS")
			(hide yes)
			(effects
				(font
					(size 1.27 1.27)
				)
				(justify mirror)
			)
		)
		(property "Value" ""
			(at 0 0 90)
			(layer "B.Fab")
			(effects
				(font
					(size 1.27 1.27)
				)
				(justify mirror)
			)
		)
		(duplicate_pad_numbers_are_jumpers no)
		(fp_line
			(start -1.2954 0.5842)
			(end 1.2954 0.5842)
			(stroke
				(width 0.1524)
				(type default)
			)
			(layer "B.SilkS")
		)
		(fp_line
			(start 1.2954 0.5842)
			(end 1.2954 -0.5842)
			(stroke
				(width 0.1524)
				(type default)
			)
			(layer "B.SilkS")
		)
		(fp_line
			(start -1.2954 -0.5842)
			(end -1.2954 0.5842)
			(stroke
				(width 0.1524)
				(type default)
			)
			(layer "B.SilkS")
		)
		(fp_line
			(start 1.2954 -0.5842)
			(end -1.2954 -0.5842)
			(stroke
				(width 0.1524)
				(type default)
			)
			(layer "B.SilkS")
		)
		(fp_line
			(start -0.8636 0.4572)
			(end 0.8636 0.4572)
			(stroke
				(width 0.1)
				(type default)
			)
			(layer "B.Fab")
		)
		(fp_line
			(start 0.8636 0.4572)
			(end 0.8636 0.4318)
			(stroke
				(width 0.1)
				(type default)
			)
			(layer "B.Fab")
		)
		(fp_line
			(start 0.8636 0.4318)
			(end 0.8636 0.4064)
			(stroke
				(width 0.1)
				(type default)
			)
			(layer "B.Fab")
		)
		(fp_line
			(start -1.1938 0.4064)
			(end -0.8636 0.4064)
			(stroke
				(width 0.1)
				(type default)
			)
			(layer "B.Fab")
		)
		(fp_line
			(start -0.8636 0.4064)
			(end -0.8636 0.4572)
			(stroke
				(width 0.1)
				(type default)
			)
			(layer "B.Fab")
		)
		(fp_line
			(start 0.8636 0.4064)
			(end 1.1938 0.4064)
			(stroke
				(width 0.1)
				(type default)
			)
			(layer "B.Fab")
		)
		(fp_line
			(start 1.1938 0.4064)
			(end 1.1938 -0.406654)
			(stroke
				(width 0.1)
				(type default)
			)
			(layer "B.Fab")
		)
		(fp_line
			(start -1.1938 -0.406654)
			(end -1.1938 0.4064)
			(stroke
				(width 0.1)
				(type default)
			)
			(layer "B.Fab")
		)
		(fp_line
			(start -0.8636 -0.406654)
			(end -1.1938 -0.406654)
			(stroke
				(width 0.1)
				(type default)
			)
			(layer "B.Fab")
		)
		(fp_line
			(start 0.8636 -0.406654)
			(end 0.8636 -0.4572)
			(stroke
				(width 0.1)
				(type default)
			)
			(layer "B.Fab")
		)
		(fp_line
			(start 1.1938 -0.406654)
			(end 0.8636 -0.406654)
			(stroke
				(width 0.1)
				(type default)
			)
			(layer "B.Fab")
		)
		(fp_line
			(start -0.8636 -0.4572)
			(end -0.8636 -0.406654)
			(stroke
				(width 0.1)
				(type default)
			)
			(layer "B.Fab")
		)
		(fp_line
			(start 0.8636 -0.4572)
			(end -0.8636 -0.4572)
			(stroke
				(width 0.1)
				(type default)
			)
			(layer "B.Fab")
		)
		(pad "1" smd rect
			(at 0.7366 0 180)
			(size 0.7112 0.8128)
			(layers "B.Cu" "B.Mask" "B.Paste")
			(net "P52V_HS2_4287_GATE_R")
		)
		(pad "2" smd rect
			(at -0.7366 0 180)
			(size 0.7112 0.8128)
			(layers "B.Cu" "B.Mask" "B.Paste")
			(net "P52V_HS2_GATE_RC")
		)
	)
	(footprint ""
		(layer "B.Cu")
		(at 161.717736 -68.326)
		(property "Reference" "R5870"
			(at 0 0 0)
			(layer "B.SilkS")
			(hide yes)
			(effects
				(font
					(size 1.27 1.27)
				)
				(justify mirror)
			)
		)
		(property "Value" ""
			(at 0 0 0)
			(layer "B.Fab")
			(effects
				(font
					(size 1.27 1.27)
				)
				(justify mirror)
			)
		)
		(duplicate_pad_numbers_are_jumpers no)
		(fp_line
			(start -0.7874 -0.4064)
			(end -0.7874 0.4064)
			(stroke
				(width 0.1524)
				(type default)
			)
			(layer "B.SilkS")
		)
		(fp_line
			(start -0.7874 0.4064)
			(end 0.7874 0.4064)
			(stroke
				(width 0.1524)
				(type default)
			)
			(layer "B.SilkS")
		)
		(fp_line
			(start 0.7874 -0.4064)
			(end -0.7874 -0.4064)
			(stroke
				(width 0.1524)
				(type default)
			)
			(layer "B.SilkS")
		)
		(fp_line
			(start 0.7874 0.4064)
			(end 0.7874 -0.4064)
			(stroke
				(width 0.1524)
				(type default)
			)
			(layer "B.SilkS")
		)
		(fp_line
			(start -0.67945 -0.3048)
			(end -0.67945 0.3048)
			(stroke
				(width 0.1)
				(type default)
			)
			(layer "B.Fab")
		)
		(fp_line
			(start -0.67945 0.3048)
			(end -0.120396 0.3048)
			(stroke
				(width 0.1)
				(type default)
			)
			(layer "B.Fab")
		)
		(fp_line
			(start -0.12065 -0.3048)
			(end -0.67945 -0.3048)
			(stroke
				(width 0.1)
				(type default)
			)
			(layer "B.Fab")
		)
		(fp_line
			(start -0.12065 -0.2794)
			(end -0.12065 -0.3048)
			(stroke
				(width 0.1)
				(type default)
			)
			(layer "B.Fab")
		)
		(fp_line
			(start -0.120396 0.2794)
			(end 0.12065 0.2794)
			(stroke
				(width 0.1)
				(type default)
			)
			(layer "B.Fab")
		)
		(fp_line
			(start -0.120396 0.3048)
			(end -0.120396 0.2794)
			(stroke
				(width 0.1)
				(type default)
			)
			(layer "B.Fab")
		)
		(fp_line
			(start 0.12065 -0.305054)
			(end 0.12065 -0.2794)
			(stroke
				(width 0.1)
				(type default)
			)
			(layer "B.Fab")
		)
		(fp_line
			(start 0.12065 -0.2794)
			(end -0.12065 -0.2794)
			(stroke
				(width 0.1)
				(type default)
			)
			(layer "B.Fab")
		)
		(fp_line
			(start 0.12065 0.2794)
			(end 0.12065 0.3048)
			(stroke
				(width 0.1)
				(type default)
			)
			(layer "B.Fab")
		)
		(fp_line
			(start 0.12065 0.3048)
			(end 0.67945 0.3048)
			(stroke
				(width 0.1)
				(type default)
			)
			(layer "B.Fab")
		)
		(fp_line
			(start 0.67945 -0.305054)
			(end 0.12065 -0.305054)
			(stroke
				(width 0.1)
				(type default)
			)
			(layer "B.Fab")
		)
		(fp_line
			(start 0.67945 0.3048)
			(end 0.67945 -0.305054)
			(stroke
				(width 0.1)
				(type default)
			)
			(layer "B.Fab")
		)
		(pad "1" smd circle
			(at 0.40005 0 180)
			(size 0 0)
			(layers "B.Cu" "B.Mask" "B.Paste")
			(net "SMB_P52V_PDB_SCL")
		)
		(pad "2" smd circle
			(at -0.40005 0 180)
			(size 0 0)
			(layers "B.Cu" "B.Mask" "B.Paste")
			(net "SMB_P52V_PDB_SCL_R4")
		)
	)
	(footprint ""
		(layer "B.Cu")
		(at 170.226736 -68.326 180)
		(property "Reference" "PR7027"
			(at 0 0 0)
			(layer "B.SilkS")
			(hide yes)
			(effects
				(font
					(size 1.27 1.27)
				)
				(justify mirror)
			)
		)
		(property "Value" ""
			(at 0 0 0)
			(layer "B.Fab")
			(effects
				(font
					(size 1.27 1.27)
				)
				(justify mirror)
			)
		)
		(duplicate_pad_numbers_are_jumpers no)
		(fp_line
			(start 0.7874 0.4064)
			(end 0.7874 -0.4064)
			(stroke
				(width 0.1524)
				(type default)
			)
			(layer "B.SilkS")
		)
		(fp_line
			(start 0.7874 -0.4064)
			(end -0.7874 -0.4064)
			(stroke
				(width 0.1524)
				(type default)
			)
			(layer "B.SilkS")
		)
		(fp_line
			(start -0.7874 0.4064)
			(end 0.7874 0.4064)
			(stroke
				(width 0.1524)
				(type default)
			)
			(layer "B.SilkS")
		)
		(fp_line
			(start -0.7874 -0.4064)
			(end -0.7874 0.4064)
			(stroke
				(width 0.1524)
				(type default)
			)
			(layer "B.SilkS")
		)
		(fp_line
			(start 0.67945 0.3048)
			(end 0.67945 -0.305054)
			(stroke
				(width 0.1)
				(type default)
			)
			(layer "B.Fab")
		)
		(fp_line
			(start 0.67945 -0.305054)
			(end 0.12065 -0.305054)
			(stroke
				(width 0.1)
				(type default)
			)
			(layer "B.Fab")
		)
		(fp_line
			(start 0.12065 0.3048)
			(end 0.67945 0.3048)
			(stroke
				(width 0.1)
				(type default)
			)
			(layer "B.Fab")
		)
		(fp_line
			(start 0.12065 0.2794)
			(end 0.12065 0.3048)
			(stroke
				(width 0.1)
				(type default)
			)
			(layer "B.Fab")
		)
		(fp_line
			(start 0.12065 -0.2794)
			(end -0.12065 -0.2794)
			(stroke
				(width 0.1)
				(type default)
			)
			(layer "B.Fab")
		)
		(fp_line
			(start 0.12065 -0.305054)
			(end 0.12065 -0.2794)
			(stroke
				(width 0.1)
				(type default)
			)
			(layer "B.Fab")
		)
		(fp_line
			(start -0.120396 0.3048)
			(end -0.120396 0.2794)
			(stroke
				(width 0.1)
				(type default)
			)
			(layer "B.Fab")
		)
		(fp_line
			(start -0.120396 0.2794)
			(end 0.12065 0.2794)
			(stroke
				(width 0.1)
				(type default)
			)
			(layer "B.Fab")
		)
		(fp_line
			(start -0.12065 -0.2794)
			(end -0.12065 -0.3048)
			(stroke
				(width 0.1)
				(type default)
			)
			(layer "B.Fab")
		)
		(fp_line
			(start -0.12065 -0.3048)
			(end -0.67945 -0.3048)
			(stroke
				(width 0.1)
				(type default)
			)
			(layer "B.Fab")
		)
		(fp_line
			(start -0.67945 0.3048)
			(end -0.120396 0.3048)
			(stroke
				(width 0.1)
				(type default)
			)
			(layer "B.Fab")
		)
		(fp_line
			(start -0.67945 -0.3048)
			(end -0.67945 0.3048)
			(stroke
				(width 0.1)
				(type default)
			)
			(layer "B.Fab")
		)
		(pad "1" smd circle
			(at 0.40005 0)
			(size 0 0)
			(layers "B.Cu" "B.Mask" "B.Paste")
			(net "P52V_HS2_ISTART")
		)
		(pad "2" smd circle
			(at -0.40005 0)
			(size 0 0)
			(layers "B.Cu" "B.Mask" "B.Paste")
			(net "P52V_HS2_VCAP")
		)
	)
	(footprint ""
		(layer "B.Cu")
		(at 106.1974 -45.7454 180)
		(property "Reference" "PC593"
			(at 0 0 0)
			(layer "B.SilkS")
			(hide yes)
			(effects
				(font
					(size 1.27 1.27)
				)
				(justify mirror)
			)
		)
		(property "Value" ""
			(at 0 0 0)
			(layer "B.Fab")
			(effects
				(font
					(size 1.27 1.27)
				)
				(justify mirror)
			)
		)
		(duplicate_pad_numbers_are_jumpers no)
		(fp_line
			(start 1.2954 0.5842)
			(end 1.2954 -0.5842)
			(stroke
				(width 0.1524)
				(type default)
			)
			(layer "B.SilkS")
		)
		(fp_line
			(start 1.2954 -0.5842)
			(end -1.2954 -0.5842)
			(stroke
				(width 0.1524)
				(type default)
			)
			(layer "B.SilkS")
		)
		(fp_line
			(start -1.2954 0.5842)
			(end 1.2954 0.5842)
			(stroke
				(width 0.1524)
				(type default)
			)
			(layer "B.SilkS")
		)
		(fp_line
			(start -1.2954 -0.5842)
			(end -1.2954 0.5842)
			(stroke
				(width 0.1524)
				(type default)
			)
			(layer "B.SilkS")
		)
		(fp_line
			(start 1.1938 0.4064)
			(end 1.1938 -0.4064)
			(stroke
				(width 0.1)
				(type default)
			)
			(layer "B.Fab")
		)
		(fp_line
			(start 1.1938 -0.4064)
			(end 0.8636 -0.4064)
			(stroke
				(width 0.1)
				(type default)
			)
			(layer "B.Fab")
		)
		(fp_line
			(start 0.8636 0.4572)
			(end 0.8636 0.4064)
			(stroke
				(width 0.1)
				(type default)
			)
			(layer "B.Fab")
		)
		(fp_line
			(start 0.8636 0.4064)
			(end 1.1938 0.4064)
			(stroke
				(width 0.1)
				(type default)
			)
			(layer "B.Fab")
		)
		(fp_line
			(start 0.8636 -0.4064)
			(end 0.8636 -0.4572)
			(stroke
				(width 0.1)
				(type default)
			)
			(layer "B.Fab")
		)
		(fp_line
			(start 0.8636 -0.4572)
			(end -0.8636 -0.4572)
			(stroke
				(width 0.1)
				(type default)
			)
			(layer "B.Fab")
		)
		(fp_line
			(start -0.8636 0.4572)
			(end 0.8636 0.4572)
			(stroke
				(width 0.1)
				(type default)
			)
			(layer "B.Fab")
		)
		(fp_line
			(start -0.8636 0.4064)
			(end -0.8636 0.4572)
			(stroke
				(width 0.1)
				(type default)
			)
			(layer "B.Fab")
		)
		(fp_line
			(start -0.8636 -0.4064)
			(end -1.1938 -0.4064)
			(stroke
				(width 0.1)
				(type default)
			)
			(layer "B.Fab")
		)
		(fp_line
			(start -0.8636 -0.4572)
			(end -0.8636 -0.4064)
			(stroke
				(width 0.1)
				(type default)
			)
			(layer "B.Fab")
		)
		(fp_line
			(start -1.1938 0.4064)
			(end -0.8636 0.4064)
			(stroke
				(width 0.1)
				(type default)
			)
			(layer "B.Fab")
		)
		(fp_line
			(start -1.1938 -0.4064)
			(end -1.1938 0.4064)
			(stroke
				(width 0.1)
				(type default)
			)
			(layer "B.Fab")
		)
		(pad "1" smd rect
			(at 0.7366 0 90)
			(size 0.7112 0.8128)
			(layers "B.Cu" "B.Mask" "B.Paste")
			(net "GND")
		)
		(pad "2" smd rect
			(at -0.7366 0 90)
			(size 0.7112 0.8128)
			(layers "B.Cu" "B.Mask" "B.Paste")
			(net "P52V_HS2_GATE2_R1")
		)
	)
	(footprint ""
		(layer "B.Cu")
		(at 154.097736 -76.835 180)
		(property "Reference" "PC600"
			(at 0 0 0)
			(layer "B.SilkS")
			(hide yes)
			(effects
				(font
					(size 1.27 1.27)
				)
				(justify mirror)
			)
		)
		(property "Value" ""
			(at 0 0 0)
			(layer "B.Fab")
			(effects
				(font
					(size 1.27 1.27)
				)
				(justify mirror)
			)
		)
		(duplicate_pad_numbers_are_jumpers no)
		(fp_line
			(start 0.7874 0.4064)
			(end 0.7874 -0.4064)
			(stroke
				(width 0.1524)
				(type default)
			)
			(layer "B.SilkS")
		)
		(fp_line
			(start 0.7874 -0.4064)
			(end -0.7874 -0.4064)
			(stroke
				(width 0.1524)
				(type default)
			)
			(layer "B.SilkS")
		)
		(fp_line
			(start -0.7874 0.4064)
			(end 0.7874 0.4064)
			(stroke
				(width 0.1524)
				(type default)
			)
			(layer "B.SilkS")
		)
		(fp_line
			(start -0.7874 -0.4064)
			(end -0.7874 0.4064)
			(stroke
				(width 0.1524)
				(type default)
			)
			(layer "B.SilkS")
		)
		(fp_line
			(start 0.67945 0.3048)
			(end 0.67945 -0.305054)
			(stroke
				(width 0.1)
				(type default)
			)
			(layer "B.Fab")
		)
		(fp_line
			(start 0.67945 -0.305054)
			(end 0.12065 -0.305054)
			(stroke
				(width 0.1)
				(type default)
			)
			(layer "B.Fab")
		)
		(fp_line
			(start 0.12065 0.3048)
			(end 0.67945 0.3048)
			(stroke
				(width 0.1)
				(type default)
			)
			(layer "B.Fab")
		)
		(fp_line
			(start 0.12065 0.2794)
			(end 0.12065 0.3048)
			(stroke
				(width 0.1)
				(type default)
			)
			(layer "B.Fab")
		)
		(fp_line
			(start 0.12065 -0.2794)
			(end -0.12065 -0.2794)
			(stroke
				(width 0.1)
				(type default)
			)
			(layer "B.Fab")
		)
		(fp_line
			(start 0.12065 -0.305054)
			(end 0.12065 -0.2794)
			(stroke
				(width 0.1)
				(type default)
			)
			(layer "B.Fab")
		)
		(fp_line
			(start -0.120396 0.3048)
			(end -0.120396 0.2794)
			(stroke
				(width 0.1)
				(type default)
			)
			(layer "B.Fab")
		)
		(fp_line
			(start -0.120396 0.2794)
			(end 0.12065 0.2794)
			(stroke
				(width 0.1)
				(type default)
			)
			(layer "B.Fab")
		)
		(fp_line
			(start -0.12065 -0.2794)
			(end -0.12065 -0.3048)
			(stroke
				(width 0.1)
				(type default)
			)
			(layer "B.Fab")
		)
		(fp_line
			(start -0.12065 -0.3048)
			(end -0.67945 -0.3048)
			(stroke
				(width 0.1)
				(type default)
			)
			(layer "B.Fab")
		)
		(fp_line
			(start -0.67945 0.3048)
			(end -0.120396 0.3048)
			(stroke
				(width 0.1)
				(type default)
			)
			(layer "B.Fab")
		)
		(fp_line
			(start -0.67945 -0.3048)
			(end -0.67945 0.3048)
			(stroke
				(width 0.1)
				(type default)
			)
			(layer "B.Fab")
		)
		(pad "1" smd circle
			(at 0.40005 0)
			(size 0 0)
			(layers "B.Cu" "B.Mask" "B.Paste")
			(net "GND1_FIELD_SIGNAL")
		)
		(pad "2" smd circle
			(at -0.40005 0)
			(size 0 0)
			(layers "B.Cu" "B.Mask" "B.Paste")
			(net "P52V_HS2_DVCC")
		)
	)
	(footprint ""
		(layer "B.Cu")
		(at 260.6294 -51.689 180)
		(property "Reference" "C69"
			(at 0 0 0)
			(layer "B.SilkS")
			(hide yes)
			(effects
				(font
					(size 1.27 1.27)
				)
				(justify mirror)
			)
		)
		(property "Value" ""
			(at 0 0 0)
			(layer "B.Fab")
			(effects
				(font
					(size 1.27 1.27)
				)
				(justify mirror)
			)
		)
		(duplicate_pad_numbers_are_jumpers no)
		(fp_line
			(start 1.2954 0.5842)
			(end 1.2954 -0.5842)
			(stroke
				(width 0.1524)
				(type default)
			)
			(layer "B.SilkS")
		)
		(fp_line
			(start 1.2954 -0.5842)
			(end -1.2954 -0.5842)
			(stroke
				(width 0.1524)
				(type default)
			)
			(layer "B.SilkS")
		)
		(fp_line
			(start -1.2954 0.5842)
			(end 1.2954 0.5842)
			(stroke
				(width 0.1524)
				(type default)
			)
			(layer "B.SilkS")
		)
		(fp_line
			(start -1.2954 -0.5842)
			(end -1.2954 0.5842)
			(stroke
				(width 0.1524)
				(type default)
			)
			(layer "B.SilkS")
		)
		(fp_line
			(start 1.1938 0.4064)
			(end 1.1938 -0.4064)
			(stroke
				(width 0.1)
				(type default)
			)
			(layer "B.Fab")
		)
		(fp_line
			(start 1.1938 -0.4064)
			(end 0.8636 -0.4064)
			(stroke
				(width 0.1)
				(type default)
			)
			(layer "B.Fab")
		)
		(fp_line
			(start 0.8636 0.4572)
			(end 0.8636 0.4064)
			(stroke
				(width 0.1)
				(type default)
			)
			(layer "B.Fab")
		)
		(fp_line
			(start 0.8636 0.4064)
			(end 1.1938 0.4064)
			(stroke
				(width 0.1)
				(type default)
			)
			(layer "B.Fab")
		)
		(fp_line
			(start 0.8636 -0.4064)
			(end 0.8636 -0.4572)
			(stroke
				(width 0.1)
				(type default)
			)
			(layer "B.Fab")
		)
		(fp_line
			(start 0.8636 -0.4572)
			(end -0.8636 -0.4572)
			(stroke
				(width 0.1)
				(type default)
			)
			(layer "B.Fab")
		)
		(fp_line
			(start -0.8636 0.4572)
			(end 0.8636 0.4572)
			(stroke
				(width 0.1)
				(type default)
			)
			(layer "B.Fab")
		)
		(fp_line
			(start -0.8636 0.4064)
			(end -0.8636 0.4572)
			(stroke
				(width 0.1)
				(type default)
			)
			(layer "B.Fab")
		)
		(fp_line
			(start -0.8636 -0.4064)
			(end -1.1938 -0.4064)
			(stroke
				(width 0.1)
				(type default)
			)
			(layer "B.Fab")
		)
		(fp_line
			(start -0.8636 -0.4572)
			(end -0.8636 -0.4064)
			(stroke
				(width 0.1)
				(type default)
			)
			(layer "B.Fab")
		)
		(fp_line
			(start -1.1938 0.4064)
			(end -0.8636 0.4064)
			(stroke
				(width 0.1)
				(type default)
			)
			(layer "B.Fab")
		)
		(fp_line
			(start -1.1938 -0.4064)
			(end -1.1938 0.4064)
			(stroke
				(width 0.1)
				(type default)
			)
			(layer "B.Fab")
		)
		(pad "1" smd rect
			(at 0.7366 0 90)
			(size 0.7112 0.8128)
			(layers "B.Cu" "B.Mask" "B.Paste")
			(net "FM_HS1_EN_FUSE")
		)
		(pad "2" smd rect
			(at -0.7366 0 90)
			(size 0.7112 0.8128)
			(layers "B.Cu" "B.Mask" "B.Paste")
			(net "GND")
		)
	)
	(footprint ""
		(layer "B.Cu")
		(at 285.9024 -71.882 180)
		(property "Reference" "R5869"
			(at 0 0 0)
			(layer "B.SilkS")
			(hide yes)
			(effects
				(font
					(size 1.27 1.27)
				)
				(justify mirror)
			)
		)
		(property "Value" ""
			(at 0 0 0)
			(layer "B.Fab")
			(effects
				(font
					(size 1.27 1.27)
				)
				(justify mirror)
			)
		)
		(duplicate_pad_numbers_are_jumpers no)
		(fp_line
			(start 0.7874 0.4064)
			(end 0.7874 -0.4064)
			(stroke
				(width 0.1524)
				(type default)
			)
			(layer "B.SilkS")
		)
		(fp_line
			(start 0.7874 -0.4064)
			(end -0.7874 -0.4064)
			(stroke
				(width 0.1524)
				(type default)
			)
			(layer "B.SilkS")
		)
		(fp_line
			(start -0.7874 0.4064)
			(end 0.7874 0.4064)
			(stroke
				(width 0.1524)
				(type default)
			)
			(layer "B.SilkS")
		)
		(fp_line
			(start -0.7874 -0.4064)
			(end -0.7874 0.4064)
			(stroke
				(width 0.1524)
				(type default)
			)
			(layer "B.SilkS")
		)
		(fp_line
			(start 0.67945 0.3048)
			(end 0.67945 -0.305054)
			(stroke
				(width 0.1)
				(type default)
			)
			(layer "B.Fab")
		)
		(fp_line
			(start 0.67945 -0.305054)
			(end 0.12065 -0.305054)
			(stroke
				(width 0.1)
				(type default)
			)
			(layer "B.Fab")
		)
		(fp_line
			(start 0.12065 0.3048)
			(end 0.67945 0.3048)
			(stroke
				(width 0.1)
				(type default)
			)
			(layer "B.Fab")
		)
		(fp_line
			(start 0.12065 0.2794)
			(end 0.12065 0.3048)
			(stroke
				(width 0.1)
				(type default)
			)
			(layer "B.Fab")
		)
		(fp_line
			(start 0.12065 -0.2794)
			(end -0.12065 -0.2794)
			(stroke
				(width 0.1)
				(type default)
			)
			(layer "B.Fab")
		)
		(fp_line
			(start 0.12065 -0.305054)
			(end 0.12065 -0.2794)
			(stroke
				(width 0.1)
				(type default)
			)
			(layer "B.Fab")
		)
		(fp_line
			(start -0.120396 0.3048)
			(end -0.120396 0.2794)
			(stroke
				(width 0.1)
				(type default)
			)
			(layer "B.Fab")
		)
		(fp_line
			(start -0.120396 0.2794)
			(end 0.12065 0.2794)
			(stroke
				(width 0.1)
				(type default)
			)
			(layer "B.Fab")
		)
		(fp_line
			(start -0.12065 -0.2794)
			(end -0.12065 -0.3048)
			(stroke
				(width 0.1)
				(type default)
			)
			(layer "B.Fab")
		)
		(fp_line
			(start -0.12065 -0.3048)
			(end -0.67945 -0.3048)
			(stroke
				(width 0.1)
				(type default)
			)
			(layer "B.Fab")
		)
		(fp_line
			(start -0.67945 0.3048)
			(end -0.120396 0.3048)
			(stroke
				(width 0.1)
				(type default)
			)
			(layer "B.Fab")
		)
		(fp_line
			(start -0.67945 -0.3048)
			(end -0.67945 0.3048)
			(stroke
				(width 0.1)
				(type default)
			)
			(layer "B.Fab")
		)
		(pad "1" smd circle
			(at 0.40005 0)
			(size 0 0)
			(layers "B.Cu" "B.Mask" "B.Paste")
			(net "SMB_P52V_PDB_SCL")
		)
		(pad "2" smd circle
			(at -0.40005 0)
			(size 0 0)
			(layers "B.Cu" "B.Mask" "B.Paste")
			(net "SMB_P52V_PDB_SCL_R3")
		)
	)
	(footprint ""
		(layer "B.Cu")
		(at 159.939736 -71.628 180)
		(property "Reference" "PR7006"
			(at 0 0 0)
			(layer "B.SilkS")
			(hide yes)
			(effects
				(font
					(size 1.27 1.27)
				)
				(justify mirror)
			)
		)
		(property "Value" ""
			(at 0 0 0)
			(layer "B.Fab")
			(effects
				(font
					(size 1.27 1.27)
				)
				(justify mirror)
			)
		)
		(duplicate_pad_numbers_are_jumpers no)
		(fp_line
			(start 0.7874 0.4064)
			(end 0.7874 -0.4064)
			(stroke
				(width 0.1524)
				(type default)
			)
			(layer "B.SilkS")
		)
		(fp_line
			(start 0.7874 -0.4064)
			(end -0.7874 -0.4064)
			(stroke
				(width 0.1524)
				(type default)
			)
			(layer "B.SilkS")
		)
		(fp_line
			(start -0.7874 0.4064)
			(end 0.7874 0.4064)
			(stroke
				(width 0.1524)
				(type default)
			)
			(layer "B.SilkS")
		)
		(fp_line
			(start -0.7874 -0.4064)
			(end -0.7874 0.4064)
			(stroke
				(width 0.1524)
				(type default)
			)
			(layer "B.SilkS")
		)
		(fp_line
			(start 0.67945 0.3048)
			(end 0.67945 -0.305054)
			(stroke
				(width 0.1)
				(type default)
			)
			(layer "B.Fab")
		)
		(fp_line
			(start 0.67945 -0.305054)
			(end 0.12065 -0.305054)
			(stroke
				(width 0.1)
				(type default)
			)
			(layer "B.Fab")
		)
		(fp_line
			(start 0.12065 0.3048)
			(end 0.67945 0.3048)
			(stroke
				(width 0.1)
				(type default)
			)
			(layer "B.Fab")
		)
		(fp_line
			(start 0.12065 0.2794)
			(end 0.12065 0.3048)
			(stroke
				(width 0.1)
				(type default)
			)
			(layer "B.Fab")
		)
		(fp_line
			(start 0.12065 -0.2794)
			(end -0.12065 -0.2794)
			(stroke
				(width 0.1)
				(type default)
			)
			(layer "B.Fab")
		)
		(fp_line
			(start 0.12065 -0.305054)
			(end 0.12065 -0.2794)
			(stroke
				(width 0.1)
				(type default)
			)
			(layer "B.Fab")
		)
		(fp_line
			(start -0.120396 0.3048)
			(end -0.120396 0.2794)
			(stroke
				(width 0.1)
				(type default)
			)
			(layer "B.Fab")
		)
		(fp_line
			(start -0.120396 0.2794)
			(end 0.12065 0.2794)
			(stroke
				(width 0.1)
				(type default)
			)
			(layer "B.Fab")
		)
		(fp_line
			(start -0.12065 -0.2794)
			(end -0.12065 -0.3048)
			(stroke
				(width 0.1)
				(type default)
			)
			(layer "B.Fab")
		)
		(fp_line
			(start -0.12065 -0.3048)
			(end -0.67945 -0.3048)
			(stroke
				(width 0.1)
				(type default)
			)
			(layer "B.Fab")
		)
		(fp_line
			(start -0.67945 0.3048)
			(end -0.120396 0.3048)
			(stroke
				(width 0.1)
				(type default)
			)
			(layer "B.Fab")
		)
		(fp_line
			(start -0.67945 -0.3048)
			(end -0.67945 0.3048)
			(stroke
				(width 0.1)
				(type default)
			)
			(layer "B.Fab")
		)
		(pad "1" smd circle
			(at 0.40005 0)
			(size 0 0)
			(layers "B.Cu" "B.Mask" "B.Paste")
			(net "P52V_HS2_SIO")
		)
		(pad "2" smd circle
			(at -0.40005 0)
			(size 0 0)
			(layers "B.Cu" "B.Mask" "B.Paste")
			(net "P52V_HS2_INTVCC")
		)
	)
	(footprint ""
		(layer "B.Cu")
		(at 278.7904 -73.533 180)
		(property "Reference" "PR6933"
			(at 0 0 0)
			(layer "B.SilkS")
			(hide yes)
			(effects
				(font
					(size 1.27 1.27)
				)
				(justify mirror)
			)
		)
		(property "Value" ""
			(at 0 0 0)
			(layer "B.Fab")
			(effects
				(font
					(size 1.27 1.27)
				)
				(justify mirror)
			)
		)
		(duplicate_pad_numbers_are_jumpers no)
		(fp_line
			(start 0.7874 0.4064)
			(end 0.7874 -0.4064)
			(stroke
				(width 0.1524)
				(type default)
			)
			(layer "B.SilkS")
		)
		(fp_line
			(start 0.7874 -0.4064)
			(end -0.7874 -0.4064)
			(stroke
				(width 0.1524)
				(type default)
			)
			(layer "B.SilkS")
		)
		(fp_line
			(start -0.7874 0.4064)
			(end 0.7874 0.4064)
			(stroke
				(width 0.1524)
				(type default)
			)
			(layer "B.SilkS")
		)
		(fp_line
			(start -0.7874 -0.4064)
			(end -0.7874 0.4064)
			(stroke
				(width 0.1524)
				(type default)
			)
			(layer "B.SilkS")
		)
		(fp_line
			(start 0.67945 0.3048)
			(end 0.67945 -0.305054)
			(stroke
				(width 0.1)
				(type default)
			)
			(layer "B.Fab")
		)
		(fp_line
			(start 0.67945 -0.305054)
			(end 0.12065 -0.305054)
			(stroke
				(width 0.1)
				(type default)
			)
			(layer "B.Fab")
		)
		(fp_line
			(start 0.12065 0.3048)
			(end 0.67945 0.3048)
			(stroke
				(width 0.1)
				(type default)
			)
			(layer "B.Fab")
		)
		(fp_line
			(start 0.12065 0.2794)
			(end 0.12065 0.3048)
			(stroke
				(width 0.1)
				(type default)
			)
			(layer "B.Fab")
		)
		(fp_line
			(start 0.12065 -0.2794)
			(end -0.12065 -0.2794)
			(stroke
				(width 0.1)
				(type default)
			)
			(layer "B.Fab")
		)
		(fp_line
			(start 0.12065 -0.305054)
			(end 0.12065 -0.2794)
			(stroke
				(width 0.1)
				(type default)
			)
			(layer "B.Fab")
		)
		(fp_line
			(start -0.120396 0.3048)
			(end -0.120396 0.2794)
			(stroke
				(width 0.1)
				(type default)
			)
			(layer "B.Fab")
		)
		(fp_line
			(start -0.120396 0.2794)
			(end 0.12065 0.2794)
			(stroke
				(width 0.1)
				(type default)
			)
			(layer "B.Fab")
		)
		(fp_line
			(start -0.12065 -0.2794)
			(end -0.12065 -0.3048)
			(stroke
				(width 0.1)
				(type default)
			)
			(layer "B.Fab")
		)
		(fp_line
			(start -0.12065 -0.3048)
			(end -0.67945 -0.3048)
			(stroke
				(width 0.1)
				(type default)
			)
			(layer "B.Fab")
		)
		(fp_line
			(start -0.67945 0.3048)
			(end -0.120396 0.3048)
			(stroke
				(width 0.1)
				(type default)
			)
			(layer "B.Fab")
		)
		(fp_line
			(start -0.67945 -0.3048)
			(end -0.67945 0.3048)
			(stroke
				(width 0.1)
				(type default)
			)
			(layer "B.Fab")
		)
		(pad "1" smd circle
			(at 0.40005 0)
			(size 0 0)
			(layers "B.Cu" "B.Mask" "B.Paste")
			(net "P52V_HS1_ISET")
		)
		(pad "2" smd circle
			(at -0.40005 0)
			(size 0 0)
			(layers "B.Cu" "B.Mask" "B.Paste")
			(net "P52V_HS1_VCAP")
		)
	)
	(footprint ""
		(layer "B.Cu")
		(at 338.8614 -50.5206 -90)
		(property "Reference" "PD15"
			(at 4.0386 1.57607 270)
			(unlocked yes)
			(layer "B.SilkS")
			(effects
				(font
					(size 0.7874 0.5842)
					(thickness 0.1524)
				)
				(justify left mirror)
			)
		)
		(property "Value" ""
			(at 0 0 90)
			(layer "B.Fab")
			(effects
				(font
					(size 1.27 1.27)
				)
				(justify mirror)
			)
		)
		(duplicate_pad_numbers_are_jumpers no)
		(fp_line
			(start -2.032 0.7112)
			(end 1.651 0.7112)
			(stroke
				(width 0.1524)
				(type default)
			)
			(layer "B.SilkS")
		)
		(fp_line
			(start 1.651 0.7112)
			(end 1.651 -0.7112)
			(stroke
				(width 0.1524)
				(type default)
			)
			(layer "B.SilkS")
		)
		(fp_line
			(start -1.778 0.6858)
			(end -1.778 -0.6858)
			(stroke
				(width 0.1524)
				(type default)
			)
			(layer "B.SilkS")
		)
		(fp_line
			(start 0.299974 0.500126)
			(end -0.199898 0)
			(stroke
				(width 0.1524)
				(type default)
			)
			(layer "B.SilkS")
		)
		(fp_line
			(start -0.199898 0)
			(end 0.299974 -0.500126)
			(stroke
				(width 0.1524)
				(type default)
			)
			(layer "B.SilkS")
		)
		(fp_line
			(start -0.299974 -0.500126)
			(end -0.299974 0.500126)
			(stroke
				(width 0.1524)
				(type default)
			)
			(layer "B.SilkS")
		)
		(fp_line
			(start 0.299974 -0.500126)
			(end 0.299974 0.500126)
			(stroke
				(width 0.1524)
				(type default)
			)
			(layer "B.SilkS")
		)
		(fp_line
			(start -1.905 -0.6858)
			(end -1.905 0.6858)
			(stroke
				(width 0.1524)
				(type default)
			)
			(layer "B.SilkS")
		)
		(fp_line
			(start -1.651 -0.6858)
			(end -1.651 0.6858)
			(stroke
				(width 0.1524)
				(type default)
			)
			(layer "B.SilkS")
		)
		(fp_line
			(start -2.032 -0.7112)
			(end -2.032 0.7112)
			(stroke
				(width 0.1524)
				(type default)
			)
			(layer "B.SilkS")
		)
		(fp_line
			(start 1.651 -0.7112)
			(end -2.032 -0.7112)
			(stroke
				(width 0.1524)
				(type default)
			)
			(layer "B.SilkS")
		)
		(fp_line
			(start -0.899922 0.700024)
			(end 0.899922 0.700024)
			(stroke
				(width 0.1)
				(type default)
			)
			(layer "B.Fab")
		)
		(fp_line
			(start 0.899922 0.700024)
			(end 0.899922 0.175006)
			(stroke
				(width 0.1)
				(type default)
			)
			(layer "B.Fab")
		)
		(fp_line
			(start 0.299974 0.500126)
			(end -0.199898 0)
			(stroke
				(width 0.1)
				(type default)
			)
			(layer "B.Fab")
		)
		(fp_line
			(start -1.35001 0.175006)
			(end -0.899922 0.175006)
			(stroke
				(width 0.1)
				(type default)
			)
			(layer "B.Fab")
		)
		(fp_line
			(start -0.899922 0.175006)
			(end -0.899922 0.700024)
			(stroke
				(width 0.1)
				(type default)
			)
			(layer "B.Fab")
		)
		(fp_line
			(start 0.899922 0.175006)
			(end 1.35001 0.175006)
			(stroke
				(width 0.1)
				(type default)
			)
			(layer "B.Fab")
		)
		(fp_line
			(start 1.35001 0.175006)
			(end 1.35001 -0.225044)
			(stroke
				(width 0.1)
				(type default)
			)
			(layer "B.Fab")
		)
		(fp_line
			(start -0.199898 0)
			(end 0.299974 -0.500126)
			(stroke
				(width 0.1)
				(type default)
			)
			(layer "B.Fab")
		)
		(fp_line
			(start -1.35001 -0.225044)
			(end -1.35001 0.175006)
			(stroke
				(width 0.1)
				(type default)
			)
			(layer "B.Fab")
		)
		(fp_line
			(start -0.899922 -0.225044)
			(end -1.35001 -0.225044)
			(stroke
				(width 0.1)
				(type default)
			)
			(layer "B.Fab")
		)
		(fp_line
			(start 0.899922 -0.225044)
			(end 0.899922 -0.700024)
			(stroke
				(width 0.1)
				(type default)
			)
			(layer "B.Fab")
		)
		(fp_line
			(start 1.35001 -0.225044)
			(end 0.899922 -0.225044)
			(stroke
				(width 0.1)
				(type default)
			)
			(layer "B.Fab")
		)
		(fp_line
			(start -0.299974 -0.500126)
			(end -0.299974 0.500126)
			(stroke
				(width 0.1)
				(type default)
			)
			(layer "B.Fab")
		)
		(fp_line
			(start 0.299974 -0.500126)
			(end 0.299974 0.500126)
			(stroke
				(width 0.1)
				(type default)
			)
			(layer "B.Fab")
		)
		(fp_line
			(start -0.899922 -0.700024)
			(end -0.899922 -0.225044)
			(stroke
				(width 0.1)
				(type default)
			)
			(layer "B.Fab")
		)
		(fp_line
			(start 0.899922 -0.700024)
			(end -0.899922 -0.700024)
			(stroke
				(width 0.1)
				(type default)
			)
			(layer "B.Fab")
		)
		(fp_text user "-"
			(at -1.8288 -0.24765 270)
			(unlocked yes)
			(layer "B.SilkS")
			(effects
				(font
					(size 1.905 1.4224)
					(thickness 0.1524)
				)
				(justify left mirror)
			)
		)
		(fp_text user "+"
			(at 2.8956 -0.70485 270)
			(unlocked yes)
			(layer "B.SilkS")
			(effects
				(font
					(size 1.905 1.4224)
					(thickness 0.1524)
				)
				(justify left mirror)
			)
		)
		(fp_text user "+"
			(at 2.794 -0.19685 270)
			(unlocked yes)
			(layer "B.Fab")
			(effects
				(font
					(size 1.905 1.4224)
					(thickness 0.1524)
				)
				(justify left mirror)
			)
		)
		(fp_text user "-"
			(at -1.8288 -0.24765 270)
			(unlocked yes)
			(layer "B.Fab")
			(effects
				(font
					(size 1.905 1.4224)
					(thickness 0.1524)
				)
				(justify left mirror)
			)
		)
		(pad "1" smd rect
			(at 1.0922 0 270)
			(size 0.8128 0.8636)
			(layers "B.Cu" "B.Mask" "B.Paste")
			(net "P52V_HS1_4287_GATE_R")
		)
		(pad "2" smd rect
			(at -1.0922 0 90)
			(size 0.8128 0.8636)
			(layers "B.Cu" "B.Mask" "B.Paste")
			(net "P52V_HS1_GATE_R1")
		)
	)
	(footprint ""
		(layer "B.Cu")
		(at 413.639 -36.195 180)
		(property "Reference" "R5935"
			(at 0 0 0)
			(layer "B.SilkS")
			(hide yes)
			(effects
				(font
					(size 1.27 1.27)
				)
				(justify mirror)
			)
		)
		(property "Value" ""
			(at 0 0 0)
			(layer "B.Fab")
			(effects
				(font
					(size 1.27 1.27)
				)
				(justify mirror)
			)
		)
		(duplicate_pad_numbers_are_jumpers no)
		(fp_line
			(start 0.7874 0.4064)
			(end 0.7874 -0.4064)
			(stroke
				(width 0.1524)
				(type default)
			)
			(layer "B.SilkS")
		)
		(fp_line
			(start 0.7874 -0.4064)
			(end -0.7874 -0.4064)
			(stroke
				(width 0.1524)
				(type default)
			)
			(layer "B.SilkS")
		)
		(fp_line
			(start -0.7874 0.4064)
			(end 0.7874 0.4064)
			(stroke
				(width 0.1524)
				(type default)
			)
			(layer "B.SilkS")
		)
		(fp_line
			(start -0.7874 -0.4064)
			(end -0.7874 0.4064)
			(stroke
				(width 0.1524)
				(type default)
			)
			(layer "B.SilkS")
		)
		(fp_line
			(start 0.67945 0.3048)
			(end 0.67945 -0.305054)
			(stroke
				(width 0.1)
				(type default)
			)
			(layer "B.Fab")
		)
		(fp_line
			(start 0.67945 -0.305054)
			(end 0.12065 -0.305054)
			(stroke
				(width 0.1)
				(type default)
			)
			(layer "B.Fab")
		)
		(fp_line
			(start 0.12065 0.3048)
			(end 0.67945 0.3048)
			(stroke
				(width 0.1)
				(type default)
			)
			(layer "B.Fab")
		)
		(fp_line
			(start 0.12065 0.2794)
			(end 0.12065 0.3048)
			(stroke
				(width 0.1)
				(type default)
			)
			(layer "B.Fab")
		)
		(fp_line
			(start 0.12065 -0.2794)
			(end -0.12065 -0.2794)
			(stroke
				(width 0.1)
				(type default)
			)
			(layer "B.Fab")
		)
		(fp_line
			(start 0.12065 -0.305054)
			(end 0.12065 -0.2794)
			(stroke
				(width 0.1)
				(type default)
			)
			(layer "B.Fab")
		)
		(fp_line
			(start -0.120396 0.3048)
			(end -0.120396 0.2794)
			(stroke
				(width 0.1)
				(type default)
			)
			(layer "B.Fab")
		)
		(fp_line
			(start -0.120396 0.2794)
			(end 0.12065 0.2794)
			(stroke
				(width 0.1)
				(type default)
			)
			(layer "B.Fab")
		)
		(fp_line
			(start -0.12065 -0.2794)
			(end -0.12065 -0.3048)
			(stroke
				(width 0.1)
				(type default)
			)
			(layer "B.Fab")
		)
		(fp_line
			(start -0.12065 -0.3048)
			(end -0.67945 -0.3048)
			(stroke
				(width 0.1)
				(type default)
			)
			(layer "B.Fab")
		)
		(fp_line
			(start -0.67945 0.3048)
			(end -0.120396 0.3048)
			(stroke
				(width 0.1)
				(type default)
			)
			(layer "B.Fab")
		)
		(fp_line
			(start -0.67945 -0.3048)
			(end -0.67945 0.3048)
			(stroke
				(width 0.1)
				(type default)
			)
			(layer "B.Fab")
		)
		(pad "1" smd circle
			(at 0.40005 0)
			(size 0 0)
			(layers "B.Cu" "B.Mask" "B.Paste")
			(net "P3V3_AUX")
		)
		(pad "2" smd circle
			(at -0.40005 0)
			(size 0 0)
			(layers "B.Cu" "B.Mask" "B.Paste")
			(net "PCA9555_2_A1")
		)
	)
	(footprint ""
		(layer "B.Cu")
		(at 175.306736 -77.851)
		(property "Reference" "R5881"
			(at 0 0 0)
			(layer "B.SilkS")
			(hide yes)
			(effects
				(font
					(size 1.27 1.27)
				)
				(justify mirror)
			)
		)
		(property "Value" ""
			(at 0 0 0)
			(layer "B.Fab")
			(effects
				(font
					(size 1.27 1.27)
				)
				(justify mirror)
			)
		)
		(duplicate_pad_numbers_are_jumpers no)
		(fp_line
			(start -0.7874 -0.4064)
			(end -0.7874 0.4064)
			(stroke
				(width 0.1524)
				(type default)
			)
			(layer "B.SilkS")
		)
		(fp_line
			(start -0.7874 0.4064)
			(end 0.7874 0.4064)
			(stroke
				(width 0.1524)
				(type default)
			)
			(layer "B.SilkS")
		)
		(fp_line
			(start 0.7874 -0.4064)
			(end -0.7874 -0.4064)
			(stroke
				(width 0.1524)
				(type default)
			)
			(layer "B.SilkS")
		)
		(fp_line
			(start 0.7874 0.4064)
			(end 0.7874 -0.4064)
			(stroke
				(width 0.1524)
				(type default)
			)
			(layer "B.SilkS")
		)
		(fp_line
			(start -0.67945 -0.3048)
			(end -0.67945 0.3048)
			(stroke
				(width 0.1)
				(type default)
			)
			(layer "B.Fab")
		)
		(fp_line
			(start -0.67945 0.3048)
			(end -0.120396 0.3048)
			(stroke
				(width 0.1)
				(type default)
			)
			(layer "B.Fab")
		)
		(fp_line
			(start -0.12065 -0.3048)
			(end -0.67945 -0.3048)
			(stroke
				(width 0.1)
				(type default)
			)
			(layer "B.Fab")
		)
		(fp_line
			(start -0.12065 -0.2794)
			(end -0.12065 -0.3048)
			(stroke
				(width 0.1)
				(type default)
			)
			(layer "B.Fab")
		)
		(fp_line
			(start -0.120396 0.2794)
			(end 0.12065 0.2794)
			(stroke
				(width 0.1)
				(type default)
			)
			(layer "B.Fab")
		)
		(fp_line
			(start -0.120396 0.3048)
			(end -0.120396 0.2794)
			(stroke
				(width 0.1)
				(type default)
			)
			(layer "B.Fab")
		)
		(fp_line
			(start 0.12065 -0.305054)
			(end 0.12065 -0.2794)
			(stroke
				(width 0.1)
				(type default)
			)
			(layer "B.Fab")
		)
		(fp_line
			(start 0.12065 -0.2794)
			(end -0.12065 -0.2794)
			(stroke
				(width 0.1)
				(type default)
			)
			(layer "B.Fab")
		)
		(fp_line
			(start 0.12065 0.2794)
			(end 0.12065 0.3048)
			(stroke
				(width 0.1)
				(type default)
			)
			(layer "B.Fab")
		)
		(fp_line
			(start 0.12065 0.3048)
			(end 0.67945 0.3048)
			(stroke
				(width 0.1)
				(type default)
			)
			(layer "B.Fab")
		)
		(fp_line
			(start 0.67945 -0.305054)
			(end 0.12065 -0.305054)
			(stroke
				(width 0.1)
				(type default)
			)
			(layer "B.Fab")
		)
		(fp_line
			(start 0.67945 0.3048)
			(end 0.67945 -0.305054)
			(stroke
				(width 0.1)
				(type default)
			)
			(layer "B.Fab")
		)
		(pad "1" smd circle
			(at 0.40005 0 180)
			(size 0 0)
			(layers "B.Cu" "B.Mask" "B.Paste")
			(net "PWRGD_P52V_HS2_PG")
		)
		(pad "2" smd circle
			(at -0.40005 0 180)
			(size 0 0)
			(layers "B.Cu" "B.Mask" "B.Paste")
			(net "GND1_FIELD_SIGNAL")
		)
	)
	(footprint ""
		(layer "B.Cu")
		(at 278.4094 -67.945)
		(property "Reference" "R146"
			(at 0 0 0)
			(layer "B.SilkS")
			(hide yes)
			(effects
				(font
					(size 1.27 1.27)
				)
				(justify mirror)
			)
		)
		(property "Value" ""
			(at 0 0 0)
			(layer "B.Fab")
			(effects
				(font
					(size 1.27 1.27)
				)
				(justify mirror)
			)
		)
		(duplicate_pad_numbers_are_jumpers no)
		(fp_line
			(start -0.7874 -0.4064)
			(end -0.7874 0.4064)
			(stroke
				(width 0.1524)
				(type default)
			)
			(layer "B.SilkS")
		)
		(fp_line
			(start -0.7874 0.4064)
			(end 0.7874 0.4064)
			(stroke
				(width 0.1524)
				(type default)
			)
			(layer "B.SilkS")
		)
		(fp_line
			(start 0.7874 -0.4064)
			(end -0.7874 -0.4064)
			(stroke
				(width 0.1524)
				(type default)
			)
			(layer "B.SilkS")
		)
		(fp_line
			(start 0.7874 0.4064)
			(end 0.7874 -0.4064)
			(stroke
				(width 0.1524)
				(type default)
			)
			(layer "B.SilkS")
		)
		(fp_line
			(start -0.67945 -0.3048)
			(end -0.67945 0.3048)
			(stroke
				(width 0.1)
				(type default)
			)
			(layer "B.Fab")
		)
		(fp_line
			(start -0.67945 0.3048)
			(end -0.120396 0.3048)
			(stroke
				(width 0.1)
				(type default)
			)
			(layer "B.Fab")
		)
		(fp_line
			(start -0.12065 -0.3048)
			(end -0.67945 -0.3048)
			(stroke
				(width 0.1)
				(type default)
			)
			(layer "B.Fab")
		)
		(fp_line
			(start -0.12065 -0.2794)
			(end -0.12065 -0.3048)
			(stroke
				(width 0.1)
				(type default)
			)
			(layer "B.Fab")
		)
		(fp_line
			(start -0.120396 0.2794)
			(end 0.12065 0.2794)
			(stroke
				(width 0.1)
				(type default)
			)
			(layer "B.Fab")
		)
		(fp_line
			(start -0.120396 0.3048)
			(end -0.120396 0.2794)
			(stroke
				(width 0.1)
				(type default)
			)
			(layer "B.Fab")
		)
		(fp_line
			(start 0.12065 -0.305054)
			(end 0.12065 -0.2794)
			(stroke
				(width 0.1)
				(type default)
			)
			(layer "B.Fab")
		)
		(fp_line
			(start 0.12065 -0.2794)
			(end -0.12065 -0.2794)
			(stroke
				(width 0.1)
				(type default)
			)
			(layer "B.Fab")
		)
		(fp_line
			(start 0.12065 0.2794)
			(end 0.12065 0.3048)
			(stroke
				(width 0.1)
				(type default)
			)
			(layer "B.Fab")
		)
		(fp_line
			(start 0.12065 0.3048)
			(end 0.67945 0.3048)
			(stroke
				(width 0.1)
				(type default)
			)
			(layer "B.Fab")
		)
		(fp_line
			(start 0.67945 -0.305054)
			(end 0.12065 -0.305054)
			(stroke
				(width 0.1)
				(type default)
			)
			(layer "B.Fab")
		)
		(fp_line
			(start 0.67945 0.3048)
			(end 0.67945 -0.305054)
			(stroke
				(width 0.1)
				(type default)
			)
			(layer "B.Fab")
		)
		(pad "1" smd circle
			(at 0.40005 0 180)
			(size 0 0)
			(layers "B.Cu" "B.Mask" "B.Paste")
			(net "P3V3_AUX")
		)
		(pad "2" smd circle
			(at -0.40005 0 180)
			(size 0 0)
			(layers "B.Cu" "B.Mask" "B.Paste")
			(net "SMB_P52V_PDB_SCL_R1")
		)
	)
	(footprint ""
		(layer "B.Cu")
		(at 180.086 -53.848 180)
		(property "Reference" "R5896"
			(at 0 0 0)
			(layer "B.SilkS")
			(hide yes)
			(effects
				(font
					(size 1.27 1.27)
				)
				(justify mirror)
			)
		)
		(property "Value" ""
			(at 0 0 0)
			(layer "B.Fab")
			(effects
				(font
					(size 1.27 1.27)
				)
				(justify mirror)
			)
		)
		(duplicate_pad_numbers_are_jumpers no)
		(fp_line
			(start 0.7874 0.4064)
			(end 0.7874 -0.4064)
			(stroke
				(width 0.1524)
				(type default)
			)
			(layer "B.SilkS")
		)
		(fp_line
			(start 0.7874 -0.4064)
			(end -0.7874 -0.4064)
			(stroke
				(width 0.1524)
				(type default)
			)
			(layer "B.SilkS")
		)
		(fp_line
			(start -0.7874 0.4064)
			(end 0.7874 0.4064)
			(stroke
				(width 0.1524)
				(type default)
			)
			(layer "B.SilkS")
		)
		(fp_line
			(start -0.7874 -0.4064)
			(end -0.7874 0.4064)
			(stroke
				(width 0.1524)
				(type default)
			)
			(layer "B.SilkS")
		)
		(fp_line
			(start 0.67945 0.3048)
			(end 0.67945 -0.305054)
			(stroke
				(width 0.1)
				(type default)
			)
			(layer "B.Fab")
		)
		(fp_line
			(start 0.67945 -0.305054)
			(end 0.12065 -0.305054)
			(stroke
				(width 0.1)
				(type default)
			)
			(layer "B.Fab")
		)
		(fp_line
			(start 0.12065 0.3048)
			(end 0.67945 0.3048)
			(stroke
				(width 0.1)
				(type default)
			)
			(layer "B.Fab")
		)
		(fp_line
			(start 0.12065 0.2794)
			(end 0.12065 0.3048)
			(stroke
				(width 0.1)
				(type default)
			)
			(layer "B.Fab")
		)
		(fp_line
			(start 0.12065 -0.2794)
			(end -0.12065 -0.2794)
			(stroke
				(width 0.1)
				(type default)
			)
			(layer "B.Fab")
		)
		(fp_line
			(start 0.12065 -0.305054)
			(end 0.12065 -0.2794)
			(stroke
				(width 0.1)
				(type default)
			)
			(layer "B.Fab")
		)
		(fp_line
			(start -0.120396 0.3048)
			(end -0.120396 0.2794)
			(stroke
				(width 0.1)
				(type default)
			)
			(layer "B.Fab")
		)
		(fp_line
			(start -0.120396 0.2794)
			(end 0.12065 0.2794)
			(stroke
				(width 0.1)
				(type default)
			)
			(layer "B.Fab")
		)
		(fp_line
			(start -0.12065 -0.2794)
			(end -0.12065 -0.3048)
			(stroke
				(width 0.1)
				(type default)
			)
			(layer "B.Fab")
		)
		(fp_line
			(start -0.12065 -0.3048)
			(end -0.67945 -0.3048)
			(stroke
				(width 0.1)
				(type default)
			)
			(layer "B.Fab")
		)
		(fp_line
			(start -0.67945 0.3048)
			(end -0.120396 0.3048)
			(stroke
				(width 0.1)
				(type default)
			)
			(layer "B.Fab")
		)
		(fp_line
			(start -0.67945 -0.3048)
			(end -0.67945 0.3048)
			(stroke
				(width 0.1)
				(type default)
			)
			(layer "B.Fab")
		)
		(pad "1" smd circle
			(at 0.40005 0)
			(size 0 0)
			(layers "B.Cu" "B.Mask" "B.Paste")
			(net "GPU_HSC2_BUF_EN")
		)
		(pad "2" smd circle
			(at -0.40005 0)
			(size 0 0)
			(layers "B.Cu" "B.Mask" "B.Paste")
			(net "FM_HS2_EN_FUSE")
		)
	)
	(footprint ""
		(layer "B.Cu")
		(at 163.3474 -78.359 180)
		(property "Reference" "PR7011"
			(at 0 0 0)
			(layer "B.SilkS")
			(hide yes)
			(effects
				(font
					(size 1.27 1.27)
				)
				(justify mirror)
			)
		)
		(property "Value" ""
			(at 0 0 0)
			(layer "B.Fab")
			(effects
				(font
					(size 1.27 1.27)
				)
				(justify mirror)
			)
		)
		(duplicate_pad_numbers_are_jumpers no)
		(fp_line
			(start 0.7874 0.4064)
			(end 0.7874 -0.4064)
			(stroke
				(width 0.1524)
				(type default)
			)
			(layer "B.SilkS")
		)
		(fp_line
			(start 0.7874 -0.4064)
			(end -0.7874 -0.4064)
			(stroke
				(width 0.1524)
				(type default)
			)
			(layer "B.SilkS")
		)
		(fp_line
			(start -0.7874 0.4064)
			(end 0.7874 0.4064)
			(stroke
				(width 0.1524)
				(type default)
			)
			(layer "B.SilkS")
		)
		(fp_line
			(start -0.7874 -0.4064)
			(end -0.7874 0.4064)
			(stroke
				(width 0.1524)
				(type default)
			)
			(layer "B.SilkS")
		)
		(fp_line
			(start 0.67945 0.3048)
			(end 0.67945 -0.305054)
			(stroke
				(width 0.1)
				(type default)
			)
			(layer "B.Fab")
		)
		(fp_line
			(start 0.67945 -0.305054)
			(end 0.12065 -0.305054)
			(stroke
				(width 0.1)
				(type default)
			)
			(layer "B.Fab")
		)
		(fp_line
			(start 0.12065 0.3048)
			(end 0.67945 0.3048)
			(stroke
				(width 0.1)
				(type default)
			)
			(layer "B.Fab")
		)
		(fp_line
			(start 0.12065 0.2794)
			(end 0.12065 0.3048)
			(stroke
				(width 0.1)
				(type default)
			)
			(layer "B.Fab")
		)
		(fp_line
			(start 0.12065 -0.2794)
			(end -0.12065 -0.2794)
			(stroke
				(width 0.1)
				(type default)
			)
			(layer "B.Fab")
		)
		(fp_line
			(start 0.12065 -0.305054)
			(end 0.12065 -0.2794)
			(stroke
				(width 0.1)
				(type default)
			)
			(layer "B.Fab")
		)
		(fp_line
			(start -0.120396 0.3048)
			(end -0.120396 0.2794)
			(stroke
				(width 0.1)
				(type default)
			)
			(layer "B.Fab")
		)
		(fp_line
			(start -0.120396 0.2794)
			(end 0.12065 0.2794)
			(stroke
				(width 0.1)
				(type default)
			)
			(layer "B.Fab")
		)
		(fp_line
			(start -0.12065 -0.2794)
			(end -0.12065 -0.3048)
			(stroke
				(width 0.1)
				(type default)
			)
			(layer "B.Fab")
		)
		(fp_line
			(start -0.12065 -0.3048)
			(end -0.67945 -0.3048)
			(stroke
				(width 0.1)
				(type default)
			)
			(layer "B.Fab")
		)
		(fp_line
			(start -0.67945 0.3048)
			(end -0.120396 0.3048)
			(stroke
				(width 0.1)
				(type default)
			)
			(layer "B.Fab")
		)
		(fp_line
			(start -0.67945 -0.3048)
			(end -0.67945 0.3048)
			(stroke
				(width 0.1)
				(type default)
			)
			(layer "B.Fab")
		)
		(pad "1" smd circle
			(at 0.40005 0)
			(size 0 0)
			(layers "B.Cu" "B.Mask" "B.Paste")
			(net "HS2_TMR2")
		)
		(pad "2" smd circle
			(at -0.40005 0)
			(size 0 0)
			(layers "B.Cu" "B.Mask" "B.Paste")
			(net "GND1_FIELD_SIGNAL")
		)
	)
	(footprint ""
		(layer "B.Cu")
		(at 274.4724 -84.201 90)
		(property "Reference" "PR480"
			(at 0 0 90)
			(layer "B.SilkS")
			(hide yes)
			(effects
				(font
					(size 1.27 1.27)
				)
				(justify mirror)
			)
		)
		(property "Value" ""
			(at 0 0 90)
			(layer "B.Fab")
			(effects
				(font
					(size 1.27 1.27)
				)
				(justify mirror)
			)
		)
		(duplicate_pad_numbers_are_jumpers no)
		(fp_line
			(start 1.651 -0.8382)
			(end -1.651 -0.8382)
			(stroke
				(width 0.1524)
				(type default)
			)
			(layer "B.SilkS")
		)
		(fp_line
			(start -1.651 -0.8382)
			(end -1.651 0.8382)
			(stroke
				(width 0.1524)
				(type default)
			)
			(layer "B.SilkS")
		)
		(fp_line
			(start 1.651 0.8382)
			(end 1.651 -0.8382)
			(stroke
				(width 0.1524)
				(type default)
			)
			(layer "B.SilkS")
		)
		(fp_line
			(start -1.651 0.8382)
			(end 1.651 0.8382)
			(stroke
				(width 0.1524)
				(type default)
			)
			(layer "B.SilkS")
		)
		(fp_line
			(start 1.559814 -0.7366)
			(end 1.559814 0.7366)
			(stroke
				(width 0.1)
				(type default)
			)
			(layer "B.Fab")
		)
		(fp_line
			(start 1.524 -0.7366)
			(end 1.559814 -0.7366)
			(stroke
				(width 0.1)
				(type default)
			)
			(layer "B.Fab")
		)
		(fp_line
			(start -1.524 -0.7366)
			(end 1.524 -0.7366)
			(stroke
				(width 0.1)
				(type default)
			)
			(layer "B.Fab")
		)
		(fp_line
			(start -1.560576 -0.7366)
			(end -1.524 -0.7366)
			(stroke
				(width 0.1)
				(type default)
			)
			(layer "B.Fab")
		)
		(fp_line
			(start 1.559814 0.7366)
			(end 1.524 0.7366)
			(stroke
				(width 0.1)
				(type default)
			)
			(layer "B.Fab")
		)
		(fp_line
			(start 1.524 0.7366)
			(end -1.524 0.7366)
			(stroke
				(width 0.1)
				(type default)
			)
			(layer "B.Fab")
		)
		(fp_line
			(start -1.524 0.7366)
			(end -1.560576 0.7366)
			(stroke
				(width 0.1)
				(type default)
			)
			(layer "B.Fab")
		)
		(fp_line
			(start -1.560576 0.7366)
			(end -1.560576 -0.7366)
			(stroke
				(width 0.1)
				(type default)
			)
			(layer "B.Fab")
		)
		(pad "1" smd rect
			(at 0.94996 0 90)
			(size 1.1176 1.3716)
			(layers "B.Cu" "B.Mask" "B.Paste")
			(net "P52V_1")
		)
		(pad "2" smd rect
			(at -0.94996 0 90)
			(size 1.1176 1.3716)
			(layers "B.Cu" "B.Mask" "B.Paste")
			(net "P52V_HS1_OV")
		)
	)
	(footprint ""
		(layer "B.Cu")
		(at 286.2834 -69.342 -90)
		(property "Reference" "PR27"
			(at 0 0 90)
			(layer "B.SilkS")
			(hide yes)
			(effects
				(font
					(size 1.27 1.27)
				)
				(justify mirror)
			)
		)
		(property "Value" ""
			(at 0 0 90)
			(layer "B.Fab")
			(effects
				(font
					(size 1.27 1.27)
				)
				(justify mirror)
			)
		)
		(duplicate_pad_numbers_are_jumpers no)
		(fp_line
			(start -0.7874 0.4064)
			(end 0.7874 0.4064)
			(stroke
				(width 0.1524)
				(type default)
			)
			(layer "B.SilkS")
		)
		(fp_line
			(start 0.7874 0.4064)
			(end 0.7874 -0.4064)
			(stroke
				(width 0.1524)
				(type default)
			)
			(layer "B.SilkS")
		)
		(fp_line
			(start -0.7874 -0.4064)
			(end -0.7874 0.4064)
			(stroke
				(width 0.1524)
				(type default)
			)
			(layer "B.SilkS")
		)
		(fp_line
			(start 0.7874 -0.4064)
			(end -0.7874 -0.4064)
			(stroke
				(width 0.1524)
				(type default)
			)
			(layer "B.SilkS")
		)
		(fp_line
			(start -0.67945 0.3048)
			(end -0.120396 0.3048)
			(stroke
				(width 0.1)
				(type default)
			)
			(layer "B.Fab")
		)
		(fp_line
			(start -0.120396 0.3048)
			(end -0.120396 0.2794)
			(stroke
				(width 0.1)
				(type default)
			)
			(layer "B.Fab")
		)
		(fp_line
			(start 0.12065 0.3048)
			(end 0.67945 0.3048)
			(stroke
				(width 0.1)
				(type default)
			)
			(layer "B.Fab")
		)
		(fp_line
			(start 0.67945 0.3048)
			(end 0.67945 -0.305054)
			(stroke
				(width 0.1)
				(type default)
			)
			(layer "B.Fab")
		)
		(fp_line
			(start -0.120396 0.2794)
			(end 0.12065 0.2794)
			(stroke
				(width 0.1)
				(type default)
			)
			(layer "B.Fab")
		)
		(fp_line
			(start 0.12065 0.2794)
			(end 0.12065 0.3048)
			(stroke
				(width 0.1)
				(type default)
			)
			(layer "B.Fab")
		)
		(fp_line
			(start -0.12065 -0.2794)
			(end -0.12065 -0.3048)
			(stroke
				(width 0.1)
				(type default)
			)
			(layer "B.Fab")
		)
		(fp_line
			(start 0.12065 -0.2794)
			(end -0.12065 -0.2794)
			(stroke
				(width 0.1)
				(type default)
			)
			(layer "B.Fab")
		)
		(fp_line
			(start -0.67945 -0.3048)
			(end -0.67945 0.3048)
			(stroke
				(width 0.1)
				(type default)
			)
			(layer "B.Fab")
		)
		(fp_line
			(start -0.12065 -0.3048)
			(end -0.67945 -0.3048)
			(stroke
				(width 0.1)
				(type default)
			)
			(layer "B.Fab")
		)
		(fp_line
			(start 0.12065 -0.305054)
			(end 0.12065 -0.2794)
			(stroke
				(width 0.1)
				(type default)
			)
			(layer "B.Fab")
		)
		(fp_line
			(start 0.67945 -0.305054)
			(end 0.12065 -0.305054)
			(stroke
				(width 0.1)
				(type default)
			)
			(layer "B.Fab")
		)
		(pad "1" smd circle
			(at 0.40005 0 90)
			(size 0 0)
			(layers "B.Cu" "B.Mask" "B.Paste")
			(net "P52V_HS1_INTVCC")
		)
		(pad "2" smd circle
			(at -0.40005 0 90)
			(size 0 0)
			(layers "B.Cu" "B.Mask" "B.Paste")
			(net "P52V_HS1_SCK")
		)
	)
	(footprint ""
		(layer "B.Cu")
		(at 161.717736 -72.263 180)
		(property "Reference" "PR7007"
			(at 0 0 0)
			(layer "B.SilkS")
			(hide yes)
			(effects
				(font
					(size 1.27 1.27)
				)
				(justify mirror)
			)
		)
		(property "Value" ""
			(at 0 0 0)
			(layer "B.Fab")
			(effects
				(font
					(size 1.27 1.27)
				)
				(justify mirror)
			)
		)
		(duplicate_pad_numbers_are_jumpers no)
		(fp_line
			(start 0.7874 0.4064)
			(end 0.7874 -0.4064)
			(stroke
				(width 0.1524)
				(type default)
			)
			(layer "B.SilkS")
		)
		(fp_line
			(start 0.7874 -0.4064)
			(end -0.7874 -0.4064)
			(stroke
				(width 0.1524)
				(type default)
			)
			(layer "B.SilkS")
		)
		(fp_line
			(start -0.7874 0.4064)
			(end 0.7874 0.4064)
			(stroke
				(width 0.1524)
				(type default)
			)
			(layer "B.SilkS")
		)
		(fp_line
			(start -0.7874 -0.4064)
			(end -0.7874 0.4064)
			(stroke
				(width 0.1524)
				(type default)
			)
			(layer "B.SilkS")
		)
		(fp_line
			(start 0.67945 0.3048)
			(end 0.67945 -0.305054)
			(stroke
				(width 0.1)
				(type default)
			)
			(layer "B.Fab")
		)
		(fp_line
			(start 0.67945 -0.305054)
			(end 0.12065 -0.305054)
			(stroke
				(width 0.1)
				(type default)
			)
			(layer "B.Fab")
		)
		(fp_line
			(start 0.12065 0.3048)
			(end 0.67945 0.3048)
			(stroke
				(width 0.1)
				(type default)
			)
			(layer "B.Fab")
		)
		(fp_line
			(start 0.12065 0.2794)
			(end 0.12065 0.3048)
			(stroke
				(width 0.1)
				(type default)
			)
			(layer "B.Fab")
		)
		(fp_line
			(start 0.12065 -0.2794)
			(end -0.12065 -0.2794)
			(stroke
				(width 0.1)
				(type default)
			)
			(layer "B.Fab")
		)
		(fp_line
			(start 0.12065 -0.305054)
			(end 0.12065 -0.2794)
			(stroke
				(width 0.1)
				(type default)
			)
			(layer "B.Fab")
		)
		(fp_line
			(start -0.120396 0.3048)
			(end -0.120396 0.2794)
			(stroke
				(width 0.1)
				(type default)
			)
			(layer "B.Fab")
		)
		(fp_line
			(start -0.120396 0.2794)
			(end 0.12065 0.2794)
			(stroke
				(width 0.1)
				(type default)
			)
			(layer "B.Fab")
		)
		(fp_line
			(start -0.12065 -0.2794)
			(end -0.12065 -0.3048)
			(stroke
				(width 0.1)
				(type default)
			)
			(layer "B.Fab")
		)
		(fp_line
			(start -0.12065 -0.3048)
			(end -0.67945 -0.3048)
			(stroke
				(width 0.1)
				(type default)
			)
			(layer "B.Fab")
		)
		(fp_line
			(start -0.67945 0.3048)
			(end -0.120396 0.3048)
			(stroke
				(width 0.1)
				(type default)
			)
			(layer "B.Fab")
		)
		(fp_line
			(start -0.67945 -0.3048)
			(end -0.67945 0.3048)
			(stroke
				(width 0.1)
				(type default)
			)
			(layer "B.Fab")
		)
		(pad "1" smd circle
			(at 0.40005 0)
			(size 0 0)
			(layers "B.Cu" "B.Mask" "B.Paste")
			(net "P52V_HS2_SIO")
		)
		(pad "2" smd circle
			(at -0.40005 0)
			(size 0 0)
			(layers "B.Cu" "B.Mask" "B.Paste")
			(net "GND1_FIELD_SIGNAL")
		)
	)
	(footprint ""
		(layer "B.Cu")
		(at 291.9984 -60.833 90)
		(property "Reference" "R158"
			(at 0 0 90)
			(layer "B.SilkS")
			(hide yes)
			(effects
				(font
					(size 1.27 1.27)
				)
				(justify mirror)
			)
		)
		(property "Value" ""
			(at 0 0 90)
			(layer "B.Fab")
			(effects
				(font
					(size 1.27 1.27)
				)
				(justify mirror)
			)
		)
		(duplicate_pad_numbers_are_jumpers no)
		(fp_line
			(start 0.7874 -0.4064)
			(end -0.7874 -0.4064)
			(stroke
				(width 0.1524)
				(type default)
			)
			(layer "B.SilkS")
		)
		(fp_line
			(start -0.7874 -0.4064)
			(end -0.7874 0.4064)
			(stroke
				(width 0.1524)
				(type default)
			)
			(layer "B.SilkS")
		)
		(fp_line
			(start 0.7874 0.4064)
			(end 0.7874 -0.4064)
			(stroke
				(width 0.1524)
				(type default)
			)
			(layer "B.SilkS")
		)
		(fp_line
			(start -0.7874 0.4064)
			(end 0.7874 0.4064)
			(stroke
				(width 0.1524)
				(type default)
			)
			(layer "B.SilkS")
		)
		(fp_line
			(start 0.67945 -0.305054)
			(end 0.12065 -0.305054)
			(stroke
				(width 0.1)
				(type default)
			)
			(layer "B.Fab")
		)
		(fp_line
			(start 0.12065 -0.305054)
			(end 0.12065 -0.2794)
			(stroke
				(width 0.1)
				(type default)
			)
			(layer "B.Fab")
		)
		(fp_line
			(start -0.12065 -0.3048)
			(end -0.67945 -0.3048)
			(stroke
				(width 0.1)
				(type default)
			)
			(layer "B.Fab")
		)
		(fp_line
			(start -0.67945 -0.3048)
			(end -0.67945 0.3048)
			(stroke
				(width 0.1)
				(type default)
			)
			(layer "B.Fab")
		)
		(fp_line
			(start 0.12065 -0.2794)
			(end -0.12065 -0.2794)
			(stroke
				(width 0.1)
				(type default)
			)
			(layer "B.Fab")
		)
		(fp_line
			(start -0.12065 -0.2794)
			(end -0.12065 -0.3048)
			(stroke
				(width 0.1)
				(type default)
			)
			(layer "B.Fab")
		)
		(fp_line
			(start 0.12065 0.2794)
			(end 0.12065 0.3048)
			(stroke
				(width 0.1)
				(type default)
			)
			(layer "B.Fab")
		)
		(fp_line
			(start -0.120396 0.2794)
			(end 0.12065 0.2794)
			(stroke
				(width 0.1)
				(type default)
			)
			(layer "B.Fab")
		)
		(fp_line
			(start 0.67945 0.3048)
			(end 0.67945 -0.305054)
			(stroke
				(width 0.1)
				(type default)
			)
			(layer "B.Fab")
		)
		(fp_line
			(start 0.12065 0.3048)
			(end 0.67945 0.3048)
			(stroke
				(width 0.1)
				(type default)
			)
			(layer "B.Fab")
		)
		(fp_line
			(start -0.120396 0.3048)
			(end -0.120396 0.2794)
			(stroke
				(width 0.1)
				(type default)
			)
			(layer "B.Fab")
		)
		(fp_line
			(start -0.67945 0.3048)
			(end -0.120396 0.3048)
			(stroke
				(width 0.1)
				(type default)
			)
			(layer "B.Fab")
		)
		(pad "1" smd circle
			(at 0.40005 0 270)
			(size 0 0)
			(layers "B.Cu" "B.Mask" "B.Paste")
			(net "P52V_HS1_ADR0")
		)
		(pad "2" smd circle
			(at -0.40005 0 270)
			(size 0 0)
			(layers "B.Cu" "B.Mask" "B.Paste")
			(net "GND_FIELD_SIGNAL")
		)
	)
	(footprint ""
		(layer "B.Cu")
		(at 162.733736 -70.485 180)
		(property "Reference" "PR7015"
			(at 0 0 0)
			(layer "B.SilkS")
			(hide yes)
			(effects
				(font
					(size 1.27 1.27)
				)
				(justify mirror)
			)
		)
		(property "Value" ""
			(at 0 0 0)
			(layer "B.Fab")
			(effects
				(font
					(size 1.27 1.27)
				)
				(justify mirror)
			)
		)
		(duplicate_pad_numbers_are_jumpers no)
		(fp_line
			(start 0.7874 0.4064)
			(end 0.7874 -0.4064)
			(stroke
				(width 0.1524)
				(type default)
			)
			(layer "B.SilkS")
		)
		(fp_line
			(start 0.7874 -0.4064)
			(end -0.7874 -0.4064)
			(stroke
				(width 0.1524)
				(type default)
			)
			(layer "B.SilkS")
		)
		(fp_line
			(start -0.7874 0.4064)
			(end 0.7874 0.4064)
			(stroke
				(width 0.1524)
				(type default)
			)
			(layer "B.SilkS")
		)
		(fp_line
			(start -0.7874 -0.4064)
			(end -0.7874 0.4064)
			(stroke
				(width 0.1524)
				(type default)
			)
			(layer "B.SilkS")
		)
		(fp_line
			(start 0.67945 0.3048)
			(end 0.67945 -0.305054)
			(stroke
				(width 0.1)
				(type default)
			)
			(layer "B.Fab")
		)
		(fp_line
			(start 0.67945 -0.305054)
			(end 0.12065 -0.305054)
			(stroke
				(width 0.1)
				(type default)
			)
			(layer "B.Fab")
		)
		(fp_line
			(start 0.12065 0.3048)
			(end 0.67945 0.3048)
			(stroke
				(width 0.1)
				(type default)
			)
			(layer "B.Fab")
		)
		(fp_line
			(start 0.12065 0.2794)
			(end 0.12065 0.3048)
			(stroke
				(width 0.1)
				(type default)
			)
			(layer "B.Fab")
		)
		(fp_line
			(start 0.12065 -0.2794)
			(end -0.12065 -0.2794)
			(stroke
				(width 0.1)
				(type default)
			)
			(layer "B.Fab")
		)
		(fp_line
			(start 0.12065 -0.305054)
			(end 0.12065 -0.2794)
			(stroke
				(width 0.1)
				(type default)
			)
			(layer "B.Fab")
		)
		(fp_line
			(start -0.120396 0.3048)
			(end -0.120396 0.2794)
			(stroke
				(width 0.1)
				(type default)
			)
			(layer "B.Fab")
		)
		(fp_line
			(start -0.120396 0.2794)
			(end 0.12065 0.2794)
			(stroke
				(width 0.1)
				(type default)
			)
			(layer "B.Fab")
		)
		(fp_line
			(start -0.12065 -0.2794)
			(end -0.12065 -0.3048)
			(stroke
				(width 0.1)
				(type default)
			)
			(layer "B.Fab")
		)
		(fp_line
			(start -0.12065 -0.3048)
			(end -0.67945 -0.3048)
			(stroke
				(width 0.1)
				(type default)
			)
			(layer "B.Fab")
		)
		(fp_line
			(start -0.67945 0.3048)
			(end -0.120396 0.3048)
			(stroke
				(width 0.1)
				(type default)
			)
			(layer "B.Fab")
		)
		(fp_line
			(start -0.67945 -0.3048)
			(end -0.67945 0.3048)
			(stroke
				(width 0.1)
				(type default)
			)
			(layer "B.Fab")
		)
		(pad "1" smd circle
			(at 0.40005 0)
			(size 0 0)
			(layers "B.Cu" "B.Mask" "B.Paste")
			(net "P52V_HS2_SCK")
		)
		(pad "2" smd circle
			(at -0.40005 0)
			(size 0 0)
			(layers "B.Cu" "B.Mask" "B.Paste")
			(net "GND1_FIELD_SIGNAL")
		)
	)
	(footprint ""
		(layer "B.Cu")
		(at 293.5224 -63.373)
		(property "Reference" "PC5"
			(at 0 0 0)
			(layer "B.SilkS")
			(hide yes)
			(effects
				(font
					(size 1.27 1.27)
				)
				(justify mirror)
			)
		)
		(property "Value" ""
			(at 0 0 0)
			(layer "B.Fab")
			(effects
				(font
					(size 1.27 1.27)
				)
				(justify mirror)
			)
		)
		(duplicate_pad_numbers_are_jumpers no)
		(fp_line
			(start -0.7874 -0.4064)
			(end -0.7874 0.4064)
			(stroke
				(width 0.1524)
				(type default)
			)
			(layer "B.SilkS")
		)
		(fp_line
			(start -0.7874 0.4064)
			(end 0.7874 0.4064)
			(stroke
				(width 0.1524)
				(type default)
			)
			(layer "B.SilkS")
		)
		(fp_line
			(start 0.7874 -0.4064)
			(end -0.7874 -0.4064)
			(stroke
				(width 0.1524)
				(type default)
			)
			(layer "B.SilkS")
		)
		(fp_line
			(start 0.7874 0.4064)
			(end 0.7874 -0.4064)
			(stroke
				(width 0.1524)
				(type default)
			)
			(layer "B.SilkS")
		)
		(fp_line
			(start -0.67945 -0.3048)
			(end -0.67945 0.3048)
			(stroke
				(width 0.1)
				(type default)
			)
			(layer "B.Fab")
		)
		(fp_line
			(start -0.67945 0.3048)
			(end -0.120396 0.3048)
			(stroke
				(width 0.1)
				(type default)
			)
			(layer "B.Fab")
		)
		(fp_line
			(start -0.12065 -0.3048)
			(end -0.67945 -0.3048)
			(stroke
				(width 0.1)
				(type default)
			)
			(layer "B.Fab")
		)
		(fp_line
			(start -0.12065 -0.2794)
			(end -0.12065 -0.3048)
			(stroke
				(width 0.1)
				(type default)
			)
			(layer "B.Fab")
		)
		(fp_line
			(start -0.120396 0.2794)
			(end 0.12065 0.2794)
			(stroke
				(width 0.1)
				(type default)
			)
			(layer "B.Fab")
		)
		(fp_line
			(start -0.120396 0.3048)
			(end -0.120396 0.2794)
			(stroke
				(width 0.1)
				(type default)
			)
			(layer "B.Fab")
		)
		(fp_line
			(start 0.12065 -0.305054)
			(end 0.12065 -0.2794)
			(stroke
				(width 0.1)
				(type default)
			)
			(layer "B.Fab")
		)
		(fp_line
			(start 0.12065 -0.2794)
			(end -0.12065 -0.2794)
			(stroke
				(width 0.1)
				(type default)
			)
			(layer "B.Fab")
		)
		(fp_line
			(start 0.12065 0.2794)
			(end 0.12065 0.3048)
			(stroke
				(width 0.1)
				(type default)
			)
			(layer "B.Fab")
		)
		(fp_line
			(start 0.12065 0.3048)
			(end 0.67945 0.3048)
			(stroke
				(width 0.1)
				(type default)
			)
			(layer "B.Fab")
		)
		(fp_line
			(start 0.67945 -0.305054)
			(end 0.12065 -0.305054)
			(stroke
				(width 0.1)
				(type default)
			)
			(layer "B.Fab")
		)
		(fp_line
			(start 0.67945 0.3048)
			(end 0.67945 -0.305054)
			(stroke
				(width 0.1)
				(type default)
			)
			(layer "B.Fab")
		)
		(pad "1" smd circle
			(at 0.40005 0 180)
			(size 0 0)
			(layers "B.Cu" "B.Mask" "B.Paste")
			(net "GND_FIELD_SIGNAL")
		)
		(pad "2" smd circle
			(at -0.40005 0 180)
			(size 0 0)
			(layers "B.Cu" "B.Mask" "B.Paste")
			(net "P52V_HS1_DVCC")
		)
	)
	(footprint ""
		(layer "B.Cu")
		(at 272.4404 -84.201 90)
		(property "Reference" "PR4"
			(at 0 0 90)
			(layer "B.SilkS")
			(hide yes)
			(effects
				(font
					(size 1.27 1.27)
				)
				(justify mirror)
			)
		)
		(property "Value" ""
			(at 0 0 90)
			(layer "B.Fab")
			(effects
				(font
					(size 1.27 1.27)
				)
				(justify mirror)
			)
		)
		(duplicate_pad_numbers_are_jumpers no)
		(fp_line
			(start 1.651 -0.8382)
			(end -1.651 -0.8382)
			(stroke
				(width 0.1524)
				(type default)
			)
			(layer "B.SilkS")
		)
		(fp_line
			(start -1.651 -0.8382)
			(end -1.651 0.8382)
			(stroke
				(width 0.1524)
				(type default)
			)
			(layer "B.SilkS")
		)
		(fp_line
			(start 1.651 0.8382)
			(end 1.651 -0.8382)
			(stroke
				(width 0.1524)
				(type default)
			)
			(layer "B.SilkS")
		)
		(fp_line
			(start -1.651 0.8382)
			(end 1.651 0.8382)
			(stroke
				(width 0.1524)
				(type default)
			)
			(layer "B.SilkS")
		)
		(fp_line
			(start 1.559814 -0.7366)
			(end 1.559814 0.7366)
			(stroke
				(width 0.1)
				(type default)
			)
			(layer "B.Fab")
		)
		(fp_line
			(start 1.524 -0.7366)
			(end 1.559814 -0.7366)
			(stroke
				(width 0.1)
				(type default)
			)
			(layer "B.Fab")
		)
		(fp_line
			(start -1.524 -0.7366)
			(end 1.524 -0.7366)
			(stroke
				(width 0.1)
				(type default)
			)
			(layer "B.Fab")
		)
		(fp_line
			(start -1.560576 -0.7366)
			(end -1.524 -0.7366)
			(stroke
				(width 0.1)
				(type default)
			)
			(layer "B.Fab")
		)
		(fp_line
			(start 1.559814 0.7366)
			(end 1.524 0.7366)
			(stroke
				(width 0.1)
				(type default)
			)
			(layer "B.Fab")
		)
		(fp_line
			(start 1.524 0.7366)
			(end -1.524 0.7366)
			(stroke
				(width 0.1)
				(type default)
			)
			(layer "B.Fab")
		)
		(fp_line
			(start -1.524 0.7366)
			(end -1.560576 0.7366)
			(stroke
				(width 0.1)
				(type default)
			)
			(layer "B.Fab")
		)
		(fp_line
			(start -1.560576 0.7366)
			(end -1.560576 -0.7366)
			(stroke
				(width 0.1)
				(type default)
			)
			(layer "B.Fab")
		)
		(pad "1" smd rect
			(at 0.94996 0 90)
			(size 1.1176 1.3716)
			(layers "B.Cu" "B.Mask" "B.Paste")
			(net "P52V_1")
		)
		(pad "2" smd rect
			(at -0.94996 0 90)
			(size 1.1176 1.3716)
			(layers "B.Cu" "B.Mask" "B.Paste")
			(net "P52V_HS1_UVH")
		)
	)
	(footprint ""
		(layer "B.Cu")
		(at 149.86 -52.959)
		(property "Reference" ""
			(at 0 0 0)
			(layer "B.SilkS")
			(hide yes)
			(effects
				(font
					(size 1.27 1.27)
				)
				(justify mirror)
			)
		)
		(property "Value" ""
			(at 0 0 0)
			(layer "B.Fab")
			(effects
				(font
					(size 1.27 1.27)
				)
				(justify mirror)
			)
		)
		(duplicate_pad_numbers_are_jumpers no)
		(pad "1" smd circle
			(at 0 0 180)
			(size 0.9906 0.9906)
			(layers "B.Cu" "B.Mask" "B.Paste")
			(net "Net_240")
		)
		(zone
			(layer "B.Cu")
			(hatch none 0.5)
			(connect_pads
				(clearance 0)
			)
			(min_thickness 0.25)
			(keepout
				(tracks not_allowed)
				(vias allowed)
				(pads allowed)
				(copperpour not_allowed)
				(footprints allowed)
			)
			(placement
				(enabled no)
				(sheetname "")
			)
			(fill
				(thermal_gap 0.5)
				(thermal_bridge_width 0.5)
				(island_removal_mode 0)
			)
			(polygon
				(pts
					(arc
						(start 151.4856 -52.959)
						(mid 148.2344 -52.959)
						(end 151.4856 -52.959)
					)
				)
			)
		)
	)
	(footprint ""
		(layer "B.Cu")
		(at 422.3004 -35.052 180)
		(property "Reference" "C102"
			(at 0 0 0)
			(layer "B.SilkS")
			(hide yes)
			(effects
				(font
					(size 1.27 1.27)
				)
				(justify mirror)
			)
		)
		(property "Value" ""
			(at 0 0 0)
			(layer "B.Fab")
			(effects
				(font
					(size 1.27 1.27)
				)
				(justify mirror)
			)
		)
		(duplicate_pad_numbers_are_jumpers no)
		(fp_line
			(start 0.7874 0.4064)
			(end 0.7874 -0.4064)
			(stroke
				(width 0.1524)
				(type default)
			)
			(layer "B.SilkS")
		)
		(fp_line
			(start 0.7874 -0.4064)
			(end -0.7874 -0.4064)
			(stroke
				(width 0.1524)
				(type default)
			)
			(layer "B.SilkS")
		)
		(fp_line
			(start -0.7874 0.4064)
			(end 0.7874 0.4064)
			(stroke
				(width 0.1524)
				(type default)
			)
			(layer "B.SilkS")
		)
		(fp_line
			(start -0.7874 -0.4064)
			(end -0.7874 0.4064)
			(stroke
				(width 0.1524)
				(type default)
			)
			(layer "B.SilkS")
		)
		(fp_line
			(start 0.67945 0.3048)
			(end 0.67945 -0.305054)
			(stroke
				(width 0.1)
				(type default)
			)
			(layer "B.Fab")
		)
		(fp_line
			(start 0.67945 -0.305054)
			(end 0.12065 -0.305054)
			(stroke
				(width 0.1)
				(type default)
			)
			(layer "B.Fab")
		)
		(fp_line
			(start 0.12065 0.3048)
			(end 0.67945 0.3048)
			(stroke
				(width 0.1)
				(type default)
			)
			(layer "B.Fab")
		)
		(fp_line
			(start 0.12065 0.2794)
			(end 0.12065 0.3048)
			(stroke
				(width 0.1)
				(type default)
			)
			(layer "B.Fab")
		)
		(fp_line
			(start 0.12065 -0.2794)
			(end -0.12065 -0.2794)
			(stroke
				(width 0.1)
				(type default)
			)
			(layer "B.Fab")
		)
		(fp_line
			(start 0.12065 -0.305054)
			(end 0.12065 -0.2794)
			(stroke
				(width 0.1)
				(type default)
			)
			(layer "B.Fab")
		)
		(fp_line
			(start -0.120396 0.3048)
			(end -0.120396 0.2794)
			(stroke
				(width 0.1)
				(type default)
			)
			(layer "B.Fab")
		)
		(fp_line
			(start -0.120396 0.2794)
			(end 0.12065 0.2794)
			(stroke
				(width 0.1)
				(type default)
			)
			(layer "B.Fab")
		)
		(fp_line
			(start -0.12065 -0.2794)
			(end -0.12065 -0.3048)
			(stroke
				(width 0.1)
				(type default)
			)
			(layer "B.Fab")
		)
		(fp_line
			(start -0.12065 -0.3048)
			(end -0.67945 -0.3048)
			(stroke
				(width 0.1)
				(type default)
			)
			(layer "B.Fab")
		)
		(fp_line
			(start -0.67945 0.3048)
			(end -0.120396 0.3048)
			(stroke
				(width 0.1)
				(type default)
			)
			(layer "B.Fab")
		)
		(fp_line
			(start -0.67945 -0.3048)
			(end -0.67945 0.3048)
			(stroke
				(width 0.1)
				(type default)
			)
			(layer "B.Fab")
		)
		(pad "1" smd circle
			(at 0.40005 0)
			(size 0 0)
			(layers "B.Cu" "B.Mask" "B.Paste")
			(net "P3V3_AUX")
		)
		(pad "2" smd circle
			(at -0.40005 0)
			(size 0 0)
			(layers "B.Cu" "B.Mask" "B.Paste")
			(net "GND")
		)
	)
	(footprint ""
		(layer "B.Cu")
		(at 110.2614 -55.626 90)
		(property "Reference" "R5865"
			(at 0 0 90)
			(layer "B.SilkS")
			(hide yes)
			(effects
				(font
					(size 1.27 1.27)
				)
				(justify mirror)
			)
		)
		(property "Value" ""
			(at 0 0 90)
			(layer "B.Fab")
			(effects
				(font
					(size 1.27 1.27)
				)
				(justify mirror)
			)
		)
		(duplicate_pad_numbers_are_jumpers no)
		(fp_line
			(start 0.7874 -0.4064)
			(end -0.7874 -0.4064)
			(stroke
				(width 0.1524)
				(type default)
			)
			(layer "B.SilkS")
		)
		(fp_line
			(start -0.7874 -0.4064)
			(end -0.7874 0.4064)
			(stroke
				(width 0.1524)
				(type default)
			)
			(layer "B.SilkS")
		)
		(fp_line
			(start 0.7874 0.4064)
			(end 0.7874 -0.4064)
			(stroke
				(width 0.1524)
				(type default)
			)
			(layer "B.SilkS")
		)
		(fp_line
			(start -0.7874 0.4064)
			(end 0.7874 0.4064)
			(stroke
				(width 0.1524)
				(type default)
			)
			(layer "B.SilkS")
		)
		(fp_line
			(start 0.67945 -0.305054)
			(end 0.12065 -0.305054)
			(stroke
				(width 0.1)
				(type default)
			)
			(layer "B.Fab")
		)
		(fp_line
			(start 0.12065 -0.305054)
			(end 0.12065 -0.2794)
			(stroke
				(width 0.1)
				(type default)
			)
			(layer "B.Fab")
		)
		(fp_line
			(start -0.12065 -0.3048)
			(end -0.67945 -0.3048)
			(stroke
				(width 0.1)
				(type default)
			)
			(layer "B.Fab")
		)
		(fp_line
			(start -0.67945 -0.3048)
			(end -0.67945 0.3048)
			(stroke
				(width 0.1)
				(type default)
			)
			(layer "B.Fab")
		)
		(fp_line
			(start 0.12065 -0.2794)
			(end -0.12065 -0.2794)
			(stroke
				(width 0.1)
				(type default)
			)
			(layer "B.Fab")
		)
		(fp_line
			(start -0.12065 -0.2794)
			(end -0.12065 -0.3048)
			(stroke
				(width 0.1)
				(type default)
			)
			(layer "B.Fab")
		)
		(fp_line
			(start 0.12065 0.2794)
			(end 0.12065 0.3048)
			(stroke
				(width 0.1)
				(type default)
			)
			(layer "B.Fab")
		)
		(fp_line
			(start -0.120396 0.2794)
			(end 0.12065 0.2794)
			(stroke
				(width 0.1)
				(type default)
			)
			(layer "B.Fab")
		)
		(fp_line
			(start 0.67945 0.3048)
			(end 0.67945 -0.305054)
			(stroke
				(width 0.1)
				(type default)
			)
			(layer "B.Fab")
		)
		(fp_line
			(start 0.12065 0.3048)
			(end 0.67945 0.3048)
			(stroke
				(width 0.1)
				(type default)
			)
			(layer "B.Fab")
		)
		(fp_line
			(start -0.120396 0.3048)
			(end -0.120396 0.2794)
			(stroke
				(width 0.1)
				(type default)
			)
			(layer "B.Fab")
		)
		(fp_line
			(start -0.67945 0.3048)
			(end -0.120396 0.3048)
			(stroke
				(width 0.1)
				(type default)
			)
			(layer "B.Fab")
		)
		(pad "1" smd circle
			(at 0.40005 0 270)
			(size 0 0)
			(layers "B.Cu" "B.Mask" "B.Paste")
			(net "P52V_HS2_GATE1_R")
		)
		(pad "2" smd circle
			(at -0.40005 0 270)
			(size 0 0)
			(layers "B.Cu" "B.Mask" "B.Paste")
			(net "P52V_HS2_4287_GATE_R")
		)
	)
	(footprint ""
		(layer "B.Cu")
		(at 295.656 -85.852)
		(property "Reference" "C104"
			(at 0 0 0)
			(layer "B.SilkS")
			(hide yes)
			(effects
				(font
					(size 1.27 1.27)
				)
				(justify mirror)
			)
		)
		(property "Value" ""
			(at 0 0 0)
			(layer "B.Fab")
			(effects
				(font
					(size 1.27 1.27)
				)
				(justify mirror)
			)
		)
		(duplicate_pad_numbers_are_jumpers no)
		(fp_line
			(start -0.7874 -0.4064)
			(end -0.7874 0.4064)
			(stroke
				(width 0.1524)
				(type default)
			)
			(layer "B.SilkS")
		)
		(fp_line
			(start -0.7874 0.4064)
			(end 0.7874 0.4064)
			(stroke
				(width 0.1524)
				(type default)
			)
			(layer "B.SilkS")
		)
		(fp_line
			(start 0.7874 -0.4064)
			(end -0.7874 -0.4064)
			(stroke
				(width 0.1524)
				(type default)
			)
			(layer "B.SilkS")
		)
		(fp_line
			(start 0.7874 0.4064)
			(end 0.7874 -0.4064)
			(stroke
				(width 0.1524)
				(type default)
			)
			(layer "B.SilkS")
		)
		(fp_line
			(start -0.67945 -0.3048)
			(end -0.67945 0.3048)
			(stroke
				(width 0.1)
				(type default)
			)
			(layer "B.Fab")
		)
		(fp_line
			(start -0.67945 0.3048)
			(end -0.120396 0.3048)
			(stroke
				(width 0.1)
				(type default)
			)
			(layer "B.Fab")
		)
		(fp_line
			(start -0.12065 -0.3048)
			(end -0.67945 -0.3048)
			(stroke
				(width 0.1)
				(type default)
			)
			(layer "B.Fab")
		)
		(fp_line
			(start -0.12065 -0.2794)
			(end -0.12065 -0.3048)
			(stroke
				(width 0.1)
				(type default)
			)
			(layer "B.Fab")
		)
		(fp_line
			(start -0.120396 0.2794)
			(end 0.12065 0.2794)
			(stroke
				(width 0.1)
				(type default)
			)
			(layer "B.Fab")
		)
		(fp_line
			(start -0.120396 0.3048)
			(end -0.120396 0.2794)
			(stroke
				(width 0.1)
				(type default)
			)
			(layer "B.Fab")
		)
		(fp_line
			(start 0.12065 -0.305054)
			(end 0.12065 -0.2794)
			(stroke
				(width 0.1)
				(type default)
			)
			(layer "B.Fab")
		)
		(fp_line
			(start 0.12065 -0.2794)
			(end -0.12065 -0.2794)
			(stroke
				(width 0.1)
				(type default)
			)
			(layer "B.Fab")
		)
		(fp_line
			(start 0.12065 0.2794)
			(end 0.12065 0.3048)
			(stroke
				(width 0.1)
				(type default)
			)
			(layer "B.Fab")
		)
		(fp_line
			(start 0.12065 0.3048)
			(end 0.67945 0.3048)
			(stroke
				(width 0.1)
				(type default)
			)
			(layer "B.Fab")
		)
		(fp_line
			(start 0.67945 -0.305054)
			(end 0.12065 -0.305054)
			(stroke
				(width 0.1)
				(type default)
			)
			(layer "B.Fab")
		)
		(fp_line
			(start 0.67945 0.3048)
			(end 0.67945 -0.305054)
			(stroke
				(width 0.1)
				(type default)
			)
			(layer "B.Fab")
		)
		(pad "1" smd circle
			(at 0.40005 0 180)
			(size 0 0)
			(layers "B.Cu" "B.Mask" "B.Paste")
			(net "GND")
		)
		(pad "2" smd circle
			(at -0.40005 0 180)
			(size 0 0)
			(layers "B.Cu" "B.Mask" "B.Paste")
			(net "P3V3_AUX")
		)
	)
	(footprint ""
		(layer "B.Cu")
		(at 105.918 -41.148 90)
		(property "Reference" "PC597"
			(at 0 0 90)
			(layer "B.SilkS")
			(hide yes)
			(effects
				(font
					(size 1.27 1.27)
				)
				(justify mirror)
			)
		)
		(property "Value" ""
			(at 0 0 90)
			(layer "B.Fab")
			(effects
				(font
					(size 1.27 1.27)
				)
				(justify mirror)
			)
		)
		(duplicate_pad_numbers_are_jumpers no)
		(fp_line
			(start 1.2954 -0.5842)
			(end -1.2954 -0.5842)
			(stroke
				(width 0.1524)
				(type default)
			)
			(layer "B.SilkS")
		)
		(fp_line
			(start -1.2954 -0.5842)
			(end -1.2954 0.5842)
			(stroke
				(width 0.1524)
				(type default)
			)
			(layer "B.SilkS")
		)
		(fp_line
			(start 1.2954 0.5842)
			(end 1.2954 -0.5842)
			(stroke
				(width 0.1524)
				(type default)
			)
			(layer "B.SilkS")
		)
		(fp_line
			(start -1.2954 0.5842)
			(end 1.2954 0.5842)
			(stroke
				(width 0.1524)
				(type default)
			)
			(layer "B.SilkS")
		)
		(fp_line
			(start 0.8636 -0.4572)
			(end -0.8636 -0.4572)
			(stroke
				(width 0.1)
				(type default)
			)
			(layer "B.Fab")
		)
		(fp_line
			(start -0.8636 -0.4572)
			(end -0.8636 -0.4064)
			(stroke
				(width 0.1)
				(type default)
			)
			(layer "B.Fab")
		)
		(fp_line
			(start 1.1938 -0.4064)
			(end 0.8636 -0.4064)
			(stroke
				(width 0.1)
				(type default)
			)
			(layer "B.Fab")
		)
		(fp_line
			(start 0.8636 -0.4064)
			(end 0.8636 -0.4572)
			(stroke
				(width 0.1)
				(type default)
			)
			(layer "B.Fab")
		)
		(fp_line
			(start -0.8636 -0.4064)
			(end -1.1938 -0.4064)
			(stroke
				(width 0.1)
				(type default)
			)
			(layer "B.Fab")
		)
		(fp_line
			(start -1.1938 -0.4064)
			(end -1.1938 0.4064)
			(stroke
				(width 0.1)
				(type default)
			)
			(layer "B.Fab")
		)
		(fp_line
			(start 1.1938 0.4064)
			(end 1.1938 -0.4064)
			(stroke
				(width 0.1)
				(type default)
			)
			(layer "B.Fab")
		)
		(fp_line
			(start 0.8636 0.4064)
			(end 1.1938 0.4064)
			(stroke
				(width 0.1)
				(type default)
			)
			(layer "B.Fab")
		)
		(fp_line
			(start -0.8636 0.4064)
			(end -0.8636 0.4572)
			(stroke
				(width 0.1)
				(type default)
			)
			(layer "B.Fab")
		)
		(fp_line
			(start -1.1938 0.4064)
			(end -0.8636 0.4064)
			(stroke
				(width 0.1)
				(type default)
			)
			(layer "B.Fab")
		)
		(fp_line
			(start 0.8636 0.4572)
			(end 0.8636 0.4064)
			(stroke
				(width 0.1)
				(type default)
			)
			(layer "B.Fab")
		)
		(fp_line
			(start -0.8636 0.4572)
			(end 0.8636 0.4572)
			(stroke
				(width 0.1)
				(type default)
			)
			(layer "B.Fab")
		)
		(pad "1" smd rect
			(at 0.7366 0)
			(size 0.7112 0.8128)
			(layers "B.Cu" "B.Mask" "B.Paste")
			(net "P52V_HS2_4287_GATE2_R")
		)
		(pad "2" smd rect
			(at -0.7366 0)
			(size 0.7112 0.8128)
			(layers "B.Cu" "B.Mask" "B.Paste")
			(net "P52V_HS2")
		)
	)
	(footprint ""
		(layer "B.Cu")
		(at 107.188 -54.864 90)
		(property "Reference" "PR7000"
			(at 0 0 90)
			(layer "B.SilkS")
			(hide yes)
			(effects
				(font
					(size 1.27 1.27)
				)
				(justify mirror)
			)
		)
		(property "Value" ""
			(at 0 0 90)
			(layer "B.Fab")
			(effects
				(font
					(size 1.27 1.27)
				)
				(justify mirror)
			)
		)
		(duplicate_pad_numbers_are_jumpers no)
		(fp_line
			(start 0.7874 -0.4064)
			(end -0.7874 -0.4064)
			(stroke
				(width 0.1524)
				(type default)
			)
			(layer "B.SilkS")
		)
		(fp_line
			(start -0.7874 -0.4064)
			(end -0.7874 0.4064)
			(stroke
				(width 0.1524)
				(type default)
			)
			(layer "B.SilkS")
		)
		(fp_line
			(start 0.7874 0.4064)
			(end 0.7874 -0.4064)
			(stroke
				(width 0.1524)
				(type default)
			)
			(layer "B.SilkS")
		)
		(fp_line
			(start -0.7874 0.4064)
			(end 0.7874 0.4064)
			(stroke
				(width 0.1524)
				(type default)
			)
			(layer "B.SilkS")
		)
		(fp_line
			(start 0.67945 -0.305054)
			(end 0.12065 -0.305054)
			(stroke
				(width 0.1)
				(type default)
			)
			(layer "B.Fab")
		)
		(fp_line
			(start 0.12065 -0.305054)
			(end 0.12065 -0.2794)
			(stroke
				(width 0.1)
				(type default)
			)
			(layer "B.Fab")
		)
		(fp_line
			(start -0.12065 -0.3048)
			(end -0.67945 -0.3048)
			(stroke
				(width 0.1)
				(type default)
			)
			(layer "B.Fab")
		)
		(fp_line
			(start -0.67945 -0.3048)
			(end -0.67945 0.3048)
			(stroke
				(width 0.1)
				(type default)
			)
			(layer "B.Fab")
		)
		(fp_line
			(start 0.12065 -0.2794)
			(end -0.12065 -0.2794)
			(stroke
				(width 0.1)
				(type default)
			)
			(layer "B.Fab")
		)
		(fp_line
			(start -0.12065 -0.2794)
			(end -0.12065 -0.3048)
			(stroke
				(width 0.1)
				(type default)
			)
			(layer "B.Fab")
		)
		(fp_line
			(start 0.12065 0.2794)
			(end 0.12065 0.3048)
			(stroke
				(width 0.1)
				(type default)
			)
			(layer "B.Fab")
		)
		(fp_line
			(start -0.120396 0.2794)
			(end 0.12065 0.2794)
			(stroke
				(width 0.1)
				(type default)
			)
			(layer "B.Fab")
		)
		(fp_line
			(start 0.67945 0.3048)
			(end 0.67945 -0.305054)
			(stroke
				(width 0.1)
				(type default)
			)
			(layer "B.Fab")
		)
		(fp_line
			(start 0.12065 0.3048)
			(end 0.67945 0.3048)
			(stroke
				(width 0.1)
				(type default)
			)
			(layer "B.Fab")
		)
		(fp_line
			(start -0.120396 0.3048)
			(end -0.120396 0.2794)
			(stroke
				(width 0.1)
				(type default)
			)
			(layer "B.Fab")
		)
		(fp_line
			(start -0.67945 0.3048)
			(end -0.120396 0.3048)
			(stroke
				(width 0.1)
				(type default)
			)
			(layer "B.Fab")
		)
		(pad "1" smd rect
			(at 0.40005 0 90)
			(size 0.4572 0.508)
			(layers "B.Cu" "B.Mask" "B.Paste")
			(net "P52V_HS2_GATE_R1")
		)
		(pad "2" smd rect
			(at -0.40005 0 90)
			(size 0.4572 0.508)
			(layers "B.Cu" "B.Mask" "B.Paste")
			(net "P52V_HS2_4287_GATE_R")
		)
	)
	(footprint ""
		(layer "B.Cu")
		(at 426.593 -35.941)
		(property "Reference" "R5932"
			(at 0 0 0)
			(layer "B.SilkS")
			(hide yes)
			(effects
				(font
					(size 1.27 1.27)
				)
				(justify mirror)
			)
		)
		(property "Value" ""
			(at 0 0 0)
			(layer "B.Fab")
			(effects
				(font
					(size 1.27 1.27)
				)
				(justify mirror)
			)
		)
		(duplicate_pad_numbers_are_jumpers no)
		(fp_line
			(start -0.7874 -0.4064)
			(end -0.7874 0.4064)
			(stroke
				(width 0.1524)
				(type default)
			)
			(layer "B.SilkS")
		)
		(fp_line
			(start -0.7874 0.4064)
			(end 0.7874 0.4064)
			(stroke
				(width 0.1524)
				(type default)
			)
			(layer "B.SilkS")
		)
		(fp_line
			(start 0.7874 -0.4064)
			(end -0.7874 -0.4064)
			(stroke
				(width 0.1524)
				(type default)
			)
			(layer "B.SilkS")
		)
		(fp_line
			(start 0.7874 0.4064)
			(end 0.7874 -0.4064)
			(stroke
				(width 0.1524)
				(type default)
			)
			(layer "B.SilkS")
		)
		(fp_line
			(start -0.67945 -0.3048)
			(end -0.67945 0.3048)
			(stroke
				(width 0.1)
				(type default)
			)
			(layer "B.Fab")
		)
		(fp_line
			(start -0.67945 0.3048)
			(end -0.120396 0.3048)
			(stroke
				(width 0.1)
				(type default)
			)
			(layer "B.Fab")
		)
		(fp_line
			(start -0.12065 -0.3048)
			(end -0.67945 -0.3048)
			(stroke
				(width 0.1)
				(type default)
			)
			(layer "B.Fab")
		)
		(fp_line
			(start -0.12065 -0.2794)
			(end -0.12065 -0.3048)
			(stroke
				(width 0.1)
				(type default)
			)
			(layer "B.Fab")
		)
		(fp_line
			(start -0.120396 0.2794)
			(end 0.12065 0.2794)
			(stroke
				(width 0.1)
				(type default)
			)
			(layer "B.Fab")
		)
		(fp_line
			(start -0.120396 0.3048)
			(end -0.120396 0.2794)
			(stroke
				(width 0.1)
				(type default)
			)
			(layer "B.Fab")
		)
		(fp_line
			(start 0.12065 -0.305054)
			(end 0.12065 -0.2794)
			(stroke
				(width 0.1)
				(type default)
			)
			(layer "B.Fab")
		)
		(fp_line
			(start 0.12065 -0.2794)
			(end -0.12065 -0.2794)
			(stroke
				(width 0.1)
				(type default)
			)
			(layer "B.Fab")
		)
		(fp_line
			(start 0.12065 0.2794)
			(end 0.12065 0.3048)
			(stroke
				(width 0.1)
				(type default)
			)
			(layer "B.Fab")
		)
		(fp_line
			(start 0.12065 0.3048)
			(end 0.67945 0.3048)
			(stroke
				(width 0.1)
				(type default)
			)
			(layer "B.Fab")
		)
		(fp_line
			(start 0.67945 -0.305054)
			(end 0.12065 -0.305054)
			(stroke
				(width 0.1)
				(type default)
			)
			(layer "B.Fab")
		)
		(fp_line
			(start 0.67945 0.3048)
			(end 0.67945 -0.305054)
			(stroke
				(width 0.1)
				(type default)
			)
			(layer "B.Fab")
		)
		(pad "1" smd circle
			(at 0.40005 0 180)
			(size 0 0)
			(layers "B.Cu" "B.Mask" "B.Paste")
			(net "SMB_PDB_MISC_SDA")
		)
		(pad "2" smd circle
			(at -0.40005 0 180)
			(size 0 0)
			(layers "B.Cu" "B.Mask" "B.Paste")
			(net "SMB_IOEXP_2_SDA")
		)
	)
	(footprint ""
		(layer "B.Cu")
		(at 295.0464 -60.833)
		(property "Reference" "PC3"
			(at 0 0 0)
			(layer "B.SilkS")
			(hide yes)
			(effects
				(font
					(size 1.27 1.27)
				)
				(justify mirror)
			)
		)
		(property "Value" ""
			(at 0 0 0)
			(layer "B.Fab")
			(effects
				(font
					(size 1.27 1.27)
				)
				(justify mirror)
			)
		)
		(duplicate_pad_numbers_are_jumpers no)
		(fp_line
			(start -2.2098 -0.9398)
			(end -2.2098 0.9398)
			(stroke
				(width 0.1524)
				(type default)
			)
			(layer "B.SilkS")
		)
		(fp_line
			(start -2.2098 0.9398)
			(end 2.2098 0.9398)
			(stroke
				(width 0.1524)
				(type default)
			)
			(layer "B.SilkS")
		)
		(fp_line
			(start 2.2098 -0.9398)
			(end -2.2098 -0.9398)
			(stroke
				(width 0.1524)
				(type default)
			)
			(layer "B.SilkS")
		)
		(fp_line
			(start 2.2098 0.9398)
			(end 2.2098 -0.9398)
			(stroke
				(width 0.1524)
				(type default)
			)
			(layer "B.SilkS")
		)
		(fp_line
			(start -2.1082 -0.8382)
			(end -2.1082 0.8382)
			(stroke
				(width 0.1)
				(type default)
			)
			(layer "B.Fab")
		)
		(fp_line
			(start -2.1082 0.8382)
			(end -1.6764 0.8382)
			(stroke
				(width 0.1)
				(type default)
			)
			(layer "B.Fab")
		)
		(fp_line
			(start -1.6764 -0.9398)
			(end -1.6764 -0.889)
			(stroke
				(width 0.1)
				(type default)
			)
			(layer "B.Fab")
		)
		(fp_line
			(start -1.6764 -0.889)
			(end -1.6764 -0.8382)
			(stroke
				(width 0.1)
				(type default)
			)
			(layer "B.Fab")
		)
		(fp_line
			(start -1.6764 -0.8382)
			(end -2.1082 -0.8382)
			(stroke
				(width 0.1)
				(type default)
			)
			(layer "B.Fab")
		)
		(fp_line
			(start -1.6764 0.8382)
			(end -1.6764 0.889)
			(stroke
				(width 0.1)
				(type default)
			)
			(layer "B.Fab")
		)
		(fp_line
			(start -1.6764 0.889)
			(end -1.6764 0.9398)
			(stroke
				(width 0.1)
				(type default)
			)
			(layer "B.Fab")
		)
		(fp_line
			(start -1.6764 0.9398)
			(end 1.6764 0.9398)
			(stroke
				(width 0.1)
				(type default)
			)
			(layer "B.Fab")
		)
		(fp_line
			(start 1.6764 -0.9398)
			(end -1.6764 -0.9398)
			(stroke
				(width 0.1)
				(type default)
			)
			(layer "B.Fab")
		)
		(fp_line
			(start 1.6764 -0.889)
			(end 1.6764 -0.9398)
			(stroke
				(width 0.1)
				(type default)
			)
			(layer "B.Fab")
		)
		(fp_line
			(start 1.6764 -0.8382)
			(end 1.6764 -0.889)
			(stroke
				(width 0.1)
				(type default)
			)
			(layer "B.Fab")
		)
		(fp_line
			(start 1.6764 0.8382)
			(end 2.1082 0.8382)
			(stroke
				(width 0.1)
				(type default)
			)
			(layer "B.Fab")
		)
		(fp_line
			(start 1.6764 0.889)
			(end 1.6764 0.8382)
			(stroke
				(width 0.1)
				(type default)
			)
			(layer "B.Fab")
		)
		(fp_line
			(start 1.6764 0.9398)
			(end 1.6764 0.889)
			(stroke
				(width 0.1)
				(type default)
			)
			(layer "B.Fab")
		)
		(fp_line
			(start 2.1082 -0.8382)
			(end 1.6764 -0.8382)
			(stroke
				(width 0.1)
				(type default)
			)
			(layer "B.Fab")
		)
		(fp_line
			(start 2.1082 0.8382)
			(end 2.1082 -0.8382)
			(stroke
				(width 0.1)
				(type default)
			)
			(layer "B.Fab")
		)
		(pad "1" smd rect
			(at 1.4732 0)
			(size 1.1684 1.5748)
			(layers "B.Cu" "B.Mask" "B.Paste")
			(net "P52V_1")
		)
		(pad "2" smd rect
			(at -1.4732 0)
			(size 1.1684 1.5748)
			(layers "B.Cu" "B.Mask" "B.Paste")
			(net "GND_FIELD_SIGNAL")
		)
	)
	(footprint ""
		(layer "B.Cu")
		(at 414.842198 -24.468836)
		(property "Reference" "C95"
			(at 0 0 0)
			(layer "B.SilkS")
			(hide yes)
			(effects
				(font
					(size 1.27 1.27)
				)
				(justify mirror)
			)
		)
		(property "Value" ""
			(at 0 0 0)
			(layer "B.Fab")
			(effects
				(font
					(size 1.27 1.27)
				)
				(justify mirror)
			)
		)
		(duplicate_pad_numbers_are_jumpers no)
		(fp_line
			(start -1.524 -0.762)
			(end -1.524 0.762)
			(stroke
				(width 0.1524)
				(type default)
			)
			(layer "B.SilkS")
		)
		(fp_line
			(start -1.524 0.762)
			(end 1.524 0.762)
			(stroke
				(width 0.1524)
				(type default)
			)
			(layer "B.SilkS")
		)
		(fp_line
			(start 1.524 -0.762)
			(end -1.524 -0.762)
			(stroke
				(width 0.1524)
				(type default)
			)
			(layer "B.SilkS")
		)
		(fp_line
			(start 1.524 0.762)
			(end 1.524 -0.762)
			(stroke
				(width 0.1524)
				(type default)
			)
			(layer "B.SilkS")
		)
		(fp_line
			(start -1.1049 -0.724916)
			(end 1.1049 -0.724916)
			(stroke
				(width 0.1)
				(type default)
			)
			(layer "B.Fab")
		)
		(fp_line
			(start -1.1049 0.724916)
			(end -1.1049 -0.724916)
			(stroke
				(width 0.1)
				(type default)
			)
			(layer "B.Fab")
		)
		(fp_line
			(start 1.1049 -0.724916)
			(end 1.1049 0.724916)
			(stroke
				(width 0.1)
				(type default)
			)
			(layer "B.Fab")
		)
		(fp_line
			(start 1.1049 0.724916)
			(end -1.1049 0.724916)
			(stroke
				(width 0.1)
				(type default)
			)
			(layer "B.Fab")
		)
		(pad "1" smd rect
			(at 0.889 0)
			(size 1.016 1.27)
			(layers "B.Cu" "B.Mask" "B.Paste")
			(net "P12V_FAN_LED")
		)
		(pad "2" smd rect
			(at -0.889 0)
			(size 1.016 1.27)
			(layers "B.Cu" "B.Mask" "B.Paste")
			(net "GND")
		)
	)
	(footprint ""
		(layer "B.Cu")
		(at 176.449736 -76.708 180)
		(property "Reference" "PR7029"
			(at 0 0 0)
			(layer "B.SilkS")
			(hide yes)
			(effects
				(font
					(size 1.27 1.27)
				)
				(justify mirror)
			)
		)
		(property "Value" ""
			(at 0 0 0)
			(layer "B.Fab")
			(effects
				(font
					(size 1.27 1.27)
				)
				(justify mirror)
			)
		)
		(duplicate_pad_numbers_are_jumpers no)
		(fp_line
			(start 0.7874 0.4064)
			(end 0.7874 -0.4064)
			(stroke
				(width 0.1524)
				(type default)
			)
			(layer "B.SilkS")
		)
		(fp_line
			(start 0.7874 -0.4064)
			(end -0.7874 -0.4064)
			(stroke
				(width 0.1524)
				(type default)
			)
			(layer "B.SilkS")
		)
		(fp_line
			(start -0.7874 0.4064)
			(end 0.7874 0.4064)
			(stroke
				(width 0.1524)
				(type default)
			)
			(layer "B.SilkS")
		)
		(fp_line
			(start -0.7874 -0.4064)
			(end -0.7874 0.4064)
			(stroke
				(width 0.1524)
				(type default)
			)
			(layer "B.SilkS")
		)
		(fp_line
			(start 0.67945 0.3048)
			(end 0.67945 -0.305054)
			(stroke
				(width 0.1)
				(type default)
			)
			(layer "B.Fab")
		)
		(fp_line
			(start 0.67945 -0.305054)
			(end 0.12065 -0.305054)
			(stroke
				(width 0.1)
				(type default)
			)
			(layer "B.Fab")
		)
		(fp_line
			(start 0.12065 0.3048)
			(end 0.67945 0.3048)
			(stroke
				(width 0.1)
				(type default)
			)
			(layer "B.Fab")
		)
		(fp_line
			(start 0.12065 0.2794)
			(end 0.12065 0.3048)
			(stroke
				(width 0.1)
				(type default)
			)
			(layer "B.Fab")
		)
		(fp_line
			(start 0.12065 -0.2794)
			(end -0.12065 -0.2794)
			(stroke
				(width 0.1)
				(type default)
			)
			(layer "B.Fab")
		)
		(fp_line
			(start 0.12065 -0.305054)
			(end 0.12065 -0.2794)
			(stroke
				(width 0.1)
				(type default)
			)
			(layer "B.Fab")
		)
		(fp_line
			(start -0.120396 0.3048)
			(end -0.120396 0.2794)
			(stroke
				(width 0.1)
				(type default)
			)
			(layer "B.Fab")
		)
		(fp_line
			(start -0.120396 0.2794)
			(end 0.12065 0.2794)
			(stroke
				(width 0.1)
				(type default)
			)
			(layer "B.Fab")
		)
		(fp_line
			(start -0.12065 -0.2794)
			(end -0.12065 -0.3048)
			(stroke
				(width 0.1)
				(type default)
			)
			(layer "B.Fab")
		)
		(fp_line
			(start -0.12065 -0.3048)
			(end -0.67945 -0.3048)
			(stroke
				(width 0.1)
				(type default)
			)
			(layer "B.Fab")
		)
		(fp_line
			(start -0.67945 0.3048)
			(end -0.120396 0.3048)
			(stroke
				(width 0.1)
				(type default)
			)
			(layer "B.Fab")
		)
		(fp_line
			(start -0.67945 -0.3048)
			(end -0.67945 0.3048)
			(stroke
				(width 0.1)
				(type default)
			)
			(layer "B.Fab")
		)
		(pad "1" smd circle
			(at 0.40005 0)
			(size 0 0)
			(layers "B.Cu" "B.Mask" "B.Paste")
			(net "PWRGD_P52V_HS2_PG")
		)
		(pad "2" smd circle
			(at -0.40005 0)
			(size 0 0)
			(layers "B.Cu" "B.Mask" "B.Paste")
			(net "P52V_HS2_PWRGIN")
		)
	)
	(footprint ""
		(layer "B.Cu")
		(at 159.685736 -61.722 180)
		(property "Reference" "U32"
			(at -2.112264 2.38633 0)
			(unlocked yes)
			(layer "B.SilkS")
			(effects
				(font
					(size 0.7874 0.5842)
					(thickness 0.1524)
				)
				(justify left mirror)
			)
		)
		(property "Value" ""
			(at 0 0 0)
			(layer "B.Fab")
			(effects
				(font
					(size 1.27 1.27)
				)
				(justify mirror)
			)
		)
		(duplicate_pad_numbers_are_jumpers no)
		(fp_line
			(start 2.249932 1.549908)
			(end -2.249932 1.549908)
			(stroke
				(width 0.1524)
				(type default)
			)
			(layer "B.SilkS")
		)
		(fp_line
			(start 2.249932 -1.549908)
			(end 2.249932 1.549908)
			(stroke
				(width 0.1524)
				(type default)
			)
			(layer "B.SilkS")
		)
		(fp_line
			(start 0.737108 -1.549908)
			(end 2.249932 -1.549908)
			(stroke
				(width 0.1524)
				(type default)
			)
			(layer "B.SilkS")
		)
		(fp_line
			(start 0 -0.8128)
			(end 0.737108 -1.549908)
			(stroke
				(width 0.1524)
				(type default)
			)
			(layer "B.SilkS")
		)
		(fp_line
			(start -0.737108 -1.549908)
			(end 0 -0.8128)
			(stroke
				(width 0.1524)
				(type default)
			)
			(layer "B.SilkS")
		)
		(fp_line
			(start -2.249932 1.549908)
			(end -2.249932 -1.549908)
			(stroke
				(width 0.1524)
				(type default)
			)
			(layer "B.SilkS")
		)
		(fp_line
			(start -2.249932 -1.549908)
			(end -0.737108 -1.549908)
			(stroke
				(width 0.1524)
				(type default)
			)
			(layer "B.SilkS")
		)
		(fp_poly
			(pts
				(xy 4.7498 -0.467106) (xy 4.7498 -1.483106) (xy 3.7338 -0.975106)
			)
			(stroke
				(width 0)
				(type default)
			)
			(fill yes)
			(layer "B.SilkS")
		)
		(fp_line
			(start 2.249932 1.549908)
			(end -2.249932 1.549908)
			(stroke
				(width 0.1)
				(type default)
			)
			(layer "B.Fab")
		)
		(fp_line
			(start 2.249932 -1.549908)
			(end 2.249932 1.549908)
			(stroke
				(width 0.1)
				(type default)
			)
			(layer "B.Fab")
		)
		(fp_line
			(start -2.249932 1.549908)
			(end -2.249932 -1.549908)
			(stroke
				(width 0.1)
				(type default)
			)
			(layer "B.Fab")
		)
		(fp_line
			(start -2.249932 -1.549908)
			(end 2.249932 -1.549908)
			(stroke
				(width 0.1)
				(type default)
			)
			(layer "B.Fab")
		)
		(fp_poly
			(pts
				(xy 4.7498 -0.467106) (xy 4.7498 -1.483106) (xy 3.7338 -0.975106)
			)
			(stroke
				(width 0)
				(type default)
			)
			(fill yes)
			(layer "B.Fab")
		)
		(pad "1" smd rect
			(at 3.052572 -0.975106 90)
			(size 0.381 1.1684)
			(layers "B.Cu" "B.Mask" "B.Paste")
			(net "P52V_HS2_CS")
		)
		(pad "2" smd rect
			(at 3.052572 -0.32512 90)
			(size 0.381 1.1684)
			(layers "B.Cu" "B.Mask" "B.Paste")
			(net "P52V_HS2_SIO")
		)
		(pad "3" smd rect
			(at 3.052572 0.32512 90)
			(size 0.381 1.1684)
			(layers "B.Cu" "B.Mask" "B.Paste")
			(net "P52V_HS2_DVCC")
		)
		(pad "4" smd rect
			(at 3.052572 0.975106 90)
			(size 0.381 1.1684)
			(layers "B.Cu" "B.Mask" "B.Paste")
			(net "GND")
		)
		(pad "5" smd rect
			(at -3.052572 0.975106 90)
			(size 0.381 1.1684)
			(layers "B.Cu" "B.Mask" "B.Paste")
			(net "P52V_HS2_SIO")
		)
		(pad "6" smd rect
			(at -3.052572 0.32512 90)
			(size 0.381 1.1684)
			(layers "B.Cu" "B.Mask" "B.Paste")
			(net "P52V_HS2_SCK")
		)
		(pad "7" smd rect
			(at -3.052572 -0.32512 90)
			(size 0.381 1.1684)
			(layers "B.Cu" "B.Mask" "B.Paste")
			(net "P52V_HS2_DVCC")
		)
		(pad "8" smd rect
			(at -3.052572 -0.975106 90)
			(size 0.381 1.1684)
			(layers "B.Cu" "B.Mask" "B.Paste")
			(net "P52V_HS2_DVCC")
		)
	)
	(footprint ""
		(layer "B.Cu")
		(at 284.8864 -69.723)
		(property "Reference" "PR28"
			(at 0 0 0)
			(layer "B.SilkS")
			(hide yes)
			(effects
				(font
					(size 1.27 1.27)
				)
				(justify mirror)
			)
		)
		(property "Value" ""
			(at 0 0 0)
			(layer "B.Fab")
			(effects
				(font
					(size 1.27 1.27)
				)
				(justify mirror)
			)
		)
		(duplicate_pad_numbers_are_jumpers no)
		(fp_line
			(start -0.7874 -0.4064)
			(end -0.7874 0.4064)
			(stroke
				(width 0.1524)
				(type default)
			)
			(layer "B.SilkS")
		)
		(fp_line
			(start -0.7874 0.4064)
			(end 0.7874 0.4064)
			(stroke
				(width 0.1524)
				(type default)
			)
			(layer "B.SilkS")
		)
		(fp_line
			(start 0.7874 -0.4064)
			(end -0.7874 -0.4064)
			(stroke
				(width 0.1524)
				(type default)
			)
			(layer "B.SilkS")
		)
		(fp_line
			(start 0.7874 0.4064)
			(end 0.7874 -0.4064)
			(stroke
				(width 0.1524)
				(type default)
			)
			(layer "B.SilkS")
		)
		(fp_line
			(start -0.67945 -0.3048)
			(end -0.67945 0.3048)
			(stroke
				(width 0.1)
				(type default)
			)
			(layer "B.Fab")
		)
		(fp_line
			(start -0.67945 0.3048)
			(end -0.120396 0.3048)
			(stroke
				(width 0.1)
				(type default)
			)
			(layer "B.Fab")
		)
		(fp_line
			(start -0.12065 -0.3048)
			(end -0.67945 -0.3048)
			(stroke
				(width 0.1)
				(type default)
			)
			(layer "B.Fab")
		)
		(fp_line
			(start -0.12065 -0.2794)
			(end -0.12065 -0.3048)
			(stroke
				(width 0.1)
				(type default)
			)
			(layer "B.Fab")
		)
		(fp_line
			(start -0.120396 0.2794)
			(end 0.12065 0.2794)
			(stroke
				(width 0.1)
				(type default)
			)
			(layer "B.Fab")
		)
		(fp_line
			(start -0.120396 0.3048)
			(end -0.120396 0.2794)
			(stroke
				(width 0.1)
				(type default)
			)
			(layer "B.Fab")
		)
		(fp_line
			(start 0.12065 -0.305054)
			(end 0.12065 -0.2794)
			(stroke
				(width 0.1)
				(type default)
			)
			(layer "B.Fab")
		)
		(fp_line
			(start 0.12065 -0.2794)
			(end -0.12065 -0.2794)
			(stroke
				(width 0.1)
				(type default)
			)
			(layer "B.Fab")
		)
		(fp_line
			(start 0.12065 0.2794)
			(end 0.12065 0.3048)
			(stroke
				(width 0.1)
				(type default)
			)
			(layer "B.Fab")
		)
		(fp_line
			(start 0.12065 0.3048)
			(end 0.67945 0.3048)
			(stroke
				(width 0.1)
				(type default)
			)
			(layer "B.Fab")
		)
		(fp_line
			(start 0.67945 -0.305054)
			(end 0.12065 -0.305054)
			(stroke
				(width 0.1)
				(type default)
			)
			(layer "B.Fab")
		)
		(fp_line
			(start 0.67945 0.3048)
			(end 0.67945 -0.305054)
			(stroke
				(width 0.1)
				(type default)
			)
			(layer "B.Fab")
		)
		(pad "1" smd circle
			(at 0.40005 0 180)
			(size 0 0)
			(layers "B.Cu" "B.Mask" "B.Paste")
			(net "P52V_HS1_SCK")
		)
		(pad "2" smd circle
			(at -0.40005 0 180)
			(size 0 0)
			(layers "B.Cu" "B.Mask" "B.Paste")
			(net "GND_FIELD_SIGNAL")
		)
	)
	(footprint ""
		(layer "B.Cu")
		(at 169.77868 -151.939498 -90)
		(property "Reference" "J13"
			(at 3.5052 -5.552948 270)
			(unlocked yes)
			(layer "B.SilkS")
			(effects
				(font
					(size 0.7874 0.5842)
					(thickness 0.1524)
				)
				(justify left mirror)
			)
		)
		(property "Value" ""
			(at 0 0 90)
			(layer "B.Fab")
			(effects
				(font
					(size 1.27 1.27)
				)
				(justify mirror)
			)
		)
		(duplicate_pad_numbers_are_jumpers no)
		(fp_line
			(start 0 4.011168)
			(end 3.330702 -4.771136)
			(stroke
				(width 0.1524)
				(type default)
			)
			(layer "B.SilkS")
		)
		(fp_line
			(start -3.330702 -4.771136)
			(end 0 4.011168)
			(stroke
				(width 0.1524)
				(type default)
			)
			(layer "B.SilkS")
		)
		(fp_line
			(start 3.330702 -4.771136)
			(end -3.330702 -4.771136)
			(stroke
				(width 0.1524)
				(type default)
			)
			(layer "B.SilkS")
		)
		(fp_line
			(start 0 4.011168)
			(end 3.330702 -4.771136)
			(stroke
				(width 0.1)
				(type default)
			)
			(layer "B.Fab")
		)
		(fp_line
			(start -3.330702 -4.771136)
			(end 0 4.011168)
			(stroke
				(width 0.1)
				(type default)
			)
			(layer "B.Fab")
		)
		(fp_line
			(start 3.330702 -4.771136)
			(end -3.330702 -4.771136)
			(stroke
				(width 0.1)
				(type default)
			)
			(layer "B.Fab")
		)
		(pad "1" thru_hole circle
			(at 0 0 90)
			(size 2.159 2.159)
			(drill 1.7018)
			(layers "*.Cu" "*.Mask")
			(remove_unused_layers no)
			(net "GND3")
			(clearance 0.0254)
			(thermal_gap 0.0254)
		)
		(pad "2" thru_hole circle
			(at 1.27 -3.348736 90)
			(size 2.159 2.159)
			(drill 1.7018)
			(layers "*.Cu" "*.Mask")
			(remove_unused_layers no)
			(net "TDR_SE_50_OHM_IN2")
			(clearance 0.0254)
			(thermal_gap 0.0254)
		)
		(pad "3" thru_hole circle
			(at -1.27 -3.348736 90)
			(size 2.159 2.159)
			(drill 1.7018)
			(layers "*.Cu" "*.Mask")
			(remove_unused_layers no)
			(net "TDR_SE_50_OHM_IN2")
			(clearance 0.0254)
			(thermal_gap 0.0254)
		)
	)
	(footprint ""
		(layer "B.Cu")
		(at 426.593 -38.989)
		(property "Reference" "R5936"
			(at 0 0 0)
			(layer "B.SilkS")
			(hide yes)
			(effects
				(font
					(size 1.27 1.27)
				)
				(justify mirror)
			)
		)
		(property "Value" ""
			(at 0 0 0)
			(layer "B.Fab")
			(effects
				(font
					(size 1.27 1.27)
				)
				(justify mirror)
			)
		)
		(duplicate_pad_numbers_are_jumpers no)
		(fp_line
			(start -0.7874 -0.4064)
			(end -0.7874 0.4064)
			(stroke
				(width 0.1524)
				(type default)
			)
			(layer "B.SilkS")
		)
		(fp_line
			(start -0.7874 0.4064)
			(end 0.7874 0.4064)
			(stroke
				(width 0.1524)
				(type default)
			)
			(layer "B.SilkS")
		)
		(fp_line
			(start 0.7874 -0.4064)
			(end -0.7874 -0.4064)
			(stroke
				(width 0.1524)
				(type default)
			)
			(layer "B.SilkS")
		)
		(fp_line
			(start 0.7874 0.4064)
			(end 0.7874 -0.4064)
			(stroke
				(width 0.1524)
				(type default)
			)
			(layer "B.SilkS")
		)
		(fp_line
			(start -0.67945 -0.3048)
			(end -0.67945 0.3048)
			(stroke
				(width 0.1)
				(type default)
			)
			(layer "B.Fab")
		)
		(fp_line
			(start -0.67945 0.3048)
			(end -0.120396 0.3048)
			(stroke
				(width 0.1)
				(type default)
			)
			(layer "B.Fab")
		)
		(fp_line
			(start -0.12065 -0.3048)
			(end -0.67945 -0.3048)
			(stroke
				(width 0.1)
				(type default)
			)
			(layer "B.Fab")
		)
		(fp_line
			(start -0.12065 -0.2794)
			(end -0.12065 -0.3048)
			(stroke
				(width 0.1)
				(type default)
			)
			(layer "B.Fab")
		)
		(fp_line
			(start -0.120396 0.2794)
			(end 0.12065 0.2794)
			(stroke
				(width 0.1)
				(type default)
			)
			(layer "B.Fab")
		)
		(fp_line
			(start -0.120396 0.3048)
			(end -0.120396 0.2794)
			(stroke
				(width 0.1)
				(type default)
			)
			(layer "B.Fab")
		)
		(fp_line
			(start 0.12065 -0.305054)
			(end 0.12065 -0.2794)
			(stroke
				(width 0.1)
				(type default)
			)
			(layer "B.Fab")
		)
		(fp_line
			(start 0.12065 -0.2794)
			(end -0.12065 -0.2794)
			(stroke
				(width 0.1)
				(type default)
			)
			(layer "B.Fab")
		)
		(fp_line
			(start 0.12065 0.2794)
			(end 0.12065 0.3048)
			(stroke
				(width 0.1)
				(type default)
			)
			(layer "B.Fab")
		)
		(fp_line
			(start 0.12065 0.3048)
			(end 0.67945 0.3048)
			(stroke
				(width 0.1)
				(type default)
			)
			(layer "B.Fab")
		)
		(fp_line
			(start 0.67945 -0.305054)
			(end 0.12065 -0.305054)
			(stroke
				(width 0.1)
				(type default)
			)
			(layer "B.Fab")
		)
		(fp_line
			(start 0.67945 0.3048)
			(end 0.67945 -0.305054)
			(stroke
				(width 0.1)
				(type default)
			)
			(layer "B.Fab")
		)
		(pad "1" smd circle
			(at 0.40005 0 180)
			(size 0 0)
			(layers "B.Cu" "B.Mask" "B.Paste")
			(net "P3V3_AUX")
		)
		(pad "2" smd circle
			(at -0.40005 0 180)
			(size 0 0)
			(layers "B.Cu" "B.Mask" "B.Paste")
			(net "PCA9555_2_A0")
		)
	)
	(footprint ""
		(layer "B.Cu")
		(at 282.702 -88.773 -90)
		(property "Reference" "R5901"
			(at 0 0 90)
			(layer "B.SilkS")
			(hide yes)
			(effects
				(font
					(size 1.27 1.27)
				)
				(justify mirror)
			)
		)
		(property "Value" ""
			(at 0 0 90)
			(layer "B.Fab")
			(effects
				(font
					(size 1.27 1.27)
				)
				(justify mirror)
			)
		)
		(duplicate_pad_numbers_are_jumpers no)
		(fp_line
			(start -1.651 0.8382)
			(end 1.651 0.8382)
			(stroke
				(width 0.1524)
				(type default)
			)
			(layer "B.SilkS")
		)
		(fp_line
			(start 1.651 0.8382)
			(end 1.651 -0.8382)
			(stroke
				(width 0.1524)
				(type default)
			)
			(layer "B.SilkS")
		)
		(fp_line
			(start -1.651 -0.8382)
			(end -1.651 0.8382)
			(stroke
				(width 0.1524)
				(type default)
			)
			(layer "B.SilkS")
		)
		(fp_line
			(start 1.651 -0.8382)
			(end -1.651 -0.8382)
			(stroke
				(width 0.1524)
				(type default)
			)
			(layer "B.SilkS")
		)
		(fp_line
			(start -1.560576 0.7366)
			(end -1.560576 -0.7366)
			(stroke
				(width 0.1)
				(type default)
			)
			(layer "B.Fab")
		)
		(fp_line
			(start -1.524 0.7366)
			(end -1.560576 0.7366)
			(stroke
				(width 0.1)
				(type default)
			)
			(layer "B.Fab")
		)
		(fp_line
			(start 1.524 0.7366)
			(end -1.524 0.7366)
			(stroke
				(width 0.1)
				(type default)
			)
			(layer "B.Fab")
		)
		(fp_line
			(start 1.559814 0.7366)
			(end 1.524 0.7366)
			(stroke
				(width 0.1)
				(type default)
			)
			(layer "B.Fab")
		)
		(fp_line
			(start -1.560576 -0.7366)
			(end -1.524 -0.7366)
			(stroke
				(width 0.1)
				(type default)
			)
			(layer "B.Fab")
		)
		(fp_line
			(start -1.524 -0.7366)
			(end 1.524 -0.7366)
			(stroke
				(width 0.1)
				(type default)
			)
			(layer "B.Fab")
		)
		(fp_line
			(start 1.524 -0.7366)
			(end 1.559814 -0.7366)
			(stroke
				(width 0.1)
				(type default)
			)
			(layer "B.Fab")
		)
		(fp_line
			(start 1.559814 -0.7366)
			(end 1.559814 0.7366)
			(stroke
				(width 0.1)
				(type default)
			)
			(layer "B.Fab")
		)
		(pad "1" smd rect
			(at 0.94996 0 270)
			(size 1.1176 1.3716)
			(layers "B.Cu" "B.Mask" "B.Paste")
			(net "P52V_1")
		)
		(pad "2" smd rect
			(at -0.94996 0 270)
			(size 1.1176 1.3716)
			(layers "B.Cu" "B.Mask" "B.Paste")
			(net "P3V3_AND")
		)
	)
	(footprint ""
		(layer "B.Cu")
		(at 272.8214 -76.454 -90)
		(property "Reference" "PR6931"
			(at 0 0 90)
			(layer "B.SilkS")
			(hide yes)
			(effects
				(font
					(size 1.27 1.27)
				)
				(justify mirror)
			)
		)
		(property "Value" ""
			(at 0 0 90)
			(layer "B.Fab")
			(effects
				(font
					(size 1.27 1.27)
				)
				(justify mirror)
			)
		)
		(duplicate_pad_numbers_are_jumpers no)
		(fp_line
			(start -0.7874 0.4064)
			(end 0.7874 0.4064)
			(stroke
				(width 0.1524)
				(type default)
			)
			(layer "B.SilkS")
		)
		(fp_line
			(start 0.7874 0.4064)
			(end 0.7874 -0.4064)
			(stroke
				(width 0.1524)
				(type default)
			)
			(layer "B.SilkS")
		)
		(fp_line
			(start -0.7874 -0.4064)
			(end -0.7874 0.4064)
			(stroke
				(width 0.1524)
				(type default)
			)
			(layer "B.SilkS")
		)
		(fp_line
			(start 0.7874 -0.4064)
			(end -0.7874 -0.4064)
			(stroke
				(width 0.1524)
				(type default)
			)
			(layer "B.SilkS")
		)
		(fp_line
			(start -0.67945 0.3048)
			(end -0.120396 0.3048)
			(stroke
				(width 0.1)
				(type default)
			)
			(layer "B.Fab")
		)
		(fp_line
			(start -0.120396 0.3048)
			(end -0.120396 0.2794)
			(stroke
				(width 0.1)
				(type default)
			)
			(layer "B.Fab")
		)
		(fp_line
			(start 0.12065 0.3048)
			(end 0.67945 0.3048)
			(stroke
				(width 0.1)
				(type default)
			)
			(layer "B.Fab")
		)
		(fp_line
			(start 0.67945 0.3048)
			(end 0.67945 -0.305054)
			(stroke
				(width 0.1)
				(type default)
			)
			(layer "B.Fab")
		)
		(fp_line
			(start -0.120396 0.2794)
			(end 0.12065 0.2794)
			(stroke
				(width 0.1)
				(type default)
			)
			(layer "B.Fab")
		)
		(fp_line
			(start 0.12065 0.2794)
			(end 0.12065 0.3048)
			(stroke
				(width 0.1)
				(type default)
			)
			(layer "B.Fab")
		)
		(fp_line
			(start -0.12065 -0.2794)
			(end -0.12065 -0.3048)
			(stroke
				(width 0.1)
				(type default)
			)
			(layer "B.Fab")
		)
		(fp_line
			(start 0.12065 -0.2794)
			(end -0.12065 -0.2794)
			(stroke
				(width 0.1)
				(type default)
			)
			(layer "B.Fab")
		)
		(fp_line
			(start -0.67945 -0.3048)
			(end -0.67945 0.3048)
			(stroke
				(width 0.1)
				(type default)
			)
			(layer "B.Fab")
		)
		(fp_line
			(start -0.12065 -0.3048)
			(end -0.67945 -0.3048)
			(stroke
				(width 0.1)
				(type default)
			)
			(layer "B.Fab")
		)
		(fp_line
			(start 0.12065 -0.305054)
			(end 0.12065 -0.2794)
			(stroke
				(width 0.1)
				(type default)
			)
			(layer "B.Fab")
		)
		(fp_line
			(start 0.67945 -0.305054)
			(end 0.12065 -0.305054)
			(stroke
				(width 0.1)
				(type default)
			)
			(layer "B.Fab")
		)
		(pad "1" smd circle
			(at 0.40005 0 90)
			(size 0 0)
			(layers "B.Cu" "B.Mask" "B.Paste")
			(net "P52V_HS1_UVH")
		)
		(pad "2" smd circle
			(at -0.40005 0 90)
			(size 0 0)
			(layers "B.Cu" "B.Mask" "B.Paste")
			(net "GND_FIELD_SIGNAL")
		)
	)
	(footprint ""
		(layer "B.Cu")
		(at 298.704 -90.17 -90)
		(property "Reference" "R5943"
			(at 0 0 90)
			(layer "B.SilkS")
			(hide yes)
			(effects
				(font
					(size 1.27 1.27)
				)
				(justify mirror)
			)
		)
		(property "Value" ""
			(at 0 0 90)
			(layer "B.Fab")
			(effects
				(font
					(size 1.27 1.27)
				)
				(justify mirror)
			)
		)
		(duplicate_pad_numbers_are_jumpers no)
		(fp_line
			(start -0.7874 0.4064)
			(end 0.7874 0.4064)
			(stroke
				(width 0.1524)
				(type default)
			)
			(layer "B.SilkS")
		)
		(fp_line
			(start 0.7874 0.4064)
			(end 0.7874 -0.4064)
			(stroke
				(width 0.1524)
				(type default)
			)
			(layer "B.SilkS")
		)
		(fp_line
			(start -0.7874 -0.4064)
			(end -0.7874 0.4064)
			(stroke
				(width 0.1524)
				(type default)
			)
			(layer "B.SilkS")
		)
		(fp_line
			(start 0.7874 -0.4064)
			(end -0.7874 -0.4064)
			(stroke
				(width 0.1524)
				(type default)
			)
			(layer "B.SilkS")
		)
		(fp_line
			(start -0.67945 0.3048)
			(end -0.120396 0.3048)
			(stroke
				(width 0.1)
				(type default)
			)
			(layer "B.Fab")
		)
		(fp_line
			(start -0.120396 0.3048)
			(end -0.120396 0.2794)
			(stroke
				(width 0.1)
				(type default)
			)
			(layer "B.Fab")
		)
		(fp_line
			(start 0.12065 0.3048)
			(end 0.67945 0.3048)
			(stroke
				(width 0.1)
				(type default)
			)
			(layer "B.Fab")
		)
		(fp_line
			(start 0.67945 0.3048)
			(end 0.67945 -0.305054)
			(stroke
				(width 0.1)
				(type default)
			)
			(layer "B.Fab")
		)
		(fp_line
			(start -0.120396 0.2794)
			(end 0.12065 0.2794)
			(stroke
				(width 0.1)
				(type default)
			)
			(layer "B.Fab")
		)
		(fp_line
			(start 0.12065 0.2794)
			(end 0.12065 0.3048)
			(stroke
				(width 0.1)
				(type default)
			)
			(layer "B.Fab")
		)
		(fp_line
			(start -0.12065 -0.2794)
			(end -0.12065 -0.3048)
			(stroke
				(width 0.1)
				(type default)
			)
			(layer "B.Fab")
		)
		(fp_line
			(start 0.12065 -0.2794)
			(end -0.12065 -0.2794)
			(stroke
				(width 0.1)
				(type default)
			)
			(layer "B.Fab")
		)
		(fp_line
			(start -0.67945 -0.3048)
			(end -0.67945 0.3048)
			(stroke
				(width 0.1)
				(type default)
			)
			(layer "B.Fab")
		)
		(fp_line
			(start -0.12065 -0.3048)
			(end -0.67945 -0.3048)
			(stroke
				(width 0.1)
				(type default)
			)
			(layer "B.Fab")
		)
		(fp_line
			(start 0.12065 -0.305054)
			(end 0.12065 -0.2794)
			(stroke
				(width 0.1)
				(type default)
			)
			(layer "B.Fab")
		)
		(fp_line
			(start 0.67945 -0.305054)
			(end 0.12065 -0.305054)
			(stroke
				(width 0.1)
				(type default)
			)
			(layer "B.Fab")
		)
		(pad "1" smd circle
			(at 0.40005 0 90)
			(size 0 0)
			(layers "B.Cu" "B.Mask" "B.Paste")
			(net "P3V3_AUX")
		)
		(pad "2" smd circle
			(at -0.40005 0 90)
			(size 0 0)
			(layers "B.Cu" "B.Mask" "B.Paste")
			(net "FM_HS1_EN_FUSE_BUF")
		)
	)
	(footprint ""
		(layer "B.Cu")
		(at 183.942736 -77.47)
		(property "Reference" "PR7033"
			(at 0 0 0)
			(layer "B.SilkS")
			(hide yes)
			(effects
				(font
					(size 1.27 1.27)
				)
				(justify mirror)
			)
		)
		(property "Value" ""
			(at 0 0 0)
			(layer "B.Fab")
			(effects
				(font
					(size 1.27 1.27)
				)
				(justify mirror)
			)
		)
		(duplicate_pad_numbers_are_jumpers no)
		(fp_line
			(start -1.651 -0.8382)
			(end -1.651 0.8382)
			(stroke
				(width 0.1524)
				(type default)
			)
			(layer "B.SilkS")
		)
		(fp_line
			(start -1.651 0.8382)
			(end 1.651 0.8382)
			(stroke
				(width 0.1524)
				(type default)
			)
			(layer "B.SilkS")
		)
		(fp_line
			(start 1.651 -0.8382)
			(end -1.651 -0.8382)
			(stroke
				(width 0.1524)
				(type default)
			)
			(layer "B.SilkS")
		)
		(fp_line
			(start 1.651 0.8382)
			(end 1.651 -0.8382)
			(stroke
				(width 0.1524)
				(type default)
			)
			(layer "B.SilkS")
		)
		(fp_line
			(start -1.560576 -0.7366)
			(end -1.524 -0.7366)
			(stroke
				(width 0.1)
				(type default)
			)
			(layer "B.Fab")
		)
		(fp_line
			(start -1.560576 0.7366)
			(end -1.560576 -0.7366)
			(stroke
				(width 0.1)
				(type default)
			)
			(layer "B.Fab")
		)
		(fp_line
			(start -1.524 -0.7366)
			(end 1.524 -0.7366)
			(stroke
				(width 0.1)
				(type default)
			)
			(layer "B.Fab")
		)
		(fp_line
			(start -1.524 0.7366)
			(end -1.560576 0.7366)
			(stroke
				(width 0.1)
				(type default)
			)
			(layer "B.Fab")
		)
		(fp_line
			(start 1.524 -0.7366)
			(end 1.559814 -0.7366)
			(stroke
				(width 0.1)
				(type default)
			)
			(layer "B.Fab")
		)
		(fp_line
			(start 1.524 0.7366)
			(end -1.524 0.7366)
			(stroke
				(width 0.1)
				(type default)
			)
			(layer "B.Fab")
		)
		(fp_line
			(start 1.559814 -0.7366)
			(end 1.559814 0.7366)
			(stroke
				(width 0.1)
				(type default)
			)
			(layer "B.Fab")
		)
		(fp_line
			(start 1.559814 0.7366)
			(end 1.524 0.7366)
			(stroke
				(width 0.1)
				(type default)
			)
			(layer "B.Fab")
		)
		(pad "1" smd rect
			(at 0.94996 0)
			(size 1.1176 1.3716)
			(layers "B.Cu" "B.Mask" "B.Paste")
			(net "P52V_HS2_DV_DT_R")
		)
		(pad "2" smd rect
			(at -0.94996 0)
			(size 1.1176 1.3716)
			(layers "B.Cu" "B.Mask" "B.Paste")
			(net "P52V_HS2_DV_DT")
		)
	)
	(footprint ""
		(layer "B.Cu")
		(at 176.195736 -63.754 180)
		(property "Reference" "PC609"
			(at 0 0 0)
			(layer "B.SilkS")
			(hide yes)
			(effects
				(font
					(size 1.27 1.27)
				)
				(justify mirror)
			)
		)
		(property "Value" ""
			(at 0 0 0)
			(layer "B.Fab")
			(effects
				(font
					(size 1.27 1.27)
				)
				(justify mirror)
			)
		)
		(duplicate_pad_numbers_are_jumpers no)
		(fp_line
			(start 0.7874 0.4064)
			(end 0.7874 -0.4064)
			(stroke
				(width 0.1524)
				(type default)
			)
			(layer "B.SilkS")
		)
		(fp_line
			(start 0.7874 -0.4064)
			(end -0.7874 -0.4064)
			(stroke
				(width 0.1524)
				(type default)
			)
			(layer "B.SilkS")
		)
		(fp_line
			(start -0.7874 0.4064)
			(end 0.7874 0.4064)
			(stroke
				(width 0.1524)
				(type default)
			)
			(layer "B.SilkS")
		)
		(fp_line
			(start -0.7874 -0.4064)
			(end -0.7874 0.4064)
			(stroke
				(width 0.1524)
				(type default)
			)
			(layer "B.SilkS")
		)
		(fp_line
			(start 0.67945 0.3048)
			(end 0.67945 -0.305054)
			(stroke
				(width 0.1)
				(type default)
			)
			(layer "B.Fab")
		)
		(fp_line
			(start 0.67945 -0.305054)
			(end 0.12065 -0.305054)
			(stroke
				(width 0.1)
				(type default)
			)
			(layer "B.Fab")
		)
		(fp_line
			(start 0.12065 0.3048)
			(end 0.67945 0.3048)
			(stroke
				(width 0.1)
				(type default)
			)
			(layer "B.Fab")
		)
		(fp_line
			(start 0.12065 0.2794)
			(end 0.12065 0.3048)
			(stroke
				(width 0.1)
				(type default)
			)
			(layer "B.Fab")
		)
		(fp_line
			(start 0.12065 -0.2794)
			(end -0.12065 -0.2794)
			(stroke
				(width 0.1)
				(type default)
			)
			(layer "B.Fab")
		)
		(fp_line
			(start 0.12065 -0.305054)
			(end 0.12065 -0.2794)
			(stroke
				(width 0.1)
				(type default)
			)
			(layer "B.Fab")
		)
		(fp_line
			(start -0.120396 0.3048)
			(end -0.120396 0.2794)
			(stroke
				(width 0.1)
				(type default)
			)
			(layer "B.Fab")
		)
		(fp_line
			(start -0.120396 0.2794)
			(end 0.12065 0.2794)
			(stroke
				(width 0.1)
				(type default)
			)
			(layer "B.Fab")
		)
		(fp_line
			(start -0.12065 -0.2794)
			(end -0.12065 -0.3048)
			(stroke
				(width 0.1)
				(type default)
			)
			(layer "B.Fab")
		)
		(fp_line
			(start -0.12065 -0.3048)
			(end -0.67945 -0.3048)
			(stroke
				(width 0.1)
				(type default)
			)
			(layer "B.Fab")
		)
		(fp_line
			(start -0.67945 0.3048)
			(end -0.120396 0.3048)
			(stroke
				(width 0.1)
				(type default)
			)
			(layer "B.Fab")
		)
		(fp_line
			(start -0.67945 -0.3048)
			(end -0.67945 0.3048)
			(stroke
				(width 0.1)
				(type default)
			)
			(layer "B.Fab")
		)
		(pad "1" smd circle
			(at 0.40005 0)
			(size 0 0)
			(layers "B.Cu" "B.Mask" "B.Paste")
			(net "P52V_HS2_TEMPP")
		)
		(pad "2" smd circle
			(at -0.40005 0)
			(size 0 0)
			(layers "B.Cu" "B.Mask" "B.Paste")
			(net "P52V_HS2_TEMPN")
		)
	)
	(footprint ""
		(layer "B.Cu")
		(at 185.212736 -71.12 -90)
		(property "Reference" "PC608"
			(at 0 0 90)
			(layer "B.SilkS")
			(hide yes)
			(effects
				(font
					(size 1.27 1.27)
				)
				(justify mirror)
			)
		)
		(property "Value" ""
			(at 0 0 90)
			(layer "B.Fab")
			(effects
				(font
					(size 1.27 1.27)
				)
				(justify mirror)
			)
		)
		(duplicate_pad_numbers_are_jumpers no)
		(fp_line
			(start -2.2098 0.9398)
			(end 2.2098 0.9398)
			(stroke
				(width 0.1524)
				(type default)
			)
			(layer "B.SilkS")
		)
		(fp_line
			(start 2.2098 0.9398)
			(end 2.2098 -0.9398)
			(stroke
				(width 0.1524)
				(type default)
			)
			(layer "B.SilkS")
		)
		(fp_line
			(start -2.2098 -0.9398)
			(end -2.2098 0.9398)
			(stroke
				(width 0.1524)
				(type default)
			)
			(layer "B.SilkS")
		)
		(fp_line
			(start 2.2098 -0.9398)
			(end -2.2098 -0.9398)
			(stroke
				(width 0.1524)
				(type default)
			)
			(layer "B.SilkS")
		)
		(fp_line
			(start -1.6764 0.9398)
			(end 1.6764 0.9398)
			(stroke
				(width 0.1)
				(type default)
			)
			(layer "B.Fab")
		)
		(fp_line
			(start 1.6764 0.9398)
			(end 1.6764 0.889)
			(stroke
				(width 0.1)
				(type default)
			)
			(layer "B.Fab")
		)
		(fp_line
			(start -1.6764 0.889)
			(end -1.6764 0.9398)
			(stroke
				(width 0.1)
				(type default)
			)
			(layer "B.Fab")
		)
		(fp_line
			(start 1.6764 0.889)
			(end 1.6764 0.8382)
			(stroke
				(width 0.1)
				(type default)
			)
			(layer "B.Fab")
		)
		(fp_line
			(start -2.1082 0.8382)
			(end -1.6764 0.8382)
			(stroke
				(width 0.1)
				(type default)
			)
			(layer "B.Fab")
		)
		(fp_line
			(start -1.6764 0.8382)
			(end -1.6764 0.889)
			(stroke
				(width 0.1)
				(type default)
			)
			(layer "B.Fab")
		)
		(fp_line
			(start 1.6764 0.8382)
			(end 2.1082 0.8382)
			(stroke
				(width 0.1)
				(type default)
			)
			(layer "B.Fab")
		)
		(fp_line
			(start 2.1082 0.8382)
			(end 2.1082 -0.8382)
			(stroke
				(width 0.1)
				(type default)
			)
			(layer "B.Fab")
		)
		(fp_line
			(start -2.1082 -0.8382)
			(end -2.1082 0.8382)
			(stroke
				(width 0.1)
				(type default)
			)
			(layer "B.Fab")
		)
		(fp_line
			(start -1.6764 -0.8382)
			(end -2.1082 -0.8382)
			(stroke
				(width 0.1)
				(type default)
			)
			(layer "B.Fab")
		)
		(fp_line
			(start 1.6764 -0.8382)
			(end 1.6764 -0.889)
			(stroke
				(width 0.1)
				(type default)
			)
			(layer "B.Fab")
		)
		(fp_line
			(start 2.1082 -0.8382)
			(end 1.6764 -0.8382)
			(stroke
				(width 0.1)
				(type default)
			)
			(layer "B.Fab")
		)
		(fp_line
			(start -1.6764 -0.889)
			(end -1.6764 -0.8382)
			(stroke
				(width 0.1)
				(type default)
			)
			(layer "B.Fab")
		)
		(fp_line
			(start 1.6764 -0.889)
			(end 1.6764 -0.9398)
			(stroke
				(width 0.1)
				(type default)
			)
			(layer "B.Fab")
		)
		(fp_line
			(start -1.6764 -0.9398)
			(end -1.6764 -0.889)
			(stroke
				(width 0.1)
				(type default)
			)
			(layer "B.Fab")
		)
		(fp_line
			(start 1.6764 -0.9398)
			(end -1.6764 -0.9398)
			(stroke
				(width 0.1)
				(type default)
			)
			(layer "B.Fab")
		)
		(pad "1" smd rect
			(at 1.4732 0 270)
			(size 1.1684 1.5748)
			(layers "B.Cu" "B.Mask" "B.Paste")
			(net "P52V_HS2")
		)
		(pad "2" smd rect
			(at -1.4732 0 270)
			(size 1.1684 1.5748)
			(layers "B.Cu" "B.Mask" "B.Paste")
			(net "P52V_HS2_VCP")
		)
	)
	(footprint ""
		(layer "B.Cu")
		(at 174.798736 -63.754 90)
		(property "Reference" "PR7021"
			(at 0 0 90)
			(layer "B.SilkS")
			(hide yes)
			(effects
				(font
					(size 1.27 1.27)
				)
				(justify mirror)
			)
		)
		(property "Value" ""
			(at 0 0 90)
			(layer "B.Fab")
			(effects
				(font
					(size 1.27 1.27)
				)
				(justify mirror)
			)
		)
		(duplicate_pad_numbers_are_jumpers no)
		(fp_line
			(start 0.7874 -0.4064)
			(end -0.7874 -0.4064)
			(stroke
				(width 0.1524)
				(type default)
			)
			(layer "B.SilkS")
		)
		(fp_line
			(start -0.7874 -0.4064)
			(end -0.7874 0.4064)
			(stroke
				(width 0.1524)
				(type default)
			)
			(layer "B.SilkS")
		)
		(fp_line
			(start 0.7874 0.4064)
			(end 0.7874 -0.4064)
			(stroke
				(width 0.1524)
				(type default)
			)
			(layer "B.SilkS")
		)
		(fp_line
			(start -0.7874 0.4064)
			(end 0.7874 0.4064)
			(stroke
				(width 0.1524)
				(type default)
			)
			(layer "B.SilkS")
		)
		(fp_line
			(start 0.67945 -0.305054)
			(end 0.12065 -0.305054)
			(stroke
				(width 0.1)
				(type default)
			)
			(layer "B.Fab")
		)
		(fp_line
			(start 0.12065 -0.305054)
			(end 0.12065 -0.2794)
			(stroke
				(width 0.1)
				(type default)
			)
			(layer "B.Fab")
		)
		(fp_line
			(start -0.12065 -0.3048)
			(end -0.67945 -0.3048)
			(stroke
				(width 0.1)
				(type default)
			)
			(layer "B.Fab")
		)
		(fp_line
			(start -0.67945 -0.3048)
			(end -0.67945 0.3048)
			(stroke
				(width 0.1)
				(type default)
			)
			(layer "B.Fab")
		)
		(fp_line
			(start 0.12065 -0.2794)
			(end -0.12065 -0.2794)
			(stroke
				(width 0.1)
				(type default)
			)
			(layer "B.Fab")
		)
		(fp_line
			(start -0.12065 -0.2794)
			(end -0.12065 -0.3048)
			(stroke
				(width 0.1)
				(type default)
			)
			(layer "B.Fab")
		)
		(fp_line
			(start 0.12065 0.2794)
			(end 0.12065 0.3048)
			(stroke
				(width 0.1)
				(type default)
			)
			(layer "B.Fab")
		)
		(fp_line
			(start -0.120396 0.2794)
			(end 0.12065 0.2794)
			(stroke
				(width 0.1)
				(type default)
			)
			(layer "B.Fab")
		)
		(fp_line
			(start 0.67945 0.3048)
			(end 0.67945 -0.305054)
			(stroke
				(width 0.1)
				(type default)
			)
			(layer "B.Fab")
		)
		(fp_line
			(start 0.12065 0.3048)
			(end 0.67945 0.3048)
			(stroke
				(width 0.1)
				(type default)
			)
			(layer "B.Fab")
		)
		(fp_line
			(start -0.120396 0.3048)
			(end -0.120396 0.2794)
			(stroke
				(width 0.1)
				(type default)
			)
			(layer "B.Fab")
		)
		(fp_line
			(start -0.67945 0.3048)
			(end -0.120396 0.3048)
			(stroke
				(width 0.1)
				(type default)
			)
			(layer "B.Fab")
		)
		(pad "1" smd circle
			(at 0.40005 0 270)
			(size 0 0)
			(layers "B.Cu" "B.Mask" "B.Paste")
			(net "P52V_HS2_UVH")
		)
		(pad "2" smd circle
			(at -0.40005 0 270)
			(size 0 0)
			(layers "B.Cu" "B.Mask" "B.Paste")
			(net "GND1_FIELD_SIGNAL")
		)
	)
	(footprint ""
		(layer "B.Cu")
		(at 273.812 -91.567 180)
		(property "Reference" "R5902"
			(at 0 0 0)
			(layer "B.SilkS")
			(hide yes)
			(effects
				(font
					(size 1.27 1.27)
				)
				(justify mirror)
			)
		)
		(property "Value" ""
			(at 0 0 0)
			(layer "B.Fab")
			(effects
				(font
					(size 1.27 1.27)
				)
				(justify mirror)
			)
		)
		(duplicate_pad_numbers_are_jumpers no)
		(fp_line
			(start 1.651 0.8382)
			(end 1.651 -0.8382)
			(stroke
				(width 0.1524)
				(type default)
			)
			(layer "B.SilkS")
		)
		(fp_line
			(start 1.651 -0.8382)
			(end -1.651 -0.8382)
			(stroke
				(width 0.1524)
				(type default)
			)
			(layer "B.SilkS")
		)
		(fp_line
			(start -1.651 0.8382)
			(end 1.651 0.8382)
			(stroke
				(width 0.1524)
				(type default)
			)
			(layer "B.SilkS")
		)
		(fp_line
			(start -1.651 -0.8382)
			(end -1.651 0.8382)
			(stroke
				(width 0.1524)
				(type default)
			)
			(layer "B.SilkS")
		)
		(fp_line
			(start 1.559814 0.7366)
			(end 1.524 0.7366)
			(stroke
				(width 0.1)
				(type default)
			)
			(layer "B.Fab")
		)
		(fp_line
			(start 1.559814 -0.7366)
			(end 1.559814 0.7366)
			(stroke
				(width 0.1)
				(type default)
			)
			(layer "B.Fab")
		)
		(fp_line
			(start 1.524 0.7366)
			(end -1.524 0.7366)
			(stroke
				(width 0.1)
				(type default)
			)
			(layer "B.Fab")
		)
		(fp_line
			(start 1.524 -0.7366)
			(end 1.559814 -0.7366)
			(stroke
				(width 0.1)
				(type default)
			)
			(layer "B.Fab")
		)
		(fp_line
			(start -1.524 0.7366)
			(end -1.560576 0.7366)
			(stroke
				(width 0.1)
				(type default)
			)
			(layer "B.Fab")
		)
		(fp_line
			(start -1.524 -0.7366)
			(end 1.524 -0.7366)
			(stroke
				(width 0.1)
				(type default)
			)
			(layer "B.Fab")
		)
		(fp_line
			(start -1.560576 0.7366)
			(end -1.560576 -0.7366)
			(stroke
				(width 0.1)
				(type default)
			)
			(layer "B.Fab")
		)
		(fp_line
			(start -1.560576 -0.7366)
			(end -1.524 -0.7366)
			(stroke
				(width 0.1)
				(type default)
			)
			(layer "B.Fab")
		)
		(pad "1" smd rect
			(at 0.94996 0 180)
			(size 1.1176 1.3716)
			(layers "B.Cu" "B.Mask" "B.Paste")
			(net "P52V_1_BUSBAR")
		)
		(pad "2" smd rect
			(at -0.94996 0 180)
			(size 1.1176 1.3716)
			(layers "B.Cu" "B.Mask" "B.Paste")
			(net "FM_HS1_EN_BUSBAR")
		)
	)
	(footprint ""
		(layer "B.Cu")
		(at 167.940736 -59.309 180)
		(property "Reference" "PR7024"
			(at 0 0 0)
			(layer "B.SilkS")
			(hide yes)
			(effects
				(font
					(size 1.27 1.27)
				)
				(justify mirror)
			)
		)
		(property "Value" ""
			(at 0 0 0)
			(layer "B.Fab")
			(effects
				(font
					(size 1.27 1.27)
				)
				(justify mirror)
			)
		)
		(duplicate_pad_numbers_are_jumpers no)
		(fp_line
			(start 1.651 0.8382)
			(end 1.651 -0.8382)
			(stroke
				(width 0.1524)
				(type default)
			)
			(layer "B.SilkS")
		)
		(fp_line
			(start 1.651 -0.8382)
			(end -1.651 -0.8382)
			(stroke
				(width 0.1524)
				(type default)
			)
			(layer "B.SilkS")
		)
		(fp_line
			(start -1.651 0.8382)
			(end 1.651 0.8382)
			(stroke
				(width 0.1524)
				(type default)
			)
			(layer "B.SilkS")
		)
		(fp_line
			(start -1.651 -0.8382)
			(end -1.651 0.8382)
			(stroke
				(width 0.1524)
				(type default)
			)
			(layer "B.SilkS")
		)
		(fp_line
			(start 1.559814 0.7366)
			(end 1.524 0.7366)
			(stroke
				(width 0.1)
				(type default)
			)
			(layer "B.Fab")
		)
		(fp_line
			(start 1.559814 -0.7366)
			(end 1.559814 0.7366)
			(stroke
				(width 0.1)
				(type default)
			)
			(layer "B.Fab")
		)
		(fp_line
			(start 1.524 0.7366)
			(end -1.524 0.7366)
			(stroke
				(width 0.1)
				(type default)
			)
			(layer "B.Fab")
		)
		(fp_line
			(start 1.524 -0.7366)
			(end 1.559814 -0.7366)
			(stroke
				(width 0.1)
				(type default)
			)
			(layer "B.Fab")
		)
		(fp_line
			(start -1.524 0.7366)
			(end -1.560576 0.7366)
			(stroke
				(width 0.1)
				(type default)
			)
			(layer "B.Fab")
		)
		(fp_line
			(start -1.524 -0.7366)
			(end 1.524 -0.7366)
			(stroke
				(width 0.1)
				(type default)
			)
			(layer "B.Fab")
		)
		(fp_line
			(start -1.560576 0.7366)
			(end -1.560576 -0.7366)
			(stroke
				(width 0.1)
				(type default)
			)
			(layer "B.Fab")
		)
		(fp_line
			(start -1.560576 -0.7366)
			(end -1.524 -0.7366)
			(stroke
				(width 0.1)
				(type default)
			)
			(layer "B.Fab")
		)
		(pad "1" smd rect
			(at 0.94996 0 180)
			(size 1.1176 1.3716)
			(layers "B.Cu" "B.Mask" "B.Paste")
			(net "P52V_HS2")
		)
		(pad "2" smd rect
			(at -0.94996 0 180)
			(size 1.1176 1.3716)
			(layers "B.Cu" "B.Mask" "B.Paste")
			(net "P52V_HS2_ISET")
		)
	)
	(footprint ""
		(layer "B.Cu")
		(at 180.259736 -77.47)
		(property "Reference" "PC616"
			(at 0 0 0)
			(layer "B.SilkS")
			(hide yes)
			(effects
				(font
					(size 1.27 1.27)
				)
				(justify mirror)
			)
		)
		(property "Value" ""
			(at 0 0 0)
			(layer "B.Fab")
			(effects
				(font
					(size 1.27 1.27)
				)
				(justify mirror)
			)
		)
		(duplicate_pad_numbers_are_jumpers no)
		(fp_line
			(start -1.524 -0.762)
			(end -1.524 0.762)
			(stroke
				(width 0.1524)
				(type default)
			)
			(layer "B.SilkS")
		)
		(fp_line
			(start -1.524 0.762)
			(end 1.524 0.762)
			(stroke
				(width 0.1524)
				(type default)
			)
			(layer "B.SilkS")
		)
		(fp_line
			(start 1.524 -0.762)
			(end -1.524 -0.762)
			(stroke
				(width 0.1524)
				(type default)
			)
			(layer "B.SilkS")
		)
		(fp_line
			(start 1.524 0.762)
			(end 1.524 -0.762)
			(stroke
				(width 0.1524)
				(type default)
			)
			(layer "B.SilkS")
		)
		(fp_line
			(start -1.1049 -0.724916)
			(end 1.1049 -0.724916)
			(stroke
				(width 0.1)
				(type default)
			)
			(layer "B.Fab")
		)
		(fp_line
			(start -1.1049 0.724916)
			(end -1.1049 -0.724916)
			(stroke
				(width 0.1)
				(type default)
			)
			(layer "B.Fab")
		)
		(fp_line
			(start 1.1049 -0.724916)
			(end 1.1049 0.724916)
			(stroke
				(width 0.1)
				(type default)
			)
			(layer "B.Fab")
		)
		(fp_line
			(start 1.1049 0.724916)
			(end -1.1049 0.724916)
			(stroke
				(width 0.1)
				(type default)
			)
			(layer "B.Fab")
		)
		(pad "1" smd rect
			(at 0.889 0)
			(size 1.016 1.27)
			(layers "B.Cu" "B.Mask" "B.Paste")
			(net "P52V_HS2_DV_DT")
		)
		(pad "2" smd rect
			(at -0.889 0)
			(size 1.016 1.27)
			(layers "B.Cu" "B.Mask" "B.Paste")
			(net "GND1_FIELD_SIGNAL")
		)
	)
	(footprint ""
		(layer "B.Cu")
		(at 177.719736 -63.754 90)
		(property "Reference" "PC613"
			(at 0 0 90)
			(layer "B.SilkS")
			(hide yes)
			(effects
				(font
					(size 1.27 1.27)
				)
				(justify mirror)
			)
		)
		(property "Value" ""
			(at 0 0 90)
			(layer "B.Fab")
			(effects
				(font
					(size 1.27 1.27)
				)
				(justify mirror)
			)
		)
		(duplicate_pad_numbers_are_jumpers no)
		(fp_line
			(start 0.7874 -0.4064)
			(end -0.7874 -0.4064)
			(stroke
				(width 0.1524)
				(type default)
			)
			(layer "B.SilkS")
		)
		(fp_line
			(start -0.7874 -0.4064)
			(end -0.7874 0.4064)
			(stroke
				(width 0.1524)
				(type default)
			)
			(layer "B.SilkS")
		)
		(fp_line
			(start 0.7874 0.4064)
			(end 0.7874 -0.4064)
			(stroke
				(width 0.1524)
				(type default)
			)
			(layer "B.SilkS")
		)
		(fp_line
			(start -0.7874 0.4064)
			(end 0.7874 0.4064)
			(stroke
				(width 0.1524)
				(type default)
			)
			(layer "B.SilkS")
		)
		(fp_line
			(start 0.67945 -0.305054)
			(end 0.12065 -0.305054)
			(stroke
				(width 0.1)
				(type default)
			)
			(layer "B.Fab")
		)
		(fp_line
			(start 0.12065 -0.305054)
			(end 0.12065 -0.2794)
			(stroke
				(width 0.1)
				(type default)
			)
			(layer "B.Fab")
		)
		(fp_line
			(start -0.12065 -0.3048)
			(end -0.67945 -0.3048)
			(stroke
				(width 0.1)
				(type default)
			)
			(layer "B.Fab")
		)
		(fp_line
			(start -0.67945 -0.3048)
			(end -0.67945 0.3048)
			(stroke
				(width 0.1)
				(type default)
			)
			(layer "B.Fab")
		)
		(fp_line
			(start 0.12065 -0.2794)
			(end -0.12065 -0.2794)
			(stroke
				(width 0.1)
				(type default)
			)
			(layer "B.Fab")
		)
		(fp_line
			(start -0.12065 -0.2794)
			(end -0.12065 -0.3048)
			(stroke
				(width 0.1)
				(type default)
			)
			(layer "B.Fab")
		)
		(fp_line
			(start 0.12065 0.2794)
			(end 0.12065 0.3048)
			(stroke
				(width 0.1)
				(type default)
			)
			(layer "B.Fab")
		)
		(fp_line
			(start -0.120396 0.2794)
			(end 0.12065 0.2794)
			(stroke
				(width 0.1)
				(type default)
			)
			(layer "B.Fab")
		)
		(fp_line
			(start 0.67945 0.3048)
			(end 0.67945 -0.305054)
			(stroke
				(width 0.1)
				(type default)
			)
			(layer "B.Fab")
		)
		(fp_line
			(start 0.12065 0.3048)
			(end 0.67945 0.3048)
			(stroke
				(width 0.1)
				(type default)
			)
			(layer "B.Fab")
		)
		(fp_line
			(start -0.120396 0.3048)
			(end -0.120396 0.2794)
			(stroke
				(width 0.1)
				(type default)
			)
			(layer "B.Fab")
		)
		(fp_line
			(start -0.67945 0.3048)
			(end -0.120396 0.3048)
			(stroke
				(width 0.1)
				(type default)
			)
			(layer "B.Fab")
		)
		(pad "1" smd circle
			(at 0.40005 0 270)
			(size 0 0)
			(layers "B.Cu" "B.Mask" "B.Paste")
			(net "P52V_HS2_VREG")
		)
		(pad "2" smd circle
			(at -0.40005 0 270)
			(size 0 0)
			(layers "B.Cu" "B.Mask" "B.Paste")
			(net "GND1_FIELD_SIGNAL")
		)
	)
	(footprint ""
		(layer "B.Cu")
		(at 110.2614 -44.3484 90)
		(property "Reference" "R5868"
			(at 0 0 90)
			(layer "B.SilkS")
			(hide yes)
			(effects
				(font
					(size 1.27 1.27)
				)
				(justify mirror)
			)
		)
		(property "Value" ""
			(at 0 0 90)
			(layer "B.Fab")
			(effects
				(font
					(size 1.27 1.27)
				)
				(justify mirror)
			)
		)
		(duplicate_pad_numbers_are_jumpers no)
		(fp_line
			(start 0.7874 -0.4064)
			(end -0.7874 -0.4064)
			(stroke
				(width 0.1524)
				(type default)
			)
			(layer "B.SilkS")
		)
		(fp_line
			(start -0.7874 -0.4064)
			(end -0.7874 0.4064)
			(stroke
				(width 0.1524)
				(type default)
			)
			(layer "B.SilkS")
		)
		(fp_line
			(start 0.7874 0.4064)
			(end 0.7874 -0.4064)
			(stroke
				(width 0.1524)
				(type default)
			)
			(layer "B.SilkS")
		)
		(fp_line
			(start -0.7874 0.4064)
			(end 0.7874 0.4064)
			(stroke
				(width 0.1524)
				(type default)
			)
			(layer "B.SilkS")
		)
		(fp_line
			(start 0.67945 -0.305054)
			(end 0.12065 -0.305054)
			(stroke
				(width 0.1)
				(type default)
			)
			(layer "B.Fab")
		)
		(fp_line
			(start 0.12065 -0.305054)
			(end 0.12065 -0.2794)
			(stroke
				(width 0.1)
				(type default)
			)
			(layer "B.Fab")
		)
		(fp_line
			(start -0.12065 -0.3048)
			(end -0.67945 -0.3048)
			(stroke
				(width 0.1)
				(type default)
			)
			(layer "B.Fab")
		)
		(fp_line
			(start -0.67945 -0.3048)
			(end -0.67945 0.3048)
			(stroke
				(width 0.1)
				(type default)
			)
			(layer "B.Fab")
		)
		(fp_line
			(start 0.12065 -0.2794)
			(end -0.12065 -0.2794)
			(stroke
				(width 0.1)
				(type default)
			)
			(layer "B.Fab")
		)
		(fp_line
			(start -0.12065 -0.2794)
			(end -0.12065 -0.3048)
			(stroke
				(width 0.1)
				(type default)
			)
			(layer "B.Fab")
		)
		(fp_line
			(start 0.12065 0.2794)
			(end 0.12065 0.3048)
			(stroke
				(width 0.1)
				(type default)
			)
			(layer "B.Fab")
		)
		(fp_line
			(start -0.120396 0.2794)
			(end 0.12065 0.2794)
			(stroke
				(width 0.1)
				(type default)
			)
			(layer "B.Fab")
		)
		(fp_line
			(start 0.67945 0.3048)
			(end 0.67945 -0.305054)
			(stroke
				(width 0.1)
				(type default)
			)
			(layer "B.Fab")
		)
		(fp_line
			(start 0.12065 0.3048)
			(end 0.67945 0.3048)
			(stroke
				(width 0.1)
				(type default)
			)
			(layer "B.Fab")
		)
		(fp_line
			(start -0.120396 0.3048)
			(end -0.120396 0.2794)
			(stroke
				(width 0.1)
				(type default)
			)
			(layer "B.Fab")
		)
		(fp_line
			(start -0.67945 0.3048)
			(end -0.120396 0.3048)
			(stroke
				(width 0.1)
				(type default)
			)
			(layer "B.Fab")
		)
		(pad "1" smd circle
			(at 0.40005 0 270)
			(size 0 0)
			(layers "B.Cu" "B.Mask" "B.Paste")
			(net "P52V_HS2_GATE2_R")
		)
		(pad "2" smd circle
			(at -0.40005 0 270)
			(size 0 0)
			(layers "B.Cu" "B.Mask" "B.Paste")
			(net "P52V_HS2_4287_GATE2_R")
		)
	)
	(footprint ""
		(layer "B.Cu")
		(at 326.7202 -84.1756)
		(property "Reference" ""
			(at 0 0 0)
			(layer "B.SilkS")
			(hide yes)
			(effects
				(font
					(size 1.27 1.27)
				)
				(justify mirror)
			)
		)
		(property "Value" ""
			(at 0 0 0)
			(layer "B.Fab")
			(effects
				(font
					(size 1.27 1.27)
				)
				(justify mirror)
			)
		)
		(duplicate_pad_numbers_are_jumpers no)
		(pad "1" smd circle
			(at 0 0 180)
			(size 0.9906 0.9906)
			(layers "B.Cu" "B.Mask" "B.Paste")
			(net "Net_242")
		)
		(zone
			(layer "B.Cu")
			(hatch none 0.5)
			(connect_pads
				(clearance 0)
			)
			(min_thickness 0.25)
			(keepout
				(tracks not_allowed)
				(vias allowed)
				(pads allowed)
				(copperpour not_allowed)
				(footprints allowed)
			)
			(placement
				(enabled no)
				(sheetname "")
			)
			(fill
				(thermal_gap 0.5)
				(thermal_bridge_width 0.5)
				(island_removal_mode 0)
			)
			(polygon
				(pts
					(arc
						(start 328.3458 -84.1756)
						(mid 325.0946 -84.1756)
						(end 328.3458 -84.1756)
					)
				)
			)
		)
	)
	(footprint ""
		(layer "B.Cu")
		(at 298.069 -92.71 90)
		(property "Reference" "U43"
			(at 2.11963 2.4765 0)
			(unlocked yes)
			(layer "B.SilkS")
			(effects
				(font
					(size 0.7874 0.5842)
					(thickness 0.1524)
				)
				(justify left mirror)
			)
		)
		(property "Value" ""
			(at 0 0 90)
			(layer "B.Fab")
			(effects
				(font
					(size 1.27 1.27)
				)
				(justify mirror)
			)
		)
		(duplicate_pad_numbers_are_jumpers no)
		(fp_line
			(start -1.400048 -1.100074)
			(end 1.400048 -1.100074)
			(stroke
				(width 0.1524)
				(type default)
			)
			(layer "B.SilkS")
		)
		(fp_line
			(start -1.400048 -1.100074)
			(end -1.400048 1.100074)
			(stroke
				(width 0.1524)
				(type default)
			)
			(layer "B.SilkS")
		)
		(fp_line
			(start 1.400048 1.100074)
			(end 1.400048 -1.100074)
			(stroke
				(width 0.1524)
				(type default)
			)
			(layer "B.SilkS")
		)
		(fp_line
			(start -1.400048 1.100074)
			(end 1.400048 1.100074)
			(stroke
				(width 0.1524)
				(type default)
			)
			(layer "B.SilkS")
		)
		(fp_poly
			(pts
				(xy 1.590548 -0.649986) (xy 2.606548 -1.157986) (xy 2.606548 -0.141986)
			)
			(stroke
				(width 0)
				(type default)
			)
			(fill yes)
			(layer "B.SilkS")
		)
		(fp_line
			(start 0.674878 -1.100074)
			(end -0.674878 -1.100074)
			(stroke
				(width 0.1)
				(type default)
			)
			(layer "B.Fab")
		)
		(fp_line
			(start -0.674878 -1.100074)
			(end -0.674878 1.100074)
			(stroke
				(width 0.1)
				(type default)
			)
			(layer "B.Fab")
		)
		(fp_line
			(start 0.674878 1.100074)
			(end 0.674878 -1.100074)
			(stroke
				(width 0.1)
				(type default)
			)
			(layer "B.Fab")
		)
		(fp_line
			(start -0.674878 1.100074)
			(end 0.674878 1.100074)
			(stroke
				(width 0.1)
				(type default)
			)
			(layer "B.Fab")
		)
		(fp_poly
			(pts
				(xy 1.590548 -0.649986) (xy 2.606548 -1.157986) (xy 2.606548 -0.141986)
			)
			(stroke
				(width 0)
				(type default)
			)
			(fill yes)
			(layer "B.Fab")
		)
		(pad "1" smd rect
			(at 0.94996 -0.649986)
			(size 0.4318 0.6096)
			(layers "B.Cu" "B.Mask" "B.Paste")
			(net "Net_417")
		)
		(pad "2" smd rect
			(at 0.94996 0)
			(size 0.4318 0.6096)
			(layers "B.Cu" "B.Mask" "B.Paste")
			(net "FM_HS1_EN_FUSE")
		)
		(pad "3" smd rect
			(at 0.94996 0.649986)
			(size 0.4318 0.6096)
			(layers "B.Cu" "B.Mask" "B.Paste")
			(net "GND")
		)
		(pad "4" smd rect
			(at -0.94996 0.649986)
			(size 0.4318 0.6096)
			(layers "B.Cu" "B.Mask" "B.Paste")
			(net "FM_HS1_EN_FUSE_BUF")
		)
		(pad "5" smd rect
			(at -0.94996 -0.649986)
			(size 0.4318 0.6096)
			(layers "B.Cu" "B.Mask" "B.Paste")
			(net "P3V3_AUX")
		)
	)
	(footprint ""
		(layer "B.Cu")
		(at 276.8854 -76.454 -90)
		(property "Reference" "PC9"
			(at 0 0 90)
			(layer "B.SilkS")
			(hide yes)
			(effects
				(font
					(size 1.27 1.27)
				)
				(justify mirror)
			)
		)
		(property "Value" ""
			(at 0 0 90)
			(layer "B.Fab")
			(effects
				(font
					(size 1.27 1.27)
				)
				(justify mirror)
			)
		)
		(duplicate_pad_numbers_are_jumpers no)
		(fp_line
			(start -0.7874 0.4064)
			(end 0.7874 0.4064)
			(stroke
				(width 0.1524)
				(type default)
			)
			(layer "B.SilkS")
		)
		(fp_line
			(start 0.7874 0.4064)
			(end 0.7874 -0.4064)
			(stroke
				(width 0.1524)
				(type default)
			)
			(layer "B.SilkS")
		)
		(fp_line
			(start -0.7874 -0.4064)
			(end -0.7874 0.4064)
			(stroke
				(width 0.1524)
				(type default)
			)
			(layer "B.SilkS")
		)
		(fp_line
			(start 0.7874 -0.4064)
			(end -0.7874 -0.4064)
			(stroke
				(width 0.1524)
				(type default)
			)
			(layer "B.SilkS")
		)
		(fp_line
			(start -0.67945 0.3048)
			(end -0.120396 0.3048)
			(stroke
				(width 0.1)
				(type default)
			)
			(layer "B.Fab")
		)
		(fp_line
			(start -0.120396 0.3048)
			(end -0.120396 0.2794)
			(stroke
				(width 0.1)
				(type default)
			)
			(layer "B.Fab")
		)
		(fp_line
			(start 0.12065 0.3048)
			(end 0.67945 0.3048)
			(stroke
				(width 0.1)
				(type default)
			)
			(layer "B.Fab")
		)
		(fp_line
			(start 0.67945 0.3048)
			(end 0.67945 -0.305054)
			(stroke
				(width 0.1)
				(type default)
			)
			(layer "B.Fab")
		)
		(fp_line
			(start -0.120396 0.2794)
			(end 0.12065 0.2794)
			(stroke
				(width 0.1)
				(type default)
			)
			(layer "B.Fab")
		)
		(fp_line
			(start 0.12065 0.2794)
			(end 0.12065 0.3048)
			(stroke
				(width 0.1)
				(type default)
			)
			(layer "B.Fab")
		)
		(fp_line
			(start -0.12065 -0.2794)
			(end -0.12065 -0.3048)
			(stroke
				(width 0.1)
				(type default)
			)
			(layer "B.Fab")
		)
		(fp_line
			(start 0.12065 -0.2794)
			(end -0.12065 -0.2794)
			(stroke
				(width 0.1)
				(type default)
			)
			(layer "B.Fab")
		)
		(fp_line
			(start -0.67945 -0.3048)
			(end -0.67945 0.3048)
			(stroke
				(width 0.1)
				(type default)
			)
			(layer "B.Fab")
		)
		(fp_line
			(start -0.12065 -0.3048)
			(end -0.67945 -0.3048)
			(stroke
				(width 0.1)
				(type default)
			)
			(layer "B.Fab")
		)
		(fp_line
			(start 0.12065 -0.305054)
			(end 0.12065 -0.2794)
			(stroke
				(width 0.1)
				(type default)
			)
			(layer "B.Fab")
		)
		(fp_line
			(start 0.67945 -0.305054)
			(end 0.12065 -0.305054)
			(stroke
				(width 0.1)
				(type default)
			)
			(layer "B.Fab")
		)
		(pad "1" smd circle
			(at 0.40005 0 90)
			(size 0 0)
			(layers "B.Cu" "B.Mask" "B.Paste")
			(net "P52V_HS1_RND")
		)
		(pad "2" smd circle
			(at -0.40005 0 90)
			(size 0 0)
			(layers "B.Cu" "B.Mask" "B.Paste")
			(net "GND_FIELD_SIGNAL")
		)
	)
	(footprint ""
		(layer "B.Cu")
		(at 263.6774 -62.738 180)
		(property "Reference" "PR32"
			(at 0 0 0)
			(layer "B.SilkS")
			(hide yes)
			(effects
				(font
					(size 1.27 1.27)
				)
				(justify mirror)
			)
		)
		(property "Value" ""
			(at 0 0 0)
			(layer "B.Fab")
			(effects
				(font
					(size 1.27 1.27)
				)
				(justify mirror)
			)
		)
		(duplicate_pad_numbers_are_jumpers no)
		(fp_line
			(start 1.651 0.8382)
			(end 1.651 -0.8382)
			(stroke
				(width 0.1524)
				(type default)
			)
			(layer "B.SilkS")
		)
		(fp_line
			(start 1.651 -0.8382)
			(end -1.651 -0.8382)
			(stroke
				(width 0.1524)
				(type default)
			)
			(layer "B.SilkS")
		)
		(fp_line
			(start -1.651 0.8382)
			(end 1.651 0.8382)
			(stroke
				(width 0.1524)
				(type default)
			)
			(layer "B.SilkS")
		)
		(fp_line
			(start -1.651 -0.8382)
			(end -1.651 0.8382)
			(stroke
				(width 0.1524)
				(type default)
			)
			(layer "B.SilkS")
		)
		(fp_line
			(start 1.559814 0.7366)
			(end 1.524 0.7366)
			(stroke
				(width 0.1)
				(type default)
			)
			(layer "B.Fab")
		)
		(fp_line
			(start 1.559814 -0.7366)
			(end 1.559814 0.7366)
			(stroke
				(width 0.1)
				(type default)
			)
			(layer "B.Fab")
		)
		(fp_line
			(start 1.524 0.7366)
			(end -1.524 0.7366)
			(stroke
				(width 0.1)
				(type default)
			)
			(layer "B.Fab")
		)
		(fp_line
			(start 1.524 -0.7366)
			(end 1.559814 -0.7366)
			(stroke
				(width 0.1)
				(type default)
			)
			(layer "B.Fab")
		)
		(fp_line
			(start -1.524 0.7366)
			(end -1.560576 0.7366)
			(stroke
				(width 0.1)
				(type default)
			)
			(layer "B.Fab")
		)
		(fp_line
			(start -1.524 -0.7366)
			(end 1.524 -0.7366)
			(stroke
				(width 0.1)
				(type default)
			)
			(layer "B.Fab")
		)
		(fp_line
			(start -1.560576 0.7366)
			(end -1.560576 -0.7366)
			(stroke
				(width 0.1)
				(type default)
			)
			(layer "B.Fab")
		)
		(fp_line
			(start -1.560576 -0.7366)
			(end -1.524 -0.7366)
			(stroke
				(width 0.1)
				(type default)
			)
			(layer "B.Fab")
		)
		(pad "1" smd rect
			(at 0.94996 0 180)
			(size 1.1176 1.3716)
			(layers "B.Cu" "B.Mask" "B.Paste")
			(net "P52V_HS1_DV_DT_R")
		)
		(pad "2" smd rect
			(at -0.94996 0 180)
			(size 1.1176 1.3716)
			(layers "B.Cu" "B.Mask" "B.Paste")
			(net "P52V_HS1_DV_DT")
		)
	)
	(footprint ""
		(layer "B.Cu")
		(at 173.782736 -63.754 90)
		(property "Reference" "PC606"
			(at 0 0 90)
			(layer "B.SilkS")
			(hide yes)
			(effects
				(font
					(size 1.27 1.27)
				)
				(justify mirror)
			)
		)
		(property "Value" ""
			(at 0 0 90)
			(layer "B.Fab")
			(effects
				(font
					(size 1.27 1.27)
				)
				(justify mirror)
			)
		)
		(duplicate_pad_numbers_are_jumpers no)
		(fp_line
			(start 0.7874 -0.4064)
			(end -0.7874 -0.4064)
			(stroke
				(width 0.1524)
				(type default)
			)
			(layer "B.SilkS")
		)
		(fp_line
			(start -0.7874 -0.4064)
			(end -0.7874 0.4064)
			(stroke
				(width 0.1524)
				(type default)
			)
			(layer "B.SilkS")
		)
		(fp_line
			(start 0.7874 0.4064)
			(end 0.7874 -0.4064)
			(stroke
				(width 0.1524)
				(type default)
			)
			(layer "B.SilkS")
		)
		(fp_line
			(start -0.7874 0.4064)
			(end 0.7874 0.4064)
			(stroke
				(width 0.1524)
				(type default)
			)
			(layer "B.SilkS")
		)
		(fp_line
			(start 0.67945 -0.305054)
			(end 0.12065 -0.305054)
			(stroke
				(width 0.1)
				(type default)
			)
			(layer "B.Fab")
		)
		(fp_line
			(start 0.12065 -0.305054)
			(end 0.12065 -0.2794)
			(stroke
				(width 0.1)
				(type default)
			)
			(layer "B.Fab")
		)
		(fp_line
			(start -0.12065 -0.3048)
			(end -0.67945 -0.3048)
			(stroke
				(width 0.1)
				(type default)
			)
			(layer "B.Fab")
		)
		(fp_line
			(start -0.67945 -0.3048)
			(end -0.67945 0.3048)
			(stroke
				(width 0.1)
				(type default)
			)
			(layer "B.Fab")
		)
		(fp_line
			(start 0.12065 -0.2794)
			(end -0.12065 -0.2794)
			(stroke
				(width 0.1)
				(type default)
			)
			(layer "B.Fab")
		)
		(fp_line
			(start -0.12065 -0.2794)
			(end -0.12065 -0.3048)
			(stroke
				(width 0.1)
				(type default)
			)
			(layer "B.Fab")
		)
		(fp_line
			(start 0.12065 0.2794)
			(end 0.12065 0.3048)
			(stroke
				(width 0.1)
				(type default)
			)
			(layer "B.Fab")
		)
		(fp_line
			(start -0.120396 0.2794)
			(end 0.12065 0.2794)
			(stroke
				(width 0.1)
				(type default)
			)
			(layer "B.Fab")
		)
		(fp_line
			(start 0.67945 0.3048)
			(end 0.67945 -0.305054)
			(stroke
				(width 0.1)
				(type default)
			)
			(layer "B.Fab")
		)
		(fp_line
			(start 0.12065 0.3048)
			(end 0.67945 0.3048)
			(stroke
				(width 0.1)
				(type default)
			)
			(layer "B.Fab")
		)
		(fp_line
			(start -0.120396 0.3048)
			(end -0.120396 0.2794)
			(stroke
				(width 0.1)
				(type default)
			)
			(layer "B.Fab")
		)
		(fp_line
			(start -0.67945 0.3048)
			(end -0.120396 0.3048)
			(stroke
				(width 0.1)
				(type default)
			)
			(layer "B.Fab")
		)
		(pad "1" smd circle
			(at 0.40005 0 270)
			(size 0 0)
			(layers "B.Cu" "B.Mask" "B.Paste")
			(net "P52V_HS2_UVH")
		)
		(pad "2" smd circle
			(at -0.40005 0 270)
			(size 0 0)
			(layers "B.Cu" "B.Mask" "B.Paste")
			(net "GND1_FIELD_SIGNAL")
		)
	)
	(footprint ""
		(layer "B.Cu")
		(at 161.717736 -69.469)
		(property "Reference" "PR7012"
			(at 0 0 0)
			(layer "B.SilkS")
			(hide yes)
			(effects
				(font
					(size 1.27 1.27)
				)
				(justify mirror)
			)
		)
		(property "Value" ""
			(at 0 0 0)
			(layer "B.Fab")
			(effects
				(font
					(size 1.27 1.27)
				)
				(justify mirror)
			)
		)
		(duplicate_pad_numbers_are_jumpers no)
		(fp_line
			(start -0.7874 -0.4064)
			(end -0.7874 0.4064)
			(stroke
				(width 0.1524)
				(type default)
			)
			(layer "B.SilkS")
		)
		(fp_line
			(start -0.7874 0.4064)
			(end 0.7874 0.4064)
			(stroke
				(width 0.1524)
				(type default)
			)
			(layer "B.SilkS")
		)
		(fp_line
			(start 0.7874 -0.4064)
			(end -0.7874 -0.4064)
			(stroke
				(width 0.1524)
				(type default)
			)
			(layer "B.SilkS")
		)
		(fp_line
			(start 0.7874 0.4064)
			(end 0.7874 -0.4064)
			(stroke
				(width 0.1524)
				(type default)
			)
			(layer "B.SilkS")
		)
		(fp_line
			(start -0.67945 -0.3048)
			(end -0.67945 0.3048)
			(stroke
				(width 0.1)
				(type default)
			)
			(layer "B.Fab")
		)
		(fp_line
			(start -0.67945 0.3048)
			(end -0.120396 0.3048)
			(stroke
				(width 0.1)
				(type default)
			)
			(layer "B.Fab")
		)
		(fp_line
			(start -0.12065 -0.3048)
			(end -0.67945 -0.3048)
			(stroke
				(width 0.1)
				(type default)
			)
			(layer "B.Fab")
		)
		(fp_line
			(start -0.12065 -0.2794)
			(end -0.12065 -0.3048)
			(stroke
				(width 0.1)
				(type default)
			)
			(layer "B.Fab")
		)
		(fp_line
			(start -0.120396 0.2794)
			(end 0.12065 0.2794)
			(stroke
				(width 0.1)
				(type default)
			)
			(layer "B.Fab")
		)
		(fp_line
			(start -0.120396 0.3048)
			(end -0.120396 0.2794)
			(stroke
				(width 0.1)
				(type default)
			)
			(layer "B.Fab")
		)
		(fp_line
			(start 0.12065 -0.305054)
			(end 0.12065 -0.2794)
			(stroke
				(width 0.1)
				(type default)
			)
			(layer "B.Fab")
		)
		(fp_line
			(start 0.12065 -0.2794)
			(end -0.12065 -0.2794)
			(stroke
				(width 0.1)
				(type default)
			)
			(layer "B.Fab")
		)
		(fp_line
			(start 0.12065 0.2794)
			(end 0.12065 0.3048)
			(stroke
				(width 0.1)
				(type default)
			)
			(layer "B.Fab")
		)
		(fp_line
			(start 0.12065 0.3048)
			(end 0.67945 0.3048)
			(stroke
				(width 0.1)
				(type default)
			)
			(layer "B.Fab")
		)
		(fp_line
			(start 0.67945 -0.305054)
			(end 0.12065 -0.305054)
			(stroke
				(width 0.1)
				(type default)
			)
			(layer "B.Fab")
		)
		(fp_line
			(start 0.67945 0.3048)
			(end 0.67945 -0.305054)
			(stroke
				(width 0.1)
				(type default)
			)
			(layer "B.Fab")
		)
		(pad "1" smd circle
			(at 0.40005 0 180)
			(size 0 0)
			(layers "B.Cu" "B.Mask" "B.Paste")
			(net "GND1_FIELD_SIGNAL")
		)
		(pad "2" smd circle
			(at -0.40005 0 180)
			(size 0 0)
			(layers "B.Cu" "B.Mask" "B.Paste")
			(net "P52V_HS2_CS")
		)
	)
	(footprint ""
		(layer "B.Cu")
		(at 413.639 -38.989 180)
		(property "Reference" "R5930"
			(at 0 0 0)
			(layer "B.SilkS")
			(hide yes)
			(effects
				(font
					(size 1.27 1.27)
				)
				(justify mirror)
			)
		)
		(property "Value" ""
			(at 0 0 0)
			(layer "B.Fab")
			(effects
				(font
					(size 1.27 1.27)
				)
				(justify mirror)
			)
		)
		(duplicate_pad_numbers_are_jumpers no)
		(fp_line
			(start 0.7874 0.4064)
			(end 0.7874 -0.4064)
			(stroke
				(width 0.1524)
				(type default)
			)
			(layer "B.SilkS")
		)
		(fp_line
			(start 0.7874 -0.4064)
			(end -0.7874 -0.4064)
			(stroke
				(width 0.1524)
				(type default)
			)
			(layer "B.SilkS")
		)
		(fp_line
			(start -0.7874 0.4064)
			(end 0.7874 0.4064)
			(stroke
				(width 0.1524)
				(type default)
			)
			(layer "B.SilkS")
		)
		(fp_line
			(start -0.7874 -0.4064)
			(end -0.7874 0.4064)
			(stroke
				(width 0.1524)
				(type default)
			)
			(layer "B.SilkS")
		)
		(fp_line
			(start 0.67945 0.3048)
			(end 0.67945 -0.305054)
			(stroke
				(width 0.1)
				(type default)
			)
			(layer "B.Fab")
		)
		(fp_line
			(start 0.67945 -0.305054)
			(end 0.12065 -0.305054)
			(stroke
				(width 0.1)
				(type default)
			)
			(layer "B.Fab")
		)
		(fp_line
			(start 0.12065 0.3048)
			(end 0.67945 0.3048)
			(stroke
				(width 0.1)
				(type default)
			)
			(layer "B.Fab")
		)
		(fp_line
			(start 0.12065 0.2794)
			(end 0.12065 0.3048)
			(stroke
				(width 0.1)
				(type default)
			)
			(layer "B.Fab")
		)
		(fp_line
			(start 0.12065 -0.2794)
			(end -0.12065 -0.2794)
			(stroke
				(width 0.1)
				(type default)
			)
			(layer "B.Fab")
		)
		(fp_line
			(start 0.12065 -0.305054)
			(end 0.12065 -0.2794)
			(stroke
				(width 0.1)
				(type default)
			)
			(layer "B.Fab")
		)
		(fp_line
			(start -0.120396 0.3048)
			(end -0.120396 0.2794)
			(stroke
				(width 0.1)
				(type default)
			)
			(layer "B.Fab")
		)
		(fp_line
			(start -0.120396 0.2794)
			(end 0.12065 0.2794)
			(stroke
				(width 0.1)
				(type default)
			)
			(layer "B.Fab")
		)
		(fp_line
			(start -0.12065 -0.2794)
			(end -0.12065 -0.3048)
			(stroke
				(width 0.1)
				(type default)
			)
			(layer "B.Fab")
		)
		(fp_line
			(start -0.12065 -0.3048)
			(end -0.67945 -0.3048)
			(stroke
				(width 0.1)
				(type default)
			)
			(layer "B.Fab")
		)
		(fp_line
			(start -0.67945 0.3048)
			(end -0.120396 0.3048)
			(stroke
				(width 0.1)
				(type default)
			)
			(layer "B.Fab")
		)
		(fp_line
			(start -0.67945 -0.3048)
			(end -0.67945 0.3048)
			(stroke
				(width 0.1)
				(type default)
			)
			(layer "B.Fab")
		)
		(pad "1" smd circle
			(at 0.40005 0)
			(size 0 0)
			(layers "B.Cu" "B.Mask" "B.Paste")
			(net "PWRGD_P12V_FAN_LED_R")
		)
		(pad "2" smd circle
			(at -0.40005 0)
			(size 0 0)
			(layers "B.Cu" "B.Mask" "B.Paste")
			(net "PWRGD_P12V_FAN_LED")
		)
	)
	(footprint ""
		(layer "B.Cu")
		(at 169.210736 -75.311 180)
		(property "Reference" "R5883"
			(at 0 0 0)
			(layer "B.SilkS")
			(hide yes)
			(effects
				(font
					(size 1.27 1.27)
				)
				(justify mirror)
			)
		)
		(property "Value" ""
			(at 0 0 0)
			(layer "B.Fab")
			(effects
				(font
					(size 1.27 1.27)
				)
				(justify mirror)
			)
		)
		(duplicate_pad_numbers_are_jumpers no)
		(fp_line
			(start 0.7874 0.4064)
			(end 0.7874 -0.4064)
			(stroke
				(width 0.1524)
				(type default)
			)
			(layer "B.SilkS")
		)
		(fp_line
			(start 0.7874 -0.4064)
			(end -0.7874 -0.4064)
			(stroke
				(width 0.1524)
				(type default)
			)
			(layer "B.SilkS")
		)
		(fp_line
			(start -0.7874 0.4064)
			(end 0.7874 0.4064)
			(stroke
				(width 0.1524)
				(type default)
			)
			(layer "B.SilkS")
		)
		(fp_line
			(start -0.7874 -0.4064)
			(end -0.7874 0.4064)
			(stroke
				(width 0.1524)
				(type default)
			)
			(layer "B.SilkS")
		)
		(fp_line
			(start 0.67945 0.3048)
			(end 0.67945 -0.305054)
			(stroke
				(width 0.1)
				(type default)
			)
			(layer "B.Fab")
		)
		(fp_line
			(start 0.67945 -0.305054)
			(end 0.12065 -0.305054)
			(stroke
				(width 0.1)
				(type default)
			)
			(layer "B.Fab")
		)
		(fp_line
			(start 0.12065 0.3048)
			(end 0.67945 0.3048)
			(stroke
				(width 0.1)
				(type default)
			)
			(layer "B.Fab")
		)
		(fp_line
			(start 0.12065 0.2794)
			(end 0.12065 0.3048)
			(stroke
				(width 0.1)
				(type default)
			)
			(layer "B.Fab")
		)
		(fp_line
			(start 0.12065 -0.2794)
			(end -0.12065 -0.2794)
			(stroke
				(width 0.1)
				(type default)
			)
			(layer "B.Fab")
		)
		(fp_line
			(start 0.12065 -0.305054)
			(end 0.12065 -0.2794)
			(stroke
				(width 0.1)
				(type default)
			)
			(layer "B.Fab")
		)
		(fp_line
			(start -0.120396 0.3048)
			(end -0.120396 0.2794)
			(stroke
				(width 0.1)
				(type default)
			)
			(layer "B.Fab")
		)
		(fp_line
			(start -0.120396 0.2794)
			(end 0.12065 0.2794)
			(stroke
				(width 0.1)
				(type default)
			)
			(layer "B.Fab")
		)
		(fp_line
			(start -0.12065 -0.2794)
			(end -0.12065 -0.3048)
			(stroke
				(width 0.1)
				(type default)
			)
			(layer "B.Fab")
		)
		(fp_line
			(start -0.12065 -0.3048)
			(end -0.67945 -0.3048)
			(stroke
				(width 0.1)
				(type default)
			)
			(layer "B.Fab")
		)
		(fp_line
			(start -0.67945 0.3048)
			(end -0.120396 0.3048)
			(stroke
				(width 0.1)
				(type default)
			)
			(layer "B.Fab")
		)
		(fp_line
			(start -0.67945 -0.3048)
			(end -0.67945 0.3048)
			(stroke
				(width 0.1)
				(type default)
			)
			(layer "B.Fab")
		)
		(pad "1" smd circle
			(at 0.40005 0)
			(size 0 0)
			(layers "B.Cu" "B.Mask" "B.Paste")
			(net "SMB_P52V_PDB_SDA")
		)
		(pad "2" smd circle
			(at -0.40005 0)
			(size 0 0)
			(layers "B.Cu" "B.Mask" "B.Paste")
			(net "SMB_CM_HS2_3V3SB_DATO")
		)
	)
	(footprint ""
		(layer "B.Cu")
		(at 287.8074 -81.534 180)
		(property "Reference" "PC487"
			(at 0 0 0)
			(layer "B.SilkS")
			(hide yes)
			(effects
				(font
					(size 1.27 1.27)
				)
				(justify mirror)
			)
		)
		(property "Value" ""
			(at 0 0 0)
			(layer "B.Fab")
			(effects
				(font
					(size 1.27 1.27)
				)
				(justify mirror)
			)
		)
		(duplicate_pad_numbers_are_jumpers no)
		(fp_line
			(start 2.2098 0.9398)
			(end 2.2098 -0.9398)
			(stroke
				(width 0.1524)
				(type default)
			)
			(layer "B.SilkS")
		)
		(fp_line
			(start 2.2098 -0.9398)
			(end -2.2098 -0.9398)
			(stroke
				(width 0.1524)
				(type default)
			)
			(layer "B.SilkS")
		)
		(fp_line
			(start -2.2098 0.9398)
			(end 2.2098 0.9398)
			(stroke
				(width 0.1524)
				(type default)
			)
			(layer "B.SilkS")
		)
		(fp_line
			(start -2.2098 -0.9398)
			(end -2.2098 0.9398)
			(stroke
				(width 0.1524)
				(type default)
			)
			(layer "B.SilkS")
		)
		(fp_line
			(start 1.700022 0.899922)
			(end 1.700022 -0.899922)
			(stroke
				(width 0.1)
				(type default)
			)
			(layer "B.Fab")
		)
		(fp_line
			(start 1.700022 -0.899922)
			(end -1.700022 -0.899922)
			(stroke
				(width 0.1)
				(type default)
			)
			(layer "B.Fab")
		)
		(fp_line
			(start -1.700022 0.899922)
			(end 1.700022 0.899922)
			(stroke
				(width 0.1)
				(type default)
			)
			(layer "B.Fab")
		)
		(fp_line
			(start -1.700022 -0.899922)
			(end -1.700022 0.899922)
			(stroke
				(width 0.1)
				(type default)
			)
			(layer "B.Fab")
		)
		(pad "1" smd rect
			(at 1.4732 0 180)
			(size 1.1684 1.5748)
			(layers "B.Cu" "B.Mask" "B.Paste")
			(net "P52V_HS1_DVCC")
		)
		(pad "2" smd rect
			(at -1.4732 0 180)
			(size 1.1684 1.5748)
			(layers "B.Cu" "B.Mask" "B.Paste")
			(net "GND")
		)
	)
	(footprint ""
		(layer "B.Cu")
		(at 278.7904 -74.549 180)
		(property "Reference" "PC590"
			(at 0 0 0)
			(layer "B.SilkS")
			(hide yes)
			(effects
				(font
					(size 1.27 1.27)
				)
				(justify mirror)
			)
		)
		(property "Value" ""
			(at 0 0 0)
			(layer "B.Fab")
			(effects
				(font
					(size 1.27 1.27)
				)
				(justify mirror)
			)
		)
		(duplicate_pad_numbers_are_jumpers no)
		(fp_line
			(start 0.7874 0.4064)
			(end 0.7874 -0.4064)
			(stroke
				(width 0.1524)
				(type default)
			)
			(layer "B.SilkS")
		)
		(fp_line
			(start 0.7874 -0.4064)
			(end -0.7874 -0.4064)
			(stroke
				(width 0.1524)
				(type default)
			)
			(layer "B.SilkS")
		)
		(fp_line
			(start -0.7874 0.4064)
			(end 0.7874 0.4064)
			(stroke
				(width 0.1524)
				(type default)
			)
			(layer "B.SilkS")
		)
		(fp_line
			(start -0.7874 -0.4064)
			(end -0.7874 0.4064)
			(stroke
				(width 0.1524)
				(type default)
			)
			(layer "B.SilkS")
		)
		(fp_line
			(start 0.67945 0.3048)
			(end 0.67945 -0.305054)
			(stroke
				(width 0.1)
				(type default)
			)
			(layer "B.Fab")
		)
		(fp_line
			(start 0.67945 -0.305054)
			(end 0.12065 -0.305054)
			(stroke
				(width 0.1)
				(type default)
			)
			(layer "B.Fab")
		)
		(fp_line
			(start 0.12065 0.3048)
			(end 0.67945 0.3048)
			(stroke
				(width 0.1)
				(type default)
			)
			(layer "B.Fab")
		)
		(fp_line
			(start 0.12065 0.2794)
			(end 0.12065 0.3048)
			(stroke
				(width 0.1)
				(type default)
			)
			(layer "B.Fab")
		)
		(fp_line
			(start 0.12065 -0.2794)
			(end -0.12065 -0.2794)
			(stroke
				(width 0.1)
				(type default)
			)
			(layer "B.Fab")
		)
		(fp_line
			(start 0.12065 -0.305054)
			(end 0.12065 -0.2794)
			(stroke
				(width 0.1)
				(type default)
			)
			(layer "B.Fab")
		)
		(fp_line
			(start -0.120396 0.3048)
			(end -0.120396 0.2794)
			(stroke
				(width 0.1)
				(type default)
			)
			(layer "B.Fab")
		)
		(fp_line
			(start -0.120396 0.2794)
			(end 0.12065 0.2794)
			(stroke
				(width 0.1)
				(type default)
			)
			(layer "B.Fab")
		)
		(fp_line
			(start -0.12065 -0.2794)
			(end -0.12065 -0.3048)
			(stroke
				(width 0.1)
				(type default)
			)
			(layer "B.Fab")
		)
		(fp_line
			(start -0.12065 -0.3048)
			(end -0.67945 -0.3048)
			(stroke
				(width 0.1)
				(type default)
			)
			(layer "B.Fab")
		)
		(fp_line
			(start -0.67945 0.3048)
			(end -0.120396 0.3048)
			(stroke
				(width 0.1)
				(type default)
			)
			(layer "B.Fab")
		)
		(fp_line
			(start -0.67945 -0.3048)
			(end -0.67945 0.3048)
			(stroke
				(width 0.1)
				(type default)
			)
			(layer "B.Fab")
		)
		(pad "1" smd circle
			(at 0.40005 0)
			(size 0 0)
			(layers "B.Cu" "B.Mask" "B.Paste")
			(net "P52V_HS1_ISET")
		)
		(pad "2" smd circle
			(at -0.40005 0)
			(size 0 0)
			(layers "B.Cu" "B.Mask" "B.Paste")
			(net "GND_FIELD_SIGNAL")
		)
	)
	(footprint ""
		(layer "B.Cu")
		(at 336.3214 -50.6476 90)
		(property "Reference" "R5860"
			(at 0 0 90)
			(layer "B.SilkS")
			(hide yes)
			(effects
				(font
					(size 1.27 1.27)
				)
				(justify mirror)
			)
		)
		(property "Value" ""
			(at 0 0 90)
			(layer "B.Fab")
			(effects
				(font
					(size 1.27 1.27)
				)
				(justify mirror)
			)
		)
		(duplicate_pad_numbers_are_jumpers no)
		(fp_line
			(start 0.7874 -0.4064)
			(end -0.7874 -0.4064)
			(stroke
				(width 0.1524)
				(type default)
			)
			(layer "B.SilkS")
		)
		(fp_line
			(start -0.7874 -0.4064)
			(end -0.7874 0.4064)
			(stroke
				(width 0.1524)
				(type default)
			)
			(layer "B.SilkS")
		)
		(fp_line
			(start 0.7874 0.4064)
			(end 0.7874 -0.4064)
			(stroke
				(width 0.1524)
				(type default)
			)
			(layer "B.SilkS")
		)
		(fp_line
			(start -0.7874 0.4064)
			(end 0.7874 0.4064)
			(stroke
				(width 0.1524)
				(type default)
			)
			(layer "B.SilkS")
		)
		(fp_line
			(start 0.67945 -0.305054)
			(end 0.12065 -0.305054)
			(stroke
				(width 0.1)
				(type default)
			)
			(layer "B.Fab")
		)
		(fp_line
			(start 0.12065 -0.305054)
			(end 0.12065 -0.2794)
			(stroke
				(width 0.1)
				(type default)
			)
			(layer "B.Fab")
		)
		(fp_line
			(start -0.12065 -0.3048)
			(end -0.67945 -0.3048)
			(stroke
				(width 0.1)
				(type default)
			)
			(layer "B.Fab")
		)
		(fp_line
			(start -0.67945 -0.3048)
			(end -0.67945 0.3048)
			(stroke
				(width 0.1)
				(type default)
			)
			(layer "B.Fab")
		)
		(fp_line
			(start 0.12065 -0.2794)
			(end -0.12065 -0.2794)
			(stroke
				(width 0.1)
				(type default)
			)
			(layer "B.Fab")
		)
		(fp_line
			(start -0.12065 -0.2794)
			(end -0.12065 -0.3048)
			(stroke
				(width 0.1)
				(type default)
			)
			(layer "B.Fab")
		)
		(fp_line
			(start 0.12065 0.2794)
			(end 0.12065 0.3048)
			(stroke
				(width 0.1)
				(type default)
			)
			(layer "B.Fab")
		)
		(fp_line
			(start -0.120396 0.2794)
			(end 0.12065 0.2794)
			(stroke
				(width 0.1)
				(type default)
			)
			(layer "B.Fab")
		)
		(fp_line
			(start 0.67945 0.3048)
			(end 0.67945 -0.305054)
			(stroke
				(width 0.1)
				(type default)
			)
			(layer "B.Fab")
		)
		(fp_line
			(start 0.12065 0.3048)
			(end 0.67945 0.3048)
			(stroke
				(width 0.1)
				(type default)
			)
			(layer "B.Fab")
		)
		(fp_line
			(start -0.120396 0.3048)
			(end -0.120396 0.2794)
			(stroke
				(width 0.1)
				(type default)
			)
			(layer "B.Fab")
		)
		(fp_line
			(start -0.67945 0.3048)
			(end -0.120396 0.3048)
			(stroke
				(width 0.1)
				(type default)
			)
			(layer "B.Fab")
		)
		(pad "1" smd circle
			(at 0.40005 0 270)
			(size 0 0)
			(layers "B.Cu" "B.Mask" "B.Paste")
			(net "P52V_HS1_GATE1_R")
		)
		(pad "2" smd circle
			(at -0.40005 0 270)
			(size 0 0)
			(layers "B.Cu" "B.Mask" "B.Paste")
			(net "P52V_HS1_1272_GATE")
		)
	)
	(footprint ""
		(layer "B.Cu")
		(at 275.8694 -76.454 -90)
		(property "Reference" "PC575"
			(at 0 0 90)
			(layer "B.SilkS")
			(hide yes)
			(effects
				(font
					(size 1.27 1.27)
				)
				(justify mirror)
			)
		)
		(property "Value" ""
			(at 0 0 90)
			(layer "B.Fab")
			(effects
				(font
					(size 1.27 1.27)
				)
				(justify mirror)
			)
		)
		(duplicate_pad_numbers_are_jumpers no)
		(fp_line
			(start -0.7874 0.4064)
			(end 0.7874 0.4064)
			(stroke
				(width 0.1524)
				(type default)
			)
			(layer "B.SilkS")
		)
		(fp_line
			(start 0.7874 0.4064)
			(end 0.7874 -0.4064)
			(stroke
				(width 0.1524)
				(type default)
			)
			(layer "B.SilkS")
		)
		(fp_line
			(start -0.7874 -0.4064)
			(end -0.7874 0.4064)
			(stroke
				(width 0.1524)
				(type default)
			)
			(layer "B.SilkS")
		)
		(fp_line
			(start 0.7874 -0.4064)
			(end -0.7874 -0.4064)
			(stroke
				(width 0.1524)
				(type default)
			)
			(layer "B.SilkS")
		)
		(fp_line
			(start -0.67945 0.3048)
			(end -0.120396 0.3048)
			(stroke
				(width 0.1)
				(type default)
			)
			(layer "B.Fab")
		)
		(fp_line
			(start -0.120396 0.3048)
			(end -0.120396 0.2794)
			(stroke
				(width 0.1)
				(type default)
			)
			(layer "B.Fab")
		)
		(fp_line
			(start 0.12065 0.3048)
			(end 0.67945 0.3048)
			(stroke
				(width 0.1)
				(type default)
			)
			(layer "B.Fab")
		)
		(fp_line
			(start 0.67945 0.3048)
			(end 0.67945 -0.305054)
			(stroke
				(width 0.1)
				(type default)
			)
			(layer "B.Fab")
		)
		(fp_line
			(start -0.120396 0.2794)
			(end 0.12065 0.2794)
			(stroke
				(width 0.1)
				(type default)
			)
			(layer "B.Fab")
		)
		(fp_line
			(start 0.12065 0.2794)
			(end 0.12065 0.3048)
			(stroke
				(width 0.1)
				(type default)
			)
			(layer "B.Fab")
		)
		(fp_line
			(start -0.12065 -0.2794)
			(end -0.12065 -0.3048)
			(stroke
				(width 0.1)
				(type default)
			)
			(layer "B.Fab")
		)
		(fp_line
			(start 0.12065 -0.2794)
			(end -0.12065 -0.2794)
			(stroke
				(width 0.1)
				(type default)
			)
			(layer "B.Fab")
		)
		(fp_line
			(start -0.67945 -0.3048)
			(end -0.67945 0.3048)
			(stroke
				(width 0.1)
				(type default)
			)
			(layer "B.Fab")
		)
		(fp_line
			(start -0.12065 -0.3048)
			(end -0.67945 -0.3048)
			(stroke
				(width 0.1)
				(type default)
			)
			(layer "B.Fab")
		)
		(fp_line
			(start 0.12065 -0.305054)
			(end 0.12065 -0.2794)
			(stroke
				(width 0.1)
				(type default)
			)
			(layer "B.Fab")
		)
		(fp_line
			(start 0.67945 -0.305054)
			(end 0.12065 -0.305054)
			(stroke
				(width 0.1)
				(type default)
			)
			(layer "B.Fab")
		)
		(pad "1" smd circle
			(at 0.40005 0 90)
			(size 0 0)
			(layers "B.Cu" "B.Mask" "B.Paste")
			(net "P52V_HS1_OV")
		)
		(pad "2" smd circle
			(at -0.40005 0 90)
			(size 0 0)
			(layers "B.Cu" "B.Mask" "B.Paste")
			(net "GND_FIELD_SIGNAL")
		)
	)
	(footprint ""
		(layer "B.Cu")
		(at 260.2484 -49.149 -90)
		(property "Reference" "R398"
			(at 0 0 90)
			(layer "B.SilkS")
			(hide yes)
			(effects
				(font
					(size 1.27 1.27)
				)
				(justify mirror)
			)
		)
		(property "Value" ""
			(at 0 0 90)
			(layer "B.Fab")
			(effects
				(font
					(size 1.27 1.27)
				)
				(justify mirror)
			)
		)
		(duplicate_pad_numbers_are_jumpers no)
		(fp_line
			(start -1.651 0.8382)
			(end 1.651 0.8382)
			(stroke
				(width 0.1524)
				(type default)
			)
			(layer "B.SilkS")
		)
		(fp_line
			(start 1.651 0.8382)
			(end 1.651 -0.8382)
			(stroke
				(width 0.1524)
				(type default)
			)
			(layer "B.SilkS")
		)
		(fp_line
			(start -1.651 -0.8382)
			(end -1.651 0.8382)
			(stroke
				(width 0.1524)
				(type default)
			)
			(layer "B.SilkS")
		)
		(fp_line
			(start 1.651 -0.8382)
			(end -1.651 -0.8382)
			(stroke
				(width 0.1524)
				(type default)
			)
			(layer "B.SilkS")
		)
		(fp_line
			(start -1.560576 0.7366)
			(end -1.560576 -0.7366)
			(stroke
				(width 0.1)
				(type default)
			)
			(layer "B.Fab")
		)
		(fp_line
			(start -1.524 0.7366)
			(end -1.560576 0.7366)
			(stroke
				(width 0.1)
				(type default)
			)
			(layer "B.Fab")
		)
		(fp_line
			(start 1.524 0.7366)
			(end -1.524 0.7366)
			(stroke
				(width 0.1)
				(type default)
			)
			(layer "B.Fab")
		)
		(fp_line
			(start 1.559814 0.7366)
			(end 1.524 0.7366)
			(stroke
				(width 0.1)
				(type default)
			)
			(layer "B.Fab")
		)
		(fp_line
			(start -1.560576 -0.7366)
			(end -1.524 -0.7366)
			(stroke
				(width 0.1)
				(type default)
			)
			(layer "B.Fab")
		)
		(fp_line
			(start -1.524 -0.7366)
			(end 1.524 -0.7366)
			(stroke
				(width 0.1)
				(type default)
			)
			(layer "B.Fab")
		)
		(fp_line
			(start 1.524 -0.7366)
			(end 1.559814 -0.7366)
			(stroke
				(width 0.1)
				(type default)
			)
			(layer "B.Fab")
		)
		(fp_line
			(start 1.559814 -0.7366)
			(end 1.559814 0.7366)
			(stroke
				(width 0.1)
				(type default)
			)
			(layer "B.Fab")
		)
		(pad "1" smd rect
			(at 0.94996 0 270)
			(size 1.1176 1.3716)
			(layers "B.Cu" "B.Mask" "B.Paste")
			(net "P52V_1_FUSE_1")
		)
		(pad "2" smd rect
			(at -0.94996 0 270)
			(size 1.1176 1.3716)
			(layers "B.Cu" "B.Mask" "B.Paste")
			(net "FM_HS1_EN_FUSE")
		)
	)
	(footprint ""
		(layer "B.Cu")
		(at 151.0284 -62.865 -90)
		(property "Reference" "PR7004"
			(at 0 0 90)
			(layer "B.SilkS")
			(hide yes)
			(effects
				(font
					(size 1.27 1.27)
				)
				(justify mirror)
			)
		)
		(property "Value" ""
			(at 0 0 90)
			(layer "B.Fab")
			(effects
				(font
					(size 1.27 1.27)
				)
				(justify mirror)
			)
		)
		(duplicate_pad_numbers_are_jumpers no)
		(fp_line
			(start -1.651 0.8382)
			(end 1.651 0.8382)
			(stroke
				(width 0.1524)
				(type default)
			)
			(layer "B.SilkS")
		)
		(fp_line
			(start 1.651 0.8382)
			(end 1.651 -0.8382)
			(stroke
				(width 0.1524)
				(type default)
			)
			(layer "B.SilkS")
		)
		(fp_line
			(start -1.651 -0.8382)
			(end -1.651 0.8382)
			(stroke
				(width 0.1524)
				(type default)
			)
			(layer "B.SilkS")
		)
		(fp_line
			(start 1.651 -0.8382)
			(end -1.651 -0.8382)
			(stroke
				(width 0.1524)
				(type default)
			)
			(layer "B.SilkS")
		)
		(fp_line
			(start -1.560576 0.7366)
			(end -1.560576 -0.7366)
			(stroke
				(width 0.1)
				(type default)
			)
			(layer "B.Fab")
		)
		(fp_line
			(start -1.524 0.7366)
			(end -1.560576 0.7366)
			(stroke
				(width 0.1)
				(type default)
			)
			(layer "B.Fab")
		)
		(fp_line
			(start 1.524 0.7366)
			(end -1.524 0.7366)
			(stroke
				(width 0.1)
				(type default)
			)
			(layer "B.Fab")
		)
		(fp_line
			(start 1.559814 0.7366)
			(end 1.524 0.7366)
			(stroke
				(width 0.1)
				(type default)
			)
			(layer "B.Fab")
		)
		(fp_line
			(start -1.560576 -0.7366)
			(end -1.524 -0.7366)
			(stroke
				(width 0.1)
				(type default)
			)
			(layer "B.Fab")
		)
		(fp_line
			(start -1.524 -0.7366)
			(end 1.524 -0.7366)
			(stroke
				(width 0.1)
				(type default)
			)
			(layer "B.Fab")
		)
		(fp_line
			(start 1.524 -0.7366)
			(end 1.559814 -0.7366)
			(stroke
				(width 0.1)
				(type default)
			)
			(layer "B.Fab")
		)
		(fp_line
			(start 1.559814 -0.7366)
			(end 1.559814 0.7366)
			(stroke
				(width 0.1)
				(type default)
			)
			(layer "B.Fab")
		)
		(pad "1" smd rect
			(at 0.94996 0 270)
			(size 1.1176 1.3716)
			(layers "B.Cu" "B.Mask" "B.Paste")
			(net "P52V_HS2")
		)
		(pad "2" smd rect
			(at -0.94996 0 270)
			(size 1.1176 1.3716)
			(layers "B.Cu" "B.Mask" "B.Paste")
			(net "P52V_HS2_VDSFB")
		)
	)
	(footprint ""
		(layer "B.Cu")
		(at 338.8614 -39.243 -90)
		(property "Reference" "PD16"
			(at 3.937 1.44907 270)
			(unlocked yes)
			(layer "B.SilkS")
			(effects
				(font
					(size 0.7874 0.5842)
					(thickness 0.1524)
				)
				(justify left mirror)
			)
		)
		(property "Value" ""
			(at 0 0 90)
			(layer "B.Fab")
			(effects
				(font
					(size 1.27 1.27)
				)
				(justify mirror)
			)
		)
		(duplicate_pad_numbers_are_jumpers no)
		(fp_line
			(start -2.032 0.7112)
			(end 1.651 0.7112)
			(stroke
				(width 0.1524)
				(type default)
			)
			(layer "B.SilkS")
		)
		(fp_line
			(start 1.651 0.7112)
			(end 1.651 -0.7112)
			(stroke
				(width 0.1524)
				(type default)
			)
			(layer "B.SilkS")
		)
		(fp_line
			(start -1.778 0.6858)
			(end -1.778 -0.6858)
			(stroke
				(width 0.1524)
				(type default)
			)
			(layer "B.SilkS")
		)
		(fp_line
			(start 0.299974 0.500126)
			(end -0.199898 0)
			(stroke
				(width 0.1524)
				(type default)
			)
			(layer "B.SilkS")
		)
		(fp_line
			(start -0.199898 0)
			(end 0.299974 -0.500126)
			(stroke
				(width 0.1524)
				(type default)
			)
			(layer "B.SilkS")
		)
		(fp_line
			(start -0.299974 -0.500126)
			(end -0.299974 0.500126)
			(stroke
				(width 0.1524)
				(type default)
			)
			(layer "B.SilkS")
		)
		(fp_line
			(start 0.299974 -0.500126)
			(end 0.299974 0.500126)
			(stroke
				(width 0.1524)
				(type default)
			)
			(layer "B.SilkS")
		)
		(fp_line
			(start -1.905 -0.6858)
			(end -1.905 0.6858)
			(stroke
				(width 0.1524)
				(type default)
			)
			(layer "B.SilkS")
		)
		(fp_line
			(start -1.651 -0.6858)
			(end -1.651 0.6858)
			(stroke
				(width 0.1524)
				(type default)
			)
			(layer "B.SilkS")
		)
		(fp_line
			(start -2.032 -0.7112)
			(end -2.032 0.7112)
			(stroke
				(width 0.1524)
				(type default)
			)
			(layer "B.SilkS")
		)
		(fp_line
			(start 1.651 -0.7112)
			(end -2.032 -0.7112)
			(stroke
				(width 0.1524)
				(type default)
			)
			(layer "B.SilkS")
		)
		(fp_line
			(start -0.899922 0.700024)
			(end 0.899922 0.700024)
			(stroke
				(width 0.1)
				(type default)
			)
			(layer "B.Fab")
		)
		(fp_line
			(start 0.899922 0.700024)
			(end 0.899922 0.175006)
			(stroke
				(width 0.1)
				(type default)
			)
			(layer "B.Fab")
		)
		(fp_line
			(start 0.299974 0.500126)
			(end -0.199898 0)
			(stroke
				(width 0.1)
				(type default)
			)
			(layer "B.Fab")
		)
		(fp_line
			(start -1.35001 0.175006)
			(end -0.899922 0.175006)
			(stroke
				(width 0.1)
				(type default)
			)
			(layer "B.Fab")
		)
		(fp_line
			(start -0.899922 0.175006)
			(end -0.899922 0.700024)
			(stroke
				(width 0.1)
				(type default)
			)
			(layer "B.Fab")
		)
		(fp_line
			(start 0.899922 0.175006)
			(end 1.35001 0.175006)
			(stroke
				(width 0.1)
				(type default)
			)
			(layer "B.Fab")
		)
		(fp_line
			(start 1.35001 0.175006)
			(end 1.35001 -0.225044)
			(stroke
				(width 0.1)
				(type default)
			)
			(layer "B.Fab")
		)
		(fp_line
			(start -0.199898 0)
			(end 0.299974 -0.500126)
			(stroke
				(width 0.1)
				(type default)
			)
			(layer "B.Fab")
		)
		(fp_line
			(start -1.35001 -0.225044)
			(end -1.35001 0.175006)
			(stroke
				(width 0.1)
				(type default)
			)
			(layer "B.Fab")
		)
		(fp_line
			(start -0.899922 -0.225044)
			(end -1.35001 -0.225044)
			(stroke
				(width 0.1)
				(type default)
			)
			(layer "B.Fab")
		)
		(fp_line
			(start 0.899922 -0.225044)
			(end 0.899922 -0.700024)
			(stroke
				(width 0.1)
				(type default)
			)
			(layer "B.Fab")
		)
		(fp_line
			(start 1.35001 -0.225044)
			(end 0.899922 -0.225044)
			(stroke
				(width 0.1)
				(type default)
			)
			(layer "B.Fab")
		)
		(fp_line
			(start -0.299974 -0.500126)
			(end -0.299974 0.500126)
			(stroke
				(width 0.1)
				(type default)
			)
			(layer "B.Fab")
		)
		(fp_line
			(start 0.299974 -0.500126)
			(end 0.299974 0.500126)
			(stroke
				(width 0.1)
				(type default)
			)
			(layer "B.Fab")
		)
		(fp_line
			(start -0.899922 -0.700024)
			(end -0.899922 -0.225044)
			(stroke
				(width 0.1)
				(type default)
			)
			(layer "B.Fab")
		)
		(fp_line
			(start 0.899922 -0.700024)
			(end -0.899922 -0.700024)
			(stroke
				(width 0.1)
				(type default)
			)
			(layer "B.Fab")
		)
		(fp_text user "+"
			(at 3.556 -0.19685 270)
			(unlocked yes)
			(layer "B.SilkS")
			(effects
				(font
					(size 1.905 1.4224)
					(thickness 0.1524)
				)
				(justify left mirror)
			)
		)
		(fp_text user "-"
			(at -1.8288 -0.24765 270)
			(unlocked yes)
			(layer "B.SilkS")
			(effects
				(font
					(size 1.905 1.4224)
					(thickness 0.1524)
				)
				(justify left mirror)
			)
		)
		(fp_text user "+"
			(at 2.794 -0.19685 270)
			(unlocked yes)
			(layer "B.Fab")
			(effects
				(font
					(size 1.905 1.4224)
					(thickness 0.1524)
				)
				(justify left mirror)
			)
		)
		(fp_text user "-"
			(at -1.8288 -0.24765 270)
			(unlocked yes)
			(layer "B.Fab")
			(effects
				(font
					(size 1.905 1.4224)
					(thickness 0.1524)
				)
				(justify left mirror)
			)
		)
		(pad "1" smd rect
			(at 1.0922 0 270)
			(size 0.8128 0.8636)
			(layers "B.Cu" "B.Mask" "B.Paste")
			(net "P52V_HS1_4287_GATE2_R")
		)
		(pad "2" smd rect
			(at -1.0922 0 90)
			(size 0.8128 0.8636)
			(layers "B.Cu" "B.Mask" "B.Paste")
			(net "P52V_HS1_GATE2_R1")
		)
	)
	(footprint ""
		(layer "B.Cu")
		(at 169.210736 -74.295 180)
		(property "Reference" "R5882"
			(at 0 0 0)
			(layer "B.SilkS")
			(hide yes)
			(effects
				(font
					(size 1.27 1.27)
				)
				(justify mirror)
			)
		)
		(property "Value" ""
			(at 0 0 0)
			(layer "B.Fab")
			(effects
				(font
					(size 1.27 1.27)
				)
				(justify mirror)
			)
		)
		(duplicate_pad_numbers_are_jumpers no)
		(fp_line
			(start 0.7874 0.4064)
			(end 0.7874 -0.4064)
			(stroke
				(width 0.1524)
				(type default)
			)
			(layer "B.SilkS")
		)
		(fp_line
			(start 0.7874 -0.4064)
			(end -0.7874 -0.4064)
			(stroke
				(width 0.1524)
				(type default)
			)
			(layer "B.SilkS")
		)
		(fp_line
			(start -0.7874 0.4064)
			(end 0.7874 0.4064)
			(stroke
				(width 0.1524)
				(type default)
			)
			(layer "B.SilkS")
		)
		(fp_line
			(start -0.7874 -0.4064)
			(end -0.7874 0.4064)
			(stroke
				(width 0.1524)
				(type default)
			)
			(layer "B.SilkS")
		)
		(fp_line
			(start 0.67945 0.3048)
			(end 0.67945 -0.305054)
			(stroke
				(width 0.1)
				(type default)
			)
			(layer "B.Fab")
		)
		(fp_line
			(start 0.67945 -0.305054)
			(end 0.12065 -0.305054)
			(stroke
				(width 0.1)
				(type default)
			)
			(layer "B.Fab")
		)
		(fp_line
			(start 0.12065 0.3048)
			(end 0.67945 0.3048)
			(stroke
				(width 0.1)
				(type default)
			)
			(layer "B.Fab")
		)
		(fp_line
			(start 0.12065 0.2794)
			(end 0.12065 0.3048)
			(stroke
				(width 0.1)
				(type default)
			)
			(layer "B.Fab")
		)
		(fp_line
			(start 0.12065 -0.2794)
			(end -0.12065 -0.2794)
			(stroke
				(width 0.1)
				(type default)
			)
			(layer "B.Fab")
		)
		(fp_line
			(start 0.12065 -0.305054)
			(end 0.12065 -0.2794)
			(stroke
				(width 0.1)
				(type default)
			)
			(layer "B.Fab")
		)
		(fp_line
			(start -0.120396 0.3048)
			(end -0.120396 0.2794)
			(stroke
				(width 0.1)
				(type default)
			)
			(layer "B.Fab")
		)
		(fp_line
			(start -0.120396 0.2794)
			(end 0.12065 0.2794)
			(stroke
				(width 0.1)
				(type default)
			)
			(layer "B.Fab")
		)
		(fp_line
			(start -0.12065 -0.2794)
			(end -0.12065 -0.3048)
			(stroke
				(width 0.1)
				(type default)
			)
			(layer "B.Fab")
		)
		(fp_line
			(start -0.12065 -0.3048)
			(end -0.67945 -0.3048)
			(stroke
				(width 0.1)
				(type default)
			)
			(layer "B.Fab")
		)
		(fp_line
			(start -0.67945 0.3048)
			(end -0.120396 0.3048)
			(stroke
				(width 0.1)
				(type default)
			)
			(layer "B.Fab")
		)
		(fp_line
			(start -0.67945 -0.3048)
			(end -0.67945 0.3048)
			(stroke
				(width 0.1)
				(type default)
			)
			(layer "B.Fab")
		)
		(pad "1" smd circle
			(at 0.40005 0)
			(size 0 0)
			(layers "B.Cu" "B.Mask" "B.Paste")
			(net "SMB_P52V_PDB_SDA")
		)
		(pad "2" smd circle
			(at -0.40005 0)
			(size 0 0)
			(layers "B.Cu" "B.Mask" "B.Paste")
			(net "SMB_CM_HS2_3V3SB_DATI")
		)
	)
	(footprint ""
		(layer "B.Cu")
		(at 282.575 -91.567 -90)
		(property "Reference" "R5904"
			(at 0 0 90)
			(layer "B.SilkS")
			(hide yes)
			(effects
				(font
					(size 1.27 1.27)
				)
				(justify mirror)
			)
		)
		(property "Value" ""
			(at 0 0 90)
			(layer "B.Fab")
			(effects
				(font
					(size 1.27 1.27)
				)
				(justify mirror)
			)
		)
		(duplicate_pad_numbers_are_jumpers no)
		(fp_line
			(start -0.7874 0.4064)
			(end 0.7874 0.4064)
			(stroke
				(width 0.1524)
				(type default)
			)
			(layer "B.SilkS")
		)
		(fp_line
			(start 0.7874 0.4064)
			(end 0.7874 -0.4064)
			(stroke
				(width 0.1524)
				(type default)
			)
			(layer "B.SilkS")
		)
		(fp_line
			(start -0.7874 -0.4064)
			(end -0.7874 0.4064)
			(stroke
				(width 0.1524)
				(type default)
			)
			(layer "B.SilkS")
		)
		(fp_line
			(start 0.7874 -0.4064)
			(end -0.7874 -0.4064)
			(stroke
				(width 0.1524)
				(type default)
			)
			(layer "B.SilkS")
		)
		(fp_line
			(start -0.67945 0.3048)
			(end -0.120396 0.3048)
			(stroke
				(width 0.1)
				(type default)
			)
			(layer "B.Fab")
		)
		(fp_line
			(start -0.120396 0.3048)
			(end -0.120396 0.2794)
			(stroke
				(width 0.1)
				(type default)
			)
			(layer "B.Fab")
		)
		(fp_line
			(start 0.12065 0.3048)
			(end 0.67945 0.3048)
			(stroke
				(width 0.1)
				(type default)
			)
			(layer "B.Fab")
		)
		(fp_line
			(start 0.67945 0.3048)
			(end 0.67945 -0.305054)
			(stroke
				(width 0.1)
				(type default)
			)
			(layer "B.Fab")
		)
		(fp_line
			(start -0.120396 0.2794)
			(end 0.12065 0.2794)
			(stroke
				(width 0.1)
				(type default)
			)
			(layer "B.Fab")
		)
		(fp_line
			(start 0.12065 0.2794)
			(end 0.12065 0.3048)
			(stroke
				(width 0.1)
				(type default)
			)
			(layer "B.Fab")
		)
		(fp_line
			(start -0.12065 -0.2794)
			(end -0.12065 -0.3048)
			(stroke
				(width 0.1)
				(type default)
			)
			(layer "B.Fab")
		)
		(fp_line
			(start 0.12065 -0.2794)
			(end -0.12065 -0.2794)
			(stroke
				(width 0.1)
				(type default)
			)
			(layer "B.Fab")
		)
		(fp_line
			(start -0.67945 -0.3048)
			(end -0.67945 0.3048)
			(stroke
				(width 0.1)
				(type default)
			)
			(layer "B.Fab")
		)
		(fp_line
			(start -0.12065 -0.3048)
			(end -0.67945 -0.3048)
			(stroke
				(width 0.1)
				(type default)
			)
			(layer "B.Fab")
		)
		(fp_line
			(start 0.12065 -0.305054)
			(end 0.12065 -0.2794)
			(stroke
				(width 0.1)
				(type default)
			)
			(layer "B.Fab")
		)
		(fp_line
			(start 0.67945 -0.305054)
			(end 0.12065 -0.305054)
			(stroke
				(width 0.1)
				(type default)
			)
			(layer "B.Fab")
		)
		(pad "1" smd circle
			(at 0.40005 0 90)
			(size 0 0)
			(layers "B.Cu" "B.Mask" "B.Paste")
			(net "FM_HS1_EN_BUSBAR")
		)
		(pad "2" smd circle
			(at -0.40005 0 90)
			(size 0 0)
			(layers "B.Cu" "B.Mask" "B.Paste")
			(net "GND")
		)
	)
	(footprint ""
		(layer "B.Cu")
		(at 168.829736 -65.659)
		(property "Reference" "PC610"
			(at 0 0 0)
			(layer "B.SilkS")
			(hide yes)
			(effects
				(font
					(size 1.27 1.27)
				)
				(justify mirror)
			)
		)
		(property "Value" ""
			(at 0 0 0)
			(layer "B.Fab")
			(effects
				(font
					(size 1.27 1.27)
				)
				(justify mirror)
			)
		)
		(duplicate_pad_numbers_are_jumpers no)
		(fp_line
			(start -0.7874 -0.4064)
			(end -0.7874 0.4064)
			(stroke
				(width 0.1524)
				(type default)
			)
			(layer "B.SilkS")
		)
		(fp_line
			(start -0.7874 0.4064)
			(end 0.7874 0.4064)
			(stroke
				(width 0.1524)
				(type default)
			)
			(layer "B.SilkS")
		)
		(fp_line
			(start 0.7874 -0.4064)
			(end -0.7874 -0.4064)
			(stroke
				(width 0.1524)
				(type default)
			)
			(layer "B.SilkS")
		)
		(fp_line
			(start 0.7874 0.4064)
			(end 0.7874 -0.4064)
			(stroke
				(width 0.1524)
				(type default)
			)
			(layer "B.SilkS")
		)
		(fp_line
			(start -0.67945 -0.3048)
			(end -0.67945 0.3048)
			(stroke
				(width 0.1)
				(type default)
			)
			(layer "B.Fab")
		)
		(fp_line
			(start -0.67945 0.3048)
			(end -0.120396 0.3048)
			(stroke
				(width 0.1)
				(type default)
			)
			(layer "B.Fab")
		)
		(fp_line
			(start -0.12065 -0.3048)
			(end -0.67945 -0.3048)
			(stroke
				(width 0.1)
				(type default)
			)
			(layer "B.Fab")
		)
		(fp_line
			(start -0.12065 -0.2794)
			(end -0.12065 -0.3048)
			(stroke
				(width 0.1)
				(type default)
			)
			(layer "B.Fab")
		)
		(fp_line
			(start -0.120396 0.2794)
			(end 0.12065 0.2794)
			(stroke
				(width 0.1)
				(type default)
			)
			(layer "B.Fab")
		)
		(fp_line
			(start -0.120396 0.3048)
			(end -0.120396 0.2794)
			(stroke
				(width 0.1)
				(type default)
			)
			(layer "B.Fab")
		)
		(fp_line
			(start 0.12065 -0.305054)
			(end 0.12065 -0.2794)
			(stroke
				(width 0.1)
				(type default)
			)
			(layer "B.Fab")
		)
		(fp_line
			(start 0.12065 -0.2794)
			(end -0.12065 -0.2794)
			(stroke
				(width 0.1)
				(type default)
			)
			(layer "B.Fab")
		)
		(fp_line
			(start 0.12065 0.2794)
			(end 0.12065 0.3048)
			(stroke
				(width 0.1)
				(type default)
			)
			(layer "B.Fab")
		)
		(fp_line
			(start 0.12065 0.3048)
			(end 0.67945 0.3048)
			(stroke
				(width 0.1)
				(type default)
			)
			(layer "B.Fab")
		)
		(fp_line
			(start 0.67945 -0.305054)
			(end 0.12065 -0.305054)
			(stroke
				(width 0.1)
				(type default)
			)
			(layer "B.Fab")
		)
		(fp_line
			(start 0.67945 0.3048)
			(end 0.67945 -0.305054)
			(stroke
				(width 0.1)
				(type default)
			)
			(layer "B.Fab")
		)
		(pad "1" smd circle
			(at 0.40005 0 180)
			(size 0 0)
			(layers "B.Cu" "B.Mask" "B.Paste")
			(net "P52V_HS2_ISET")
		)
		(pad "2" smd circle
			(at -0.40005 0 180)
			(size 0 0)
			(layers "B.Cu" "B.Mask" "B.Paste")
			(net "GND1_FIELD_SIGNAL")
		)
	)
	(footprint ""
		(layer "B.Cu")
		(at 270.0274 -62.357)
		(property "Reference" "PR6932"
			(at 0 0 0)
			(layer "B.SilkS")
			(hide yes)
			(effects
				(font
					(size 1.27 1.27)
				)
				(justify mirror)
			)
		)
		(property "Value" ""
			(at 0 0 0)
			(layer "B.Fab")
			(effects
				(font
					(size 1.27 1.27)
				)
				(justify mirror)
			)
		)
		(duplicate_pad_numbers_are_jumpers no)
		(fp_line
			(start -0.7874 -0.4064)
			(end -0.7874 0.4064)
			(stroke
				(width 0.1524)
				(type default)
			)
			(layer "B.SilkS")
		)
		(fp_line
			(start -0.7874 0.4064)
			(end 0.7874 0.4064)
			(stroke
				(width 0.1524)
				(type default)
			)
			(layer "B.SilkS")
		)
		(fp_line
			(start 0.7874 -0.4064)
			(end -0.7874 -0.4064)
			(stroke
				(width 0.1524)
				(type default)
			)
			(layer "B.SilkS")
		)
		(fp_line
			(start 0.7874 0.4064)
			(end 0.7874 -0.4064)
			(stroke
				(width 0.1524)
				(type default)
			)
			(layer "B.SilkS")
		)
		(fp_line
			(start -0.67945 -0.3048)
			(end -0.67945 0.3048)
			(stroke
				(width 0.1)
				(type default)
			)
			(layer "B.Fab")
		)
		(fp_line
			(start -0.67945 0.3048)
			(end -0.120396 0.3048)
			(stroke
				(width 0.1)
				(type default)
			)
			(layer "B.Fab")
		)
		(fp_line
			(start -0.12065 -0.3048)
			(end -0.67945 -0.3048)
			(stroke
				(width 0.1)
				(type default)
			)
			(layer "B.Fab")
		)
		(fp_line
			(start -0.12065 -0.2794)
			(end -0.12065 -0.3048)
			(stroke
				(width 0.1)
				(type default)
			)
			(layer "B.Fab")
		)
		(fp_line
			(start -0.120396 0.2794)
			(end 0.12065 0.2794)
			(stroke
				(width 0.1)
				(type default)
			)
			(layer "B.Fab")
		)
		(fp_line
			(start -0.120396 0.3048)
			(end -0.120396 0.2794)
			(stroke
				(width 0.1)
				(type default)
			)
			(layer "B.Fab")
		)
		(fp_line
			(start 0.12065 -0.305054)
			(end 0.12065 -0.2794)
			(stroke
				(width 0.1)
				(type default)
			)
			(layer "B.Fab")
		)
		(fp_line
			(start 0.12065 -0.2794)
			(end -0.12065 -0.2794)
			(stroke
				(width 0.1)
				(type default)
			)
			(layer "B.Fab")
		)
		(fp_line
			(start 0.12065 0.2794)
			(end 0.12065 0.3048)
			(stroke
				(width 0.1)
				(type default)
			)
			(layer "B.Fab")
		)
		(fp_line
			(start 0.12065 0.3048)
			(end 0.67945 0.3048)
			(stroke
				(width 0.1)
				(type default)
			)
			(layer "B.Fab")
		)
		(fp_line
			(start 0.67945 -0.305054)
			(end 0.12065 -0.305054)
			(stroke
				(width 0.1)
				(type default)
			)
			(layer "B.Fab")
		)
		(fp_line
			(start 0.67945 0.3048)
			(end 0.67945 -0.305054)
			(stroke
				(width 0.1)
				(type default)
			)
			(layer "B.Fab")
		)
		(pad "1" smd circle
			(at 0.40005 0 180)
			(size 0 0)
			(layers "B.Cu" "B.Mask" "B.Paste")
			(net "P52V_HS1_PWRGIN")
		)
		(pad "2" smd circle
			(at -0.40005 0 180)
			(size 0 0)
			(layers "B.Cu" "B.Mask" "B.Paste")
			(net "GND_FIELD_SIGNAL")
		)
	)
	(footprint ""
		(layer "B.Cu")
		(at 152.573736 -79.375 180)
		(property "Reference" "PC595"
			(at 0 0 0)
			(layer "B.SilkS")
			(hide yes)
			(effects
				(font
					(size 1.27 1.27)
				)
				(justify mirror)
			)
		)
		(property "Value" ""
			(at 0 0 0)
			(layer "B.Fab")
			(effects
				(font
					(size 1.27 1.27)
				)
				(justify mirror)
			)
		)
		(duplicate_pad_numbers_are_jumpers no)
		(fp_line
			(start 2.2098 0.9398)
			(end 2.2098 -0.9398)
			(stroke
				(width 0.1524)
				(type default)
			)
			(layer "B.SilkS")
		)
		(fp_line
			(start 2.2098 -0.9398)
			(end -2.2098 -0.9398)
			(stroke
				(width 0.1524)
				(type default)
			)
			(layer "B.SilkS")
		)
		(fp_line
			(start -2.2098 0.9398)
			(end 2.2098 0.9398)
			(stroke
				(width 0.1524)
				(type default)
			)
			(layer "B.SilkS")
		)
		(fp_line
			(start -2.2098 -0.9398)
			(end -2.2098 0.9398)
			(stroke
				(width 0.1524)
				(type default)
			)
			(layer "B.SilkS")
		)
		(fp_line
			(start 2.1082 0.8382)
			(end 2.1082 -0.8382)
			(stroke
				(width 0.1)
				(type default)
			)
			(layer "B.Fab")
		)
		(fp_line
			(start 2.1082 -0.8382)
			(end 1.6764 -0.8382)
			(stroke
				(width 0.1)
				(type default)
			)
			(layer "B.Fab")
		)
		(fp_line
			(start 1.6764 0.9398)
			(end 1.6764 0.889)
			(stroke
				(width 0.1)
				(type default)
			)
			(layer "B.Fab")
		)
		(fp_line
			(start 1.6764 0.889)
			(end 1.6764 0.8382)
			(stroke
				(width 0.1)
				(type default)
			)
			(layer "B.Fab")
		)
		(fp_line
			(start 1.6764 0.8382)
			(end 2.1082 0.8382)
			(stroke
				(width 0.1)
				(type default)
			)
			(layer "B.Fab")
		)
		(fp_line
			(start 1.6764 -0.8382)
			(end 1.6764 -0.889)
			(stroke
				(width 0.1)
				(type default)
			)
			(layer "B.Fab")
		)
		(fp_line
			(start 1.6764 -0.889)
			(end 1.6764 -0.9398)
			(stroke
				(width 0.1)
				(type default)
			)
			(layer "B.Fab")
		)
		(fp_line
			(start 1.6764 -0.9398)
			(end -1.6764 -0.9398)
			(stroke
				(width 0.1)
				(type default)
			)
			(layer "B.Fab")
		)
		(fp_line
			(start -1.6764 0.9398)
			(end 1.6764 0.9398)
			(stroke
				(width 0.1)
				(type default)
			)
			(layer "B.Fab")
		)
		(fp_line
			(start -1.6764 0.889)
			(end -1.6764 0.9398)
			(stroke
				(width 0.1)
				(type default)
			)
			(layer "B.Fab")
		)
		(fp_line
			(start -1.6764 0.8382)
			(end -1.6764 0.889)
			(stroke
				(width 0.1)
				(type default)
			)
			(layer "B.Fab")
		)
		(fp_line
			(start -1.6764 -0.8382)
			(end -2.1082 -0.8382)
			(stroke
				(width 0.1)
				(type default)
			)
			(layer "B.Fab")
		)
		(fp_line
			(start -1.6764 -0.889)
			(end -1.6764 -0.8382)
			(stroke
				(width 0.1)
				(type default)
			)
			(layer "B.Fab")
		)
		(fp_line
			(start -1.6764 -0.9398)
			(end -1.6764 -0.889)
			(stroke
				(width 0.1)
				(type default)
			)
			(layer "B.Fab")
		)
		(fp_line
			(start -2.1082 0.8382)
			(end -1.6764 0.8382)
			(stroke
				(width 0.1)
				(type default)
			)
			(layer "B.Fab")
		)
		(fp_line
			(start -2.1082 -0.8382)
			(end -2.1082 0.8382)
			(stroke
				(width 0.1)
				(type default)
			)
			(layer "B.Fab")
		)
		(pad "1" smd rect
			(at 1.4732 0 180)
			(size 1.1684 1.5748)
			(layers "B.Cu" "B.Mask" "B.Paste")
			(net "P52V_2")
		)
		(pad "2" smd rect
			(at -1.4732 0 180)
			(size 1.1684 1.5748)
			(layers "B.Cu" "B.Mask" "B.Paste")
			(net "GND1_FIELD_SIGNAL")
		)
	)
	(footprint ""
		(layer "B.Cu")
		(at 426.593 -37.973 180)
		(property "Reference" "R5939"
			(at 0 0 0)
			(layer "B.SilkS")
			(hide yes)
			(effects
				(font
					(size 1.27 1.27)
				)
				(justify mirror)
			)
		)
		(property "Value" ""
			(at 0 0 0)
			(layer "B.Fab")
			(effects
				(font
					(size 1.27 1.27)
				)
				(justify mirror)
			)
		)
		(duplicate_pad_numbers_are_jumpers no)
		(fp_line
			(start 0.7874 0.4064)
			(end 0.7874 -0.4064)
			(stroke
				(width 0.1524)
				(type default)
			)
			(layer "B.SilkS")
		)
		(fp_line
			(start 0.7874 -0.4064)
			(end -0.7874 -0.4064)
			(stroke
				(width 0.1524)
				(type default)
			)
			(layer "B.SilkS")
		)
		(fp_line
			(start -0.7874 0.4064)
			(end 0.7874 0.4064)
			(stroke
				(width 0.1524)
				(type default)
			)
			(layer "B.SilkS")
		)
		(fp_line
			(start -0.7874 -0.4064)
			(end -0.7874 0.4064)
			(stroke
				(width 0.1524)
				(type default)
			)
			(layer "B.SilkS")
		)
		(fp_line
			(start 0.67945 0.3048)
			(end 0.67945 -0.305054)
			(stroke
				(width 0.1)
				(type default)
			)
			(layer "B.Fab")
		)
		(fp_line
			(start 0.67945 -0.305054)
			(end 0.12065 -0.305054)
			(stroke
				(width 0.1)
				(type default)
			)
			(layer "B.Fab")
		)
		(fp_line
			(start 0.12065 0.3048)
			(end 0.67945 0.3048)
			(stroke
				(width 0.1)
				(type default)
			)
			(layer "B.Fab")
		)
		(fp_line
			(start 0.12065 0.2794)
			(end 0.12065 0.3048)
			(stroke
				(width 0.1)
				(type default)
			)
			(layer "B.Fab")
		)
		(fp_line
			(start 0.12065 -0.2794)
			(end -0.12065 -0.2794)
			(stroke
				(width 0.1)
				(type default)
			)
			(layer "B.Fab")
		)
		(fp_line
			(start 0.12065 -0.305054)
			(end 0.12065 -0.2794)
			(stroke
				(width 0.1)
				(type default)
			)
			(layer "B.Fab")
		)
		(fp_line
			(start -0.120396 0.3048)
			(end -0.120396 0.2794)
			(stroke
				(width 0.1)
				(type default)
			)
			(layer "B.Fab")
		)
		(fp_line
			(start -0.120396 0.2794)
			(end 0.12065 0.2794)
			(stroke
				(width 0.1)
				(type default)
			)
			(layer "B.Fab")
		)
		(fp_line
			(start -0.12065 -0.2794)
			(end -0.12065 -0.3048)
			(stroke
				(width 0.1)
				(type default)
			)
			(layer "B.Fab")
		)
		(fp_line
			(start -0.12065 -0.3048)
			(end -0.67945 -0.3048)
			(stroke
				(width 0.1)
				(type default)
			)
			(layer "B.Fab")
		)
		(fp_line
			(start -0.67945 0.3048)
			(end -0.120396 0.3048)
			(stroke
				(width 0.1)
				(type default)
			)
			(layer "B.Fab")
		)
		(fp_line
			(start -0.67945 -0.3048)
			(end -0.67945 0.3048)
			(stroke
				(width 0.1)
				(type default)
			)
			(layer "B.Fab")
		)
		(pad "1" smd circle
			(at 0.40005 0)
			(size 0 0)
			(layers "B.Cu" "B.Mask" "B.Paste")
			(net "PCA9555_2_A0")
		)
		(pad "2" smd circle
			(at -0.40005 0)
			(size 0 0)
			(layers "B.Cu" "B.Mask" "B.Paste")
			(net "GND")
		)
	)
	(footprint ""
		(layer "B.Cu")
		(at 162.860736 -74.549 180)
		(property "Reference" "PC603"
			(at 0 0 0)
			(layer "B.SilkS")
			(hide yes)
			(effects
				(font
					(size 1.27 1.27)
				)
				(justify mirror)
			)
		)
		(property "Value" ""
			(at 0 0 0)
			(layer "B.Fab")
			(effects
				(font
					(size 1.27 1.27)
				)
				(justify mirror)
			)
		)
		(duplicate_pad_numbers_are_jumpers no)
		(fp_line
			(start 0.7874 0.4064)
			(end 0.7874 -0.4064)
			(stroke
				(width 0.1524)
				(type default)
			)
			(layer "B.SilkS")
		)
		(fp_line
			(start 0.7874 -0.4064)
			(end -0.7874 -0.4064)
			(stroke
				(width 0.1524)
				(type default)
			)
			(layer "B.SilkS")
		)
		(fp_line
			(start -0.7874 0.4064)
			(end 0.7874 0.4064)
			(stroke
				(width 0.1524)
				(type default)
			)
			(layer "B.SilkS")
		)
		(fp_line
			(start -0.7874 -0.4064)
			(end -0.7874 0.4064)
			(stroke
				(width 0.1524)
				(type default)
			)
			(layer "B.SilkS")
		)
		(fp_line
			(start 0.67945 0.3048)
			(end 0.67945 -0.305054)
			(stroke
				(width 0.1)
				(type default)
			)
			(layer "B.Fab")
		)
		(fp_line
			(start 0.67945 -0.305054)
			(end 0.12065 -0.305054)
			(stroke
				(width 0.1)
				(type default)
			)
			(layer "B.Fab")
		)
		(fp_line
			(start 0.12065 0.3048)
			(end 0.67945 0.3048)
			(stroke
				(width 0.1)
				(type default)
			)
			(layer "B.Fab")
		)
		(fp_line
			(start 0.12065 0.2794)
			(end 0.12065 0.3048)
			(stroke
				(width 0.1)
				(type default)
			)
			(layer "B.Fab")
		)
		(fp_line
			(start 0.12065 -0.2794)
			(end -0.12065 -0.2794)
			(stroke
				(width 0.1)
				(type default)
			)
			(layer "B.Fab")
		)
		(fp_line
			(start 0.12065 -0.305054)
			(end 0.12065 -0.2794)
			(stroke
				(width 0.1)
				(type default)
			)
			(layer "B.Fab")
		)
		(fp_line
			(start -0.120396 0.3048)
			(end -0.120396 0.2794)
			(stroke
				(width 0.1)
				(type default)
			)
			(layer "B.Fab")
		)
		(fp_line
			(start -0.120396 0.2794)
			(end 0.12065 0.2794)
			(stroke
				(width 0.1)
				(type default)
			)
			(layer "B.Fab")
		)
		(fp_line
			(start -0.12065 -0.2794)
			(end -0.12065 -0.3048)
			(stroke
				(width 0.1)
				(type default)
			)
			(layer "B.Fab")
		)
		(fp_line
			(start -0.12065 -0.3048)
			(end -0.67945 -0.3048)
			(stroke
				(width 0.1)
				(type default)
			)
			(layer "B.Fab")
		)
		(fp_line
			(start -0.67945 0.3048)
			(end -0.120396 0.3048)
			(stroke
				(width 0.1)
				(type default)
			)
			(layer "B.Fab")
		)
		(fp_line
			(start -0.67945 -0.3048)
			(end -0.67945 0.3048)
			(stroke
				(width 0.1)
				(type default)
			)
			(layer "B.Fab")
		)
		(pad "1" smd circle
			(at 0.40005 0)
			(size 0 0)
			(layers "B.Cu" "B.Mask" "B.Paste")
			(net "P52V_HS2_TMR")
		)
		(pad "2" smd circle
			(at -0.40005 0)
			(size 0 0)
			(layers "B.Cu" "B.Mask" "B.Paste")
			(net "GND1_FIELD_SIGNAL")
		)
	)
	(footprint ""
		(layer "B.Cu")
		(at 272.3134 -59.817 -90)
		(property "Reference" "R148"
			(at 0 0 90)
			(layer "B.SilkS")
			(hide yes)
			(effects
				(font
					(size 1.27 1.27)
				)
				(justify mirror)
			)
		)
		(property "Value" ""
			(at 0 0 90)
			(layer "B.Fab")
			(effects
				(font
					(size 1.27 1.27)
				)
				(justify mirror)
			)
		)
		(duplicate_pad_numbers_are_jumpers no)
		(fp_line
			(start -1.651 0.8382)
			(end 1.651 0.8382)
			(stroke
				(width 0.1524)
				(type default)
			)
			(layer "B.SilkS")
		)
		(fp_line
			(start 1.651 0.8382)
			(end 1.651 -0.8382)
			(stroke
				(width 0.1524)
				(type default)
			)
			(layer "B.SilkS")
		)
		(fp_line
			(start -1.651 -0.8382)
			(end -1.651 0.8382)
			(stroke
				(width 0.1524)
				(type default)
			)
			(layer "B.SilkS")
		)
		(fp_line
			(start 1.651 -0.8382)
			(end -1.651 -0.8382)
			(stroke
				(width 0.1524)
				(type default)
			)
			(layer "B.SilkS")
		)
		(fp_line
			(start -1.560576 0.7366)
			(end -1.560576 -0.7366)
			(stroke
				(width 0.1)
				(type default)
			)
			(layer "B.Fab")
		)
		(fp_line
			(start -1.524 0.7366)
			(end -1.560576 0.7366)
			(stroke
				(width 0.1)
				(type default)
			)
			(layer "B.Fab")
		)
		(fp_line
			(start 1.524 0.7366)
			(end -1.524 0.7366)
			(stroke
				(width 0.1)
				(type default)
			)
			(layer "B.Fab")
		)
		(fp_line
			(start 1.559814 0.7366)
			(end 1.524 0.7366)
			(stroke
				(width 0.1)
				(type default)
			)
			(layer "B.Fab")
		)
		(fp_line
			(start -1.560576 -0.7366)
			(end -1.524 -0.7366)
			(stroke
				(width 0.1)
				(type default)
			)
			(layer "B.Fab")
		)
		(fp_line
			(start -1.524 -0.7366)
			(end 1.524 -0.7366)
			(stroke
				(width 0.1)
				(type default)
			)
			(layer "B.Fab")
		)
		(fp_line
			(start 1.524 -0.7366)
			(end 1.559814 -0.7366)
			(stroke
				(width 0.1)
				(type default)
			)
			(layer "B.Fab")
		)
		(fp_line
			(start 1.559814 -0.7366)
			(end 1.559814 0.7366)
			(stroke
				(width 0.1)
				(type default)
			)
			(layer "B.Fab")
		)
		(pad "1" smd rect
			(at 0.94996 0 270)
			(size 1.1176 1.3716)
			(layers "B.Cu" "B.Mask" "B.Paste")
			(net "P52V_HS1")
		)
		(pad "2" smd rect
			(at -0.94996 0 270)
			(size 1.1176 1.3716)
			(layers "B.Cu" "B.Mask" "B.Paste")
			(net "PWRGD_P52V_HS1_PG")
		)
	)
	(footprint ""
		(layer "B.Cu")
		(at 179.4764 -58.039 -90)
		(property "Reference" "PR7020"
			(at 0 0 90)
			(layer "B.SilkS")
			(hide yes)
			(effects
				(font
					(size 1.27 1.27)
				)
				(justify mirror)
			)
		)
		(property "Value" ""
			(at 0 0 90)
			(layer "B.Fab")
			(effects
				(font
					(size 1.27 1.27)
				)
				(justify mirror)
			)
		)
		(duplicate_pad_numbers_are_jumpers no)
		(fp_line
			(start -2.234946 0.9271)
			(end 2.234946 0.9271)
			(stroke
				(width 0.1524)
				(type default)
			)
			(layer "B.SilkS")
		)
		(fp_line
			(start 2.234946 0.9271)
			(end 2.234946 -0.9271)
			(stroke
				(width 0.1524)
				(type default)
			)
			(layer "B.SilkS")
		)
		(fp_line
			(start -2.234946 -0.9271)
			(end -2.234946 0.9271)
			(stroke
				(width 0.1524)
				(type default)
			)
			(layer "B.SilkS")
		)
		(fp_line
			(start 2.234946 -0.9271)
			(end -2.234946 -0.9271)
			(stroke
				(width 0.1524)
				(type default)
			)
			(layer "B.SilkS")
		)
		(fp_line
			(start -1.575054 0.824992)
			(end -1.575054 -0.824992)
			(stroke
				(width 0.1)
				(type default)
			)
			(layer "B.Fab")
		)
		(fp_line
			(start 1.575054 0.824992)
			(end -1.575054 0.824992)
			(stroke
				(width 0.1)
				(type default)
			)
			(layer "B.Fab")
		)
		(fp_line
			(start -1.575054 -0.824992)
			(end 1.575054 -0.824992)
			(stroke
				(width 0.1)
				(type default)
			)
			(layer "B.Fab")
		)
		(fp_line
			(start 1.575054 -0.824992)
			(end 1.575054 0.824992)
			(stroke
				(width 0.1)
				(type default)
			)
			(layer "B.Fab")
		)
		(pad "1" smd rect
			(at 1.599946 0 90)
			(size 1.016 1.6002)
			(layers "B.Cu" "B.Mask" "B.Paste")
			(net "P52V_2")
		)
		(pad "2" smd rect
			(at -1.599946 0 90)
			(size 1.016 1.6002)
			(layers "B.Cu" "B.Mask" "B.Paste")
			(net "P52V_HS2_VCC")
		)
	)
	(footprint ""
		(layer "B.Cu")
		(at 169.1894 -78.359 180)
		(property "Reference" "R5889"
			(at 0 0 0)
			(layer "B.SilkS")
			(hide yes)
			(effects
				(font
					(size 1.27 1.27)
				)
				(justify mirror)
			)
		)
		(property "Value" ""
			(at 0 0 0)
			(layer "B.Fab")
			(effects
				(font
					(size 1.27 1.27)
				)
				(justify mirror)
			)
		)
		(duplicate_pad_numbers_are_jumpers no)
		(fp_line
			(start 0.7874 0.4064)
			(end 0.7874 -0.4064)
			(stroke
				(width 0.1524)
				(type default)
			)
			(layer "B.SilkS")
		)
		(fp_line
			(start 0.7874 -0.4064)
			(end -0.7874 -0.4064)
			(stroke
				(width 0.1524)
				(type default)
			)
			(layer "B.SilkS")
		)
		(fp_line
			(start -0.7874 0.4064)
			(end 0.7874 0.4064)
			(stroke
				(width 0.1524)
				(type default)
			)
			(layer "B.SilkS")
		)
		(fp_line
			(start -0.7874 -0.4064)
			(end -0.7874 0.4064)
			(stroke
				(width 0.1524)
				(type default)
			)
			(layer "B.SilkS")
		)
		(fp_line
			(start 0.67945 0.3048)
			(end 0.67945 -0.305054)
			(stroke
				(width 0.1)
				(type default)
			)
			(layer "B.Fab")
		)
		(fp_line
			(start 0.67945 -0.305054)
			(end 0.12065 -0.305054)
			(stroke
				(width 0.1)
				(type default)
			)
			(layer "B.Fab")
		)
		(fp_line
			(start 0.12065 0.3048)
			(end 0.67945 0.3048)
			(stroke
				(width 0.1)
				(type default)
			)
			(layer "B.Fab")
		)
		(fp_line
			(start 0.12065 0.2794)
			(end 0.12065 0.3048)
			(stroke
				(width 0.1)
				(type default)
			)
			(layer "B.Fab")
		)
		(fp_line
			(start 0.12065 -0.2794)
			(end -0.12065 -0.2794)
			(stroke
				(width 0.1)
				(type default)
			)
			(layer "B.Fab")
		)
		(fp_line
			(start 0.12065 -0.305054)
			(end 0.12065 -0.2794)
			(stroke
				(width 0.1)
				(type default)
			)
			(layer "B.Fab")
		)
		(fp_line
			(start -0.120396 0.3048)
			(end -0.120396 0.2794)
			(stroke
				(width 0.1)
				(type default)
			)
			(layer "B.Fab")
		)
		(fp_line
			(start -0.120396 0.2794)
			(end 0.12065 0.2794)
			(stroke
				(width 0.1)
				(type default)
			)
			(layer "B.Fab")
		)
		(fp_line
			(start -0.12065 -0.2794)
			(end -0.12065 -0.3048)
			(stroke
				(width 0.1)
				(type default)
			)
			(layer "B.Fab")
		)
		(fp_line
			(start -0.12065 -0.3048)
			(end -0.67945 -0.3048)
			(stroke
				(width 0.1)
				(type default)
			)
			(layer "B.Fab")
		)
		(fp_line
			(start -0.67945 0.3048)
			(end -0.120396 0.3048)
			(stroke
				(width 0.1)
				(type default)
			)
			(layer "B.Fab")
		)
		(fp_line
			(start -0.67945 -0.3048)
			(end -0.67945 0.3048)
			(stroke
				(width 0.1)
				(type default)
			)
			(layer "B.Fab")
		)
		(pad "1" smd circle
			(at 0.40005 0)
			(size 0 0)
			(layers "B.Cu" "B.Mask" "B.Paste")
			(net "P3V3_AUX")
		)
		(pad "2" smd circle
			(at -0.40005 0)
			(size 0 0)
			(layers "B.Cu" "B.Mask" "B.Paste")
			(net "P52V_HS2_GPO1")
		)
	)
	(footprint ""
		(layer "B.Cu")
		(at 173.147736 -56.007 -90)
		(property "Reference" "PR7019"
			(at 0 0 90)
			(layer "B.SilkS")
			(hide yes)
			(effects
				(font
					(size 1.27 1.27)
				)
				(justify mirror)
			)
		)
		(property "Value" ""
			(at 0 0 90)
			(layer "B.Fab")
			(effects
				(font
					(size 1.27 1.27)
				)
				(justify mirror)
			)
		)
		(duplicate_pad_numbers_are_jumpers no)
		(fp_line
			(start -1.651 0.8382)
			(end 1.651 0.8382)
			(stroke
				(width 0.1524)
				(type default)
			)
			(layer "B.SilkS")
		)
		(fp_line
			(start 1.651 0.8382)
			(end 1.651 -0.8382)
			(stroke
				(width 0.1524)
				(type default)
			)
			(layer "B.SilkS")
		)
		(fp_line
			(start -1.651 -0.8382)
			(end -1.651 0.8382)
			(stroke
				(width 0.1524)
				(type default)
			)
			(layer "B.SilkS")
		)
		(fp_line
			(start 1.651 -0.8382)
			(end -1.651 -0.8382)
			(stroke
				(width 0.1524)
				(type default)
			)
			(layer "B.SilkS")
		)
		(fp_line
			(start -1.560576 0.7366)
			(end -1.560576 -0.7366)
			(stroke
				(width 0.1)
				(type default)
			)
			(layer "B.Fab")
		)
		(fp_line
			(start -1.524 0.7366)
			(end -1.560576 0.7366)
			(stroke
				(width 0.1)
				(type default)
			)
			(layer "B.Fab")
		)
		(fp_line
			(start 1.524 0.7366)
			(end -1.524 0.7366)
			(stroke
				(width 0.1)
				(type default)
			)
			(layer "B.Fab")
		)
		(fp_line
			(start 1.559814 0.7366)
			(end 1.524 0.7366)
			(stroke
				(width 0.1)
				(type default)
			)
			(layer "B.Fab")
		)
		(fp_line
			(start -1.560576 -0.7366)
			(end -1.524 -0.7366)
			(stroke
				(width 0.1)
				(type default)
			)
			(layer "B.Fab")
		)
		(fp_line
			(start -1.524 -0.7366)
			(end 1.524 -0.7366)
			(stroke
				(width 0.1)
				(type default)
			)
			(layer "B.Fab")
		)
		(fp_line
			(start 1.524 -0.7366)
			(end 1.559814 -0.7366)
			(stroke
				(width 0.1)
				(type default)
			)
			(layer "B.Fab")
		)
		(fp_line
			(start 1.559814 -0.7366)
			(end 1.559814 0.7366)
			(stroke
				(width 0.1)
				(type default)
			)
			(layer "B.Fab")
		)
		(pad "1" smd rect
			(at 0.94996 0 270)
			(size 1.1176 1.3716)
			(layers "B.Cu" "B.Mask" "B.Paste")
			(net "P52V_2")
		)
		(pad "2" smd rect
			(at -0.94996 0 270)
			(size 1.1176 1.3716)
			(layers "B.Cu" "B.Mask" "B.Paste")
			(net "P52V_HS2_UVH")
		)
	)
	(footprint ""
		(layer "B.Cu")
		(at 293.6494 -77.851)
		(property "Reference" "PR24"
			(at 0 0 0)
			(layer "B.SilkS")
			(hide yes)
			(effects
				(font
					(size 1.27 1.27)
				)
				(justify mirror)
			)
		)
		(property "Value" ""
			(at 0 0 0)
			(layer "B.Fab")
			(effects
				(font
					(size 1.27 1.27)
				)
				(justify mirror)
			)
		)
		(duplicate_pad_numbers_are_jumpers no)
		(fp_line
			(start -0.7874 -0.4064)
			(end -0.7874 0.4064)
			(stroke
				(width 0.1524)
				(type default)
			)
			(layer "B.SilkS")
		)
		(fp_line
			(start -0.7874 0.4064)
			(end 0.7874 0.4064)
			(stroke
				(width 0.1524)
				(type default)
			)
			(layer "B.SilkS")
		)
		(fp_line
			(start 0.7874 -0.4064)
			(end -0.7874 -0.4064)
			(stroke
				(width 0.1524)
				(type default)
			)
			(layer "B.SilkS")
		)
		(fp_line
			(start 0.7874 0.4064)
			(end 0.7874 -0.4064)
			(stroke
				(width 0.1524)
				(type default)
			)
			(layer "B.SilkS")
		)
		(fp_line
			(start -0.67945 -0.3048)
			(end -0.67945 0.3048)
			(stroke
				(width 0.1)
				(type default)
			)
			(layer "B.Fab")
		)
		(fp_line
			(start -0.67945 0.3048)
			(end -0.120396 0.3048)
			(stroke
				(width 0.1)
				(type default)
			)
			(layer "B.Fab")
		)
		(fp_line
			(start -0.12065 -0.3048)
			(end -0.67945 -0.3048)
			(stroke
				(width 0.1)
				(type default)
			)
			(layer "B.Fab")
		)
		(fp_line
			(start -0.12065 -0.2794)
			(end -0.12065 -0.3048)
			(stroke
				(width 0.1)
				(type default)
			)
			(layer "B.Fab")
		)
		(fp_line
			(start -0.120396 0.2794)
			(end 0.12065 0.2794)
			(stroke
				(width 0.1)
				(type default)
			)
			(layer "B.Fab")
		)
		(fp_line
			(start -0.120396 0.3048)
			(end -0.120396 0.2794)
			(stroke
				(width 0.1)
				(type default)
			)
			(layer "B.Fab")
		)
		(fp_line
			(start 0.12065 -0.305054)
			(end 0.12065 -0.2794)
			(stroke
				(width 0.1)
				(type default)
			)
			(layer "B.Fab")
		)
		(fp_line
			(start 0.12065 -0.2794)
			(end -0.12065 -0.2794)
			(stroke
				(width 0.1)
				(type default)
			)
			(layer "B.Fab")
		)
		(fp_line
			(start 0.12065 0.2794)
			(end 0.12065 0.3048)
			(stroke
				(width 0.1)
				(type default)
			)
			(layer "B.Fab")
		)
		(fp_line
			(start 0.12065 0.3048)
			(end 0.67945 0.3048)
			(stroke
				(width 0.1)
				(type default)
			)
			(layer "B.Fab")
		)
		(fp_line
			(start 0.67945 -0.305054)
			(end 0.12065 -0.305054)
			(stroke
				(width 0.1)
				(type default)
			)
			(layer "B.Fab")
		)
		(fp_line
			(start 0.67945 0.3048)
			(end 0.67945 -0.305054)
			(stroke
				(width 0.1)
				(type default)
			)
			(layer "B.Fab")
		)
		(pad "1" smd circle
			(at 0.40005 0 180)
			(size 0 0)
			(layers "B.Cu" "B.Mask" "B.Paste")
			(net "P52V_HS1_FB")
		)
		(pad "2" smd circle
			(at -0.40005 0 180)
			(size 0 0)
			(layers "B.Cu" "B.Mask" "B.Paste")
			(net "GND_FIELD_SIGNAL")
		)
	)
	(footprint ""
		(layer "B.Cu")
		(at 291.9984 -62.992 -90)
		(property "Reference" "R156"
			(at 0 0 90)
			(layer "B.SilkS")
			(hide yes)
			(effects
				(font
					(size 1.27 1.27)
				)
				(justify mirror)
			)
		)
		(property "Value" ""
			(at 0 0 90)
			(layer "B.Fab")
			(effects
				(font
					(size 1.27 1.27)
				)
				(justify mirror)
			)
		)
		(duplicate_pad_numbers_are_jumpers no)
		(fp_line
			(start -0.7874 0.4064)
			(end 0.7874 0.4064)
			(stroke
				(width 0.1524)
				(type default)
			)
			(layer "B.SilkS")
		)
		(fp_line
			(start 0.7874 0.4064)
			(end 0.7874 -0.4064)
			(stroke
				(width 0.1524)
				(type default)
			)
			(layer "B.SilkS")
		)
		(fp_line
			(start -0.7874 -0.4064)
			(end -0.7874 0.4064)
			(stroke
				(width 0.1524)
				(type default)
			)
			(layer "B.SilkS")
		)
		(fp_line
			(start 0.7874 -0.4064)
			(end -0.7874 -0.4064)
			(stroke
				(width 0.1524)
				(type default)
			)
			(layer "B.SilkS")
		)
		(fp_line
			(start -0.67945 0.3048)
			(end -0.120396 0.3048)
			(stroke
				(width 0.1)
				(type default)
			)
			(layer "B.Fab")
		)
		(fp_line
			(start -0.120396 0.3048)
			(end -0.120396 0.2794)
			(stroke
				(width 0.1)
				(type default)
			)
			(layer "B.Fab")
		)
		(fp_line
			(start 0.12065 0.3048)
			(end 0.67945 0.3048)
			(stroke
				(width 0.1)
				(type default)
			)
			(layer "B.Fab")
		)
		(fp_line
			(start 0.67945 0.3048)
			(end 0.67945 -0.305054)
			(stroke
				(width 0.1)
				(type default)
			)
			(layer "B.Fab")
		)
		(fp_line
			(start -0.120396 0.2794)
			(end 0.12065 0.2794)
			(stroke
				(width 0.1)
				(type default)
			)
			(layer "B.Fab")
		)
		(fp_line
			(start 0.12065 0.2794)
			(end 0.12065 0.3048)
			(stroke
				(width 0.1)
				(type default)
			)
			(layer "B.Fab")
		)
		(fp_line
			(start -0.12065 -0.2794)
			(end -0.12065 -0.3048)
			(stroke
				(width 0.1)
				(type default)
			)
			(layer "B.Fab")
		)
		(fp_line
			(start 0.12065 -0.2794)
			(end -0.12065 -0.2794)
			(stroke
				(width 0.1)
				(type default)
			)
			(layer "B.Fab")
		)
		(fp_line
			(start -0.67945 -0.3048)
			(end -0.67945 0.3048)
			(stroke
				(width 0.1)
				(type default)
			)
			(layer "B.Fab")
		)
		(fp_line
			(start -0.12065 -0.3048)
			(end -0.67945 -0.3048)
			(stroke
				(width 0.1)
				(type default)
			)
			(layer "B.Fab")
		)
		(fp_line
			(start 0.12065 -0.305054)
			(end 0.12065 -0.2794)
			(stroke
				(width 0.1)
				(type default)
			)
			(layer "B.Fab")
		)
		(fp_line
			(start 0.67945 -0.305054)
			(end 0.12065 -0.305054)
			(stroke
				(width 0.1)
				(type default)
			)
			(layer "B.Fab")
		)
		(pad "1" smd circle
			(at 0.40005 0 90)
			(size 0 0)
			(layers "B.Cu" "B.Mask" "B.Paste")
			(net "P52V_HS1_INTVCC")
		)
		(pad "2" smd circle
			(at -0.40005 0 90)
			(size 0 0)
			(layers "B.Cu" "B.Mask" "B.Paste")
			(net "P52V_HS1_ADR0")
		)
	)
	(footprint ""
		(layer "B.Cu")
		(at 260.6294 -52.959 180)
		(property "Reference" "R399"
			(at 0 0 0)
			(layer "B.SilkS")
			(hide yes)
			(effects
				(font
					(size 1.27 1.27)
				)
				(justify mirror)
			)
		)
		(property "Value" ""
			(at 0 0 0)
			(layer "B.Fab")
			(effects
				(font
					(size 1.27 1.27)
				)
				(justify mirror)
			)
		)
		(duplicate_pad_numbers_are_jumpers no)
		(fp_line
			(start 0.7874 0.4064)
			(end 0.7874 -0.4064)
			(stroke
				(width 0.1524)
				(type default)
			)
			(layer "B.SilkS")
		)
		(fp_line
			(start 0.7874 -0.4064)
			(end -0.7874 -0.4064)
			(stroke
				(width 0.1524)
				(type default)
			)
			(layer "B.SilkS")
		)
		(fp_line
			(start -0.7874 0.4064)
			(end 0.7874 0.4064)
			(stroke
				(width 0.1524)
				(type default)
			)
			(layer "B.SilkS")
		)
		(fp_line
			(start -0.7874 -0.4064)
			(end -0.7874 0.4064)
			(stroke
				(width 0.1524)
				(type default)
			)
			(layer "B.SilkS")
		)
		(fp_line
			(start 0.67945 0.3048)
			(end 0.67945 -0.305054)
			(stroke
				(width 0.1)
				(type default)
			)
			(layer "B.Fab")
		)
		(fp_line
			(start 0.67945 -0.305054)
			(end 0.12065 -0.305054)
			(stroke
				(width 0.1)
				(type default)
			)
			(layer "B.Fab")
		)
		(fp_line
			(start 0.12065 0.3048)
			(end 0.67945 0.3048)
			(stroke
				(width 0.1)
				(type default)
			)
			(layer "B.Fab")
		)
		(fp_line
			(start 0.12065 0.2794)
			(end 0.12065 0.3048)
			(stroke
				(width 0.1)
				(type default)
			)
			(layer "B.Fab")
		)
		(fp_line
			(start 0.12065 -0.2794)
			(end -0.12065 -0.2794)
			(stroke
				(width 0.1)
				(type default)
			)
			(layer "B.Fab")
		)
		(fp_line
			(start 0.12065 -0.305054)
			(end 0.12065 -0.2794)
			(stroke
				(width 0.1)
				(type default)
			)
			(layer "B.Fab")
		)
		(fp_line
			(start -0.120396 0.3048)
			(end -0.120396 0.2794)
			(stroke
				(width 0.1)
				(type default)
			)
			(layer "B.Fab")
		)
		(fp_line
			(start -0.120396 0.2794)
			(end 0.12065 0.2794)
			(stroke
				(width 0.1)
				(type default)
			)
			(layer "B.Fab")
		)
		(fp_line
			(start -0.12065 -0.2794)
			(end -0.12065 -0.3048)
			(stroke
				(width 0.1)
				(type default)
			)
			(layer "B.Fab")
		)
		(fp_line
			(start -0.12065 -0.3048)
			(end -0.67945 -0.3048)
			(stroke
				(width 0.1)
				(type default)
			)
			(layer "B.Fab")
		)
		(fp_line
			(start -0.67945 0.3048)
			(end -0.120396 0.3048)
			(stroke
				(width 0.1)
				(type default)
			)
			(layer "B.Fab")
		)
		(fp_line
			(start -0.67945 -0.3048)
			(end -0.67945 0.3048)
			(stroke
				(width 0.1)
				(type default)
			)
			(layer "B.Fab")
		)
		(pad "1" smd circle
			(at 0.40005 0)
			(size 0 0)
			(layers "B.Cu" "B.Mask" "B.Paste")
			(net "FM_HS1_EN_FUSE")
		)
		(pad "2" smd circle
			(at -0.40005 0)
			(size 0 0)
			(layers "B.Cu" "B.Mask" "B.Paste")
			(net "GND")
		)
	)
	(footprint ""
		(layer "B.Cu")
		(at 168.321736 -67.818)
		(property "Reference" "PR7028"
			(at 0 0 0)
			(layer "B.SilkS")
			(hide yes)
			(effects
				(font
					(size 1.27 1.27)
				)
				(justify mirror)
			)
		)
		(property "Value" ""
			(at 0 0 0)
			(layer "B.Fab")
			(effects
				(font
					(size 1.27 1.27)
				)
				(justify mirror)
			)
		)
		(duplicate_pad_numbers_are_jumpers no)
		(fp_line
			(start -0.7874 -0.4064)
			(end -0.7874 0.4064)
			(stroke
				(width 0.1524)
				(type default)
			)
			(layer "B.SilkS")
		)
		(fp_line
			(start -0.7874 0.4064)
			(end 0.7874 0.4064)
			(stroke
				(width 0.1524)
				(type default)
			)
			(layer "B.SilkS")
		)
		(fp_line
			(start 0.7874 -0.4064)
			(end -0.7874 -0.4064)
			(stroke
				(width 0.1524)
				(type default)
			)
			(layer "B.SilkS")
		)
		(fp_line
			(start 0.7874 0.4064)
			(end 0.7874 -0.4064)
			(stroke
				(width 0.1524)
				(type default)
			)
			(layer "B.SilkS")
		)
		(fp_line
			(start -0.67945 -0.3048)
			(end -0.67945 0.3048)
			(stroke
				(width 0.1)
				(type default)
			)
			(layer "B.Fab")
		)
		(fp_line
			(start -0.67945 0.3048)
			(end -0.120396 0.3048)
			(stroke
				(width 0.1)
				(type default)
			)
			(layer "B.Fab")
		)
		(fp_line
			(start -0.12065 -0.3048)
			(end -0.67945 -0.3048)
			(stroke
				(width 0.1)
				(type default)
			)
			(layer "B.Fab")
		)
		(fp_line
			(start -0.12065 -0.2794)
			(end -0.12065 -0.3048)
			(stroke
				(width 0.1)
				(type default)
			)
			(layer "B.Fab")
		)
		(fp_line
			(start -0.120396 0.2794)
			(end 0.12065 0.2794)
			(stroke
				(width 0.1)
				(type default)
			)
			(layer "B.Fab")
		)
		(fp_line
			(start -0.120396 0.3048)
			(end -0.120396 0.2794)
			(stroke
				(width 0.1)
				(type default)
			)
			(layer "B.Fab")
		)
		(fp_line
			(start 0.12065 -0.305054)
			(end 0.12065 -0.2794)
			(stroke
				(width 0.1)
				(type default)
			)
			(layer "B.Fab")
		)
		(fp_line
			(start 0.12065 -0.2794)
			(end -0.12065 -0.2794)
			(stroke
				(width 0.1)
				(type default)
			)
			(layer "B.Fab")
		)
		(fp_line
			(start 0.12065 0.2794)
			(end 0.12065 0.3048)
			(stroke
				(width 0.1)
				(type default)
			)
			(layer "B.Fab")
		)
		(fp_line
			(start 0.12065 0.3048)
			(end 0.67945 0.3048)
			(stroke
				(width 0.1)
				(type default)
			)
			(layer "B.Fab")
		)
		(fp_line
			(start 0.67945 -0.305054)
			(end 0.12065 -0.305054)
			(stroke
				(width 0.1)
				(type default)
			)
			(layer "B.Fab")
		)
		(fp_line
			(start 0.67945 0.3048)
			(end 0.67945 -0.305054)
			(stroke
				(width 0.1)
				(type default)
			)
			(layer "B.Fab")
		)
		(pad "1" smd circle
			(at 0.40005 0 180)
			(size 0 0)
			(layers "B.Cu" "B.Mask" "B.Paste")
			(net "P52V_HS2_ISTART")
		)
		(pad "2" smd circle
			(at -0.40005 0 180)
			(size 0 0)
			(layers "B.Cu" "B.Mask" "B.Paste")
			(net "GND1_FIELD_SIGNAL")
		)
	)
	(footprint ""
		(layer "B.Cu")
		(at 161.717736 -73.279)
		(property "Reference" "PR7013"
			(at 0 0 0)
			(layer "B.SilkS")
			(hide yes)
			(effects
				(font
					(size 1.27 1.27)
				)
				(justify mirror)
			)
		)
		(property "Value" ""
			(at 0 0 0)
			(layer "B.Fab")
			(effects
				(font
					(size 1.27 1.27)
				)
				(justify mirror)
			)
		)
		(duplicate_pad_numbers_are_jumpers no)
		(fp_line
			(start -0.7874 -0.4064)
			(end -0.7874 0.4064)
			(stroke
				(width 0.1524)
				(type default)
			)
			(layer "B.SilkS")
		)
		(fp_line
			(start -0.7874 0.4064)
			(end 0.7874 0.4064)
			(stroke
				(width 0.1524)
				(type default)
			)
			(layer "B.SilkS")
		)
		(fp_line
			(start 0.7874 -0.4064)
			(end -0.7874 -0.4064)
			(stroke
				(width 0.1524)
				(type default)
			)
			(layer "B.SilkS")
		)
		(fp_line
			(start 0.7874 0.4064)
			(end 0.7874 -0.4064)
			(stroke
				(width 0.1524)
				(type default)
			)
			(layer "B.SilkS")
		)
		(fp_line
			(start -0.67945 -0.3048)
			(end -0.67945 0.3048)
			(stroke
				(width 0.1)
				(type default)
			)
			(layer "B.Fab")
		)
		(fp_line
			(start -0.67945 0.3048)
			(end -0.120396 0.3048)
			(stroke
				(width 0.1)
				(type default)
			)
			(layer "B.Fab")
		)
		(fp_line
			(start -0.12065 -0.3048)
			(end -0.67945 -0.3048)
			(stroke
				(width 0.1)
				(type default)
			)
			(layer "B.Fab")
		)
		(fp_line
			(start -0.12065 -0.2794)
			(end -0.12065 -0.3048)
			(stroke
				(width 0.1)
				(type default)
			)
			(layer "B.Fab")
		)
		(fp_line
			(start -0.120396 0.2794)
			(end 0.12065 0.2794)
			(stroke
				(width 0.1)
				(type default)
			)
			(layer "B.Fab")
		)
		(fp_line
			(start -0.120396 0.3048)
			(end -0.120396 0.2794)
			(stroke
				(width 0.1)
				(type default)
			)
			(layer "B.Fab")
		)
		(fp_line
			(start 0.12065 -0.305054)
			(end 0.12065 -0.2794)
			(stroke
				(width 0.1)
				(type default)
			)
			(layer "B.Fab")
		)
		(fp_line
			(start 0.12065 -0.2794)
			(end -0.12065 -0.2794)
			(stroke
				(width 0.1)
				(type default)
			)
			(layer "B.Fab")
		)
		(fp_line
			(start 0.12065 0.2794)
			(end 0.12065 0.3048)
			(stroke
				(width 0.1)
				(type default)
			)
			(layer "B.Fab")
		)
		(fp_line
			(start 0.12065 0.3048)
			(end 0.67945 0.3048)
			(stroke
				(width 0.1)
				(type default)
			)
			(layer "B.Fab")
		)
		(fp_line
			(start 0.67945 -0.305054)
			(end 0.12065 -0.305054)
			(stroke
				(width 0.1)
				(type default)
			)
			(layer "B.Fab")
		)
		(fp_line
			(start 0.67945 0.3048)
			(end 0.67945 -0.305054)
			(stroke
				(width 0.1)
				(type default)
			)
			(layer "B.Fab")
		)
		(pad "1" smd circle
			(at 0.40005 0 180)
			(size 0 0)
			(layers "B.Cu" "B.Mask" "B.Paste")
			(net "GND1_FIELD_SIGNAL")
		)
		(pad "2" smd circle
			(at -0.40005 0 180)
			(size 0 0)
			(layers "B.Cu" "B.Mask" "B.Paste")
			(net "P52V_HS2_CLKIN")
		)
	)
	(footprint ""
		(layer "B.Cu")
		(at 441.325 -45.974 180)
		(property "Reference" "R5940"
			(at 0 0 0)
			(layer "B.SilkS")
			(hide yes)
			(effects
				(font
					(size 1.27 1.27)
				)
				(justify mirror)
			)
		)
		(property "Value" ""
			(at 0 0 0)
			(layer "B.Fab")
			(effects
				(font
					(size 1.27 1.27)
				)
				(justify mirror)
			)
		)
		(duplicate_pad_numbers_are_jumpers no)
		(fp_line
			(start 0.7874 0.4064)
			(end 0.7874 -0.4064)
			(stroke
				(width 0.1524)
				(type default)
			)
			(layer "B.SilkS")
		)
		(fp_line
			(start 0.7874 -0.4064)
			(end -0.7874 -0.4064)
			(stroke
				(width 0.1524)
				(type default)
			)
			(layer "B.SilkS")
		)
		(fp_line
			(start -0.7874 0.4064)
			(end 0.7874 0.4064)
			(stroke
				(width 0.1524)
				(type default)
			)
			(layer "B.SilkS")
		)
		(fp_line
			(start -0.7874 -0.4064)
			(end -0.7874 0.4064)
			(stroke
				(width 0.1524)
				(type default)
			)
			(layer "B.SilkS")
		)
		(fp_line
			(start 0.67945 0.3048)
			(end 0.67945 -0.305054)
			(stroke
				(width 0.1)
				(type default)
			)
			(layer "B.Fab")
		)
		(fp_line
			(start 0.67945 -0.305054)
			(end 0.12065 -0.305054)
			(stroke
				(width 0.1)
				(type default)
			)
			(layer "B.Fab")
		)
		(fp_line
			(start 0.12065 0.3048)
			(end 0.67945 0.3048)
			(stroke
				(width 0.1)
				(type default)
			)
			(layer "B.Fab")
		)
		(fp_line
			(start 0.12065 0.2794)
			(end 0.12065 0.3048)
			(stroke
				(width 0.1)
				(type default)
			)
			(layer "B.Fab")
		)
		(fp_line
			(start 0.12065 -0.2794)
			(end -0.12065 -0.2794)
			(stroke
				(width 0.1)
				(type default)
			)
			(layer "B.Fab")
		)
		(fp_line
			(start 0.12065 -0.305054)
			(end 0.12065 -0.2794)
			(stroke
				(width 0.1)
				(type default)
			)
			(layer "B.Fab")
		)
		(fp_line
			(start -0.120396 0.3048)
			(end -0.120396 0.2794)
			(stroke
				(width 0.1)
				(type default)
			)
			(layer "B.Fab")
		)
		(fp_line
			(start -0.120396 0.2794)
			(end 0.12065 0.2794)
			(stroke
				(width 0.1)
				(type default)
			)
			(layer "B.Fab")
		)
		(fp_line
			(start -0.12065 -0.2794)
			(end -0.12065 -0.3048)
			(stroke
				(width 0.1)
				(type default)
			)
			(layer "B.Fab")
		)
		(fp_line
			(start -0.12065 -0.3048)
			(end -0.67945 -0.3048)
			(stroke
				(width 0.1)
				(type default)
			)
			(layer "B.Fab")
		)
		(fp_line
			(start -0.67945 0.3048)
			(end -0.120396 0.3048)
			(stroke
				(width 0.1)
				(type default)
			)
			(layer "B.Fab")
		)
		(fp_line
			(start -0.67945 -0.3048)
			(end -0.67945 0.3048)
			(stroke
				(width 0.1)
				(type default)
			)
			(layer "B.Fab")
		)
		(pad "1" smd circle
			(at 0.40005 0)
			(size 0 0)
			(layers "B.Cu" "B.Mask" "B.Paste")
			(net "FAN_PWR_EN_BUF")
		)
		(pad "2" smd circle
			(at -0.40005 0)
			(size 0 0)
			(layers "B.Cu" "B.Mask" "B.Paste")
			(net "FAN_PWR_EN_BUF_R")
		)
	)
	(footprint ""
		(layer "B.Cu")
		(at 170.734736 -63.754 90)
		(property "Reference" "PC612"
			(at 0 0 90)
			(layer "B.SilkS")
			(hide yes)
			(effects
				(font
					(size 1.27 1.27)
				)
				(justify mirror)
			)
		)
		(property "Value" ""
			(at 0 0 90)
			(layer "B.Fab")
			(effects
				(font
					(size 1.27 1.27)
				)
				(justify mirror)
			)
		)
		(duplicate_pad_numbers_are_jumpers no)
		(fp_line
			(start 0.7874 -0.4064)
			(end -0.7874 -0.4064)
			(stroke
				(width 0.1524)
				(type default)
			)
			(layer "B.SilkS")
		)
		(fp_line
			(start -0.7874 -0.4064)
			(end -0.7874 0.4064)
			(stroke
				(width 0.1524)
				(type default)
			)
			(layer "B.SilkS")
		)
		(fp_line
			(start 0.7874 0.4064)
			(end 0.7874 -0.4064)
			(stroke
				(width 0.1524)
				(type default)
			)
			(layer "B.SilkS")
		)
		(fp_line
			(start -0.7874 0.4064)
			(end 0.7874 0.4064)
			(stroke
				(width 0.1524)
				(type default)
			)
			(layer "B.SilkS")
		)
		(fp_line
			(start 0.67945 -0.305054)
			(end 0.12065 -0.305054)
			(stroke
				(width 0.1)
				(type default)
			)
			(layer "B.Fab")
		)
		(fp_line
			(start 0.12065 -0.305054)
			(end 0.12065 -0.2794)
			(stroke
				(width 0.1)
				(type default)
			)
			(layer "B.Fab")
		)
		(fp_line
			(start -0.12065 -0.3048)
			(end -0.67945 -0.3048)
			(stroke
				(width 0.1)
				(type default)
			)
			(layer "B.Fab")
		)
		(fp_line
			(start -0.67945 -0.3048)
			(end -0.67945 0.3048)
			(stroke
				(width 0.1)
				(type default)
			)
			(layer "B.Fab")
		)
		(fp_line
			(start 0.12065 -0.2794)
			(end -0.12065 -0.2794)
			(stroke
				(width 0.1)
				(type default)
			)
			(layer "B.Fab")
		)
		(fp_line
			(start -0.12065 -0.2794)
			(end -0.12065 -0.3048)
			(stroke
				(width 0.1)
				(type default)
			)
			(layer "B.Fab")
		)
		(fp_line
			(start 0.12065 0.2794)
			(end 0.12065 0.3048)
			(stroke
				(width 0.1)
				(type default)
			)
			(layer "B.Fab")
		)
		(fp_line
			(start -0.120396 0.2794)
			(end 0.12065 0.2794)
			(stroke
				(width 0.1)
				(type default)
			)
			(layer "B.Fab")
		)
		(fp_line
			(start 0.67945 0.3048)
			(end 0.67945 -0.305054)
			(stroke
				(width 0.1)
				(type default)
			)
			(layer "B.Fab")
		)
		(fp_line
			(start 0.12065 0.3048)
			(end 0.67945 0.3048)
			(stroke
				(width 0.1)
				(type default)
			)
			(layer "B.Fab")
		)
		(fp_line
			(start -0.120396 0.3048)
			(end -0.120396 0.2794)
			(stroke
				(width 0.1)
				(type default)
			)
			(layer "B.Fab")
		)
		(fp_line
			(start -0.67945 0.3048)
			(end -0.120396 0.3048)
			(stroke
				(width 0.1)
				(type default)
			)
			(layer "B.Fab")
		)
		(pad "1" smd circle
			(at 0.40005 0 270)
			(size 0 0)
			(layers "B.Cu" "B.Mask" "B.Paste")
			(net "P52V_HS2_RND")
		)
		(pad "2" smd circle
			(at -0.40005 0 270)
			(size 0 0)
			(layers "B.Cu" "B.Mask" "B.Paste")
			(net "GND1_FIELD_SIGNAL")
		)
	)
	(footprint ""
		(layer "B.Cu")
		(at 252.476 -40.259 90)
		(property "Reference" "FS5"
			(at 3.937 2.64033 270)
			(unlocked yes)
			(layer "B.SilkS")
			(effects
				(font
					(size 0.7874 0.5842)
					(thickness 0.1524)
				)
				(justify left mirror)
			)
		)
		(property "Value" ""
			(at 0 0 90)
			(layer "B.Fab")
			(effects
				(font
					(size 1.27 1.27)
				)
				(justify mirror)
			)
		)
		(duplicate_pad_numbers_are_jumpers no)
		(fp_line
			(start 6.427724 -1.8415)
			(end 6.427724 1.8415)
			(stroke
				(width 0.1524)
				(type default)
			)
			(layer "B.SilkS")
		)
		(fp_line
			(start -6.427724 -1.8415)
			(end 6.427724 -1.8415)
			(stroke
				(width 0.1524)
				(type default)
			)
			(layer "B.SilkS")
		)
		(fp_line
			(start 6.427724 1.8415)
			(end -6.427724 1.8415)
			(stroke
				(width 0.1524)
				(type default)
			)
			(layer "B.SilkS")
		)
		(fp_line
			(start -6.427724 1.8415)
			(end -6.427724 -1.8415)
			(stroke
				(width 0.1524)
				(type default)
			)
			(layer "B.SilkS")
		)
		(fp_line
			(start 5.225034 -1.610106)
			(end -5.225034 -1.610106)
			(stroke
				(width 0.1)
				(type default)
			)
			(layer "B.Fab")
		)
		(fp_line
			(start -5.225034 -1.610106)
			(end -5.225034 1.610106)
			(stroke
				(width 0.1)
				(type default)
			)
			(layer "B.Fab")
		)
		(fp_line
			(start 5.225034 1.610106)
			(end 5.225034 -1.610106)
			(stroke
				(width 0.1)
				(type default)
			)
			(layer "B.Fab")
		)
		(fp_line
			(start -5.225034 1.610106)
			(end 5.225034 1.610106)
			(stroke
				(width 0.1)
				(type default)
			)
			(layer "B.Fab")
		)
		(pad "1" smd rect
			(at 4.675124 0 270)
			(size 3.2512 3.429)
			(layers "B.Cu" "B.Mask" "B.Paste")
			(net "P52V_1_FUSE_1")
		)
		(pad "2" smd rect
			(at -4.675124 0 270)
			(size 3.2512 3.429)
			(layers "B.Cu" "B.Mask" "B.Paste")
			(net "P52V_1")
		)
	)
	(footprint ""
		(layer "B.Cu")
		(at 278.4094 -62.865 180)
		(property "Reference" "R151"
			(at 0 0 0)
			(layer "B.SilkS")
			(hide yes)
			(effects
				(font
					(size 1.27 1.27)
				)
				(justify mirror)
			)
		)
		(property "Value" ""
			(at 0 0 0)
			(layer "B.Fab")
			(effects
				(font
					(size 1.27 1.27)
				)
				(justify mirror)
			)
		)
		(duplicate_pad_numbers_are_jumpers no)
		(fp_line
			(start 0.7874 0.4064)
			(end 0.7874 -0.4064)
			(stroke
				(width 0.1524)
				(type default)
			)
			(layer "B.SilkS")
		)
		(fp_line
			(start 0.7874 -0.4064)
			(end -0.7874 -0.4064)
			(stroke
				(width 0.1524)
				(type default)
			)
			(layer "B.SilkS")
		)
		(fp_line
			(start -0.7874 0.4064)
			(end 0.7874 0.4064)
			(stroke
				(width 0.1524)
				(type default)
			)
			(layer "B.SilkS")
		)
		(fp_line
			(start -0.7874 -0.4064)
			(end -0.7874 0.4064)
			(stroke
				(width 0.1524)
				(type default)
			)
			(layer "B.SilkS")
		)
		(fp_line
			(start 0.67945 0.3048)
			(end 0.67945 -0.305054)
			(stroke
				(width 0.1)
				(type default)
			)
			(layer "B.Fab")
		)
		(fp_line
			(start 0.67945 -0.305054)
			(end 0.12065 -0.305054)
			(stroke
				(width 0.1)
				(type default)
			)
			(layer "B.Fab")
		)
		(fp_line
			(start 0.12065 0.3048)
			(end 0.67945 0.3048)
			(stroke
				(width 0.1)
				(type default)
			)
			(layer "B.Fab")
		)
		(fp_line
			(start 0.12065 0.2794)
			(end 0.12065 0.3048)
			(stroke
				(width 0.1)
				(type default)
			)
			(layer "B.Fab")
		)
		(fp_line
			(start 0.12065 -0.2794)
			(end -0.12065 -0.2794)
			(stroke
				(width 0.1)
				(type default)
			)
			(layer "B.Fab")
		)
		(fp_line
			(start 0.12065 -0.305054)
			(end 0.12065 -0.2794)
			(stroke
				(width 0.1)
				(type default)
			)
			(layer "B.Fab")
		)
		(fp_line
			(start -0.120396 0.3048)
			(end -0.120396 0.2794)
			(stroke
				(width 0.1)
				(type default)
			)
			(layer "B.Fab")
		)
		(fp_line
			(start -0.120396 0.2794)
			(end 0.12065 0.2794)
			(stroke
				(width 0.1)
				(type default)
			)
			(layer "B.Fab")
		)
		(fp_line
			(start -0.12065 -0.2794)
			(end -0.12065 -0.3048)
			(stroke
				(width 0.1)
				(type default)
			)
			(layer "B.Fab")
		)
		(fp_line
			(start -0.12065 -0.3048)
			(end -0.67945 -0.3048)
			(stroke
				(width 0.1)
				(type default)
			)
			(layer "B.Fab")
		)
		(fp_line
			(start -0.67945 0.3048)
			(end -0.120396 0.3048)
			(stroke
				(width 0.1)
				(type default)
			)
			(layer "B.Fab")
		)
		(fp_line
			(start -0.67945 -0.3048)
			(end -0.67945 0.3048)
			(stroke
				(width 0.1)
				(type default)
			)
			(layer "B.Fab")
		)
		(pad "1" smd circle
			(at 0.40005 0)
			(size 0 0)
			(layers "B.Cu" "B.Mask" "B.Paste")
			(net "P52V_HS1_GPO2")
		)
		(pad "2" smd circle
			(at -0.40005 0)
			(size 0 0)
			(layers "B.Cu" "B.Mask" "B.Paste")
			(net "P52V_HS1_FLT")
		)
	)
	(footprint ""
		(layer "B.Cu")
		(at 270.0274 -59.817 -90)
		(property "Reference" "PR17"
			(at 0 0 90)
			(layer "B.SilkS")
			(hide yes)
			(effects
				(font
					(size 1.27 1.27)
				)
				(justify mirror)
			)
		)
		(property "Value" ""
			(at 0 0 90)
			(layer "B.Fab")
			(effects
				(font
					(size 1.27 1.27)
				)
				(justify mirror)
			)
		)
		(duplicate_pad_numbers_are_jumpers no)
		(fp_line
			(start -1.651 0.8382)
			(end 1.651 0.8382)
			(stroke
				(width 0.1524)
				(type default)
			)
			(layer "B.SilkS")
		)
		(fp_line
			(start 1.651 0.8382)
			(end 1.651 -0.8382)
			(stroke
				(width 0.1524)
				(type default)
			)
			(layer "B.SilkS")
		)
		(fp_line
			(start -1.651 -0.8382)
			(end -1.651 0.8382)
			(stroke
				(width 0.1524)
				(type default)
			)
			(layer "B.SilkS")
		)
		(fp_line
			(start 1.651 -0.8382)
			(end -1.651 -0.8382)
			(stroke
				(width 0.1524)
				(type default)
			)
			(layer "B.SilkS")
		)
		(fp_line
			(start -1.560576 0.7366)
			(end -1.560576 -0.7366)
			(stroke
				(width 0.1)
				(type default)
			)
			(layer "B.Fab")
		)
		(fp_line
			(start -1.524 0.7366)
			(end -1.560576 0.7366)
			(stroke
				(width 0.1)
				(type default)
			)
			(layer "B.Fab")
		)
		(fp_line
			(start 1.524 0.7366)
			(end -1.524 0.7366)
			(stroke
				(width 0.1)
				(type default)
			)
			(layer "B.Fab")
		)
		(fp_line
			(start 1.559814 0.7366)
			(end 1.524 0.7366)
			(stroke
				(width 0.1)
				(type default)
			)
			(layer "B.Fab")
		)
		(fp_line
			(start -1.560576 -0.7366)
			(end -1.524 -0.7366)
			(stroke
				(width 0.1)
				(type default)
			)
			(layer "B.Fab")
		)
		(fp_line
			(start -1.524 -0.7366)
			(end 1.524 -0.7366)
			(stroke
				(width 0.1)
				(type default)
			)
			(layer "B.Fab")
		)
		(fp_line
			(start 1.524 -0.7366)
			(end 1.559814 -0.7366)
			(stroke
				(width 0.1)
				(type default)
			)
			(layer "B.Fab")
		)
		(fp_line
			(start 1.559814 -0.7366)
			(end 1.559814 0.7366)
			(stroke
				(width 0.1)
				(type default)
			)
			(layer "B.Fab")
		)
		(pad "1" smd rect
			(at 0.94996 0 270)
			(size 1.1176 1.3716)
			(layers "B.Cu" "B.Mask" "B.Paste")
			(net "P52V_HS1")
		)
		(pad "2" smd rect
			(at -0.94996 0 270)
			(size 1.1176 1.3716)
			(layers "B.Cu" "B.Mask" "B.Paste")
			(net "P52V_HS1_PWRGIN")
		)
	)
	(footprint ""
		(layer "B.Cu")
		(at 154.097736 -70.104 180)
		(property "Reference" "PU8"
			(at -3.636264 -4.59867 0)
			(unlocked yes)
			(layer "B.SilkS")
			(effects
				(font
					(size 0.7874 0.5842)
					(thickness 0.1524)
				)
				(justify left mirror)
			)
		)
		(property "Value" ""
			(at 0 0 0)
			(layer "B.Fab")
			(effects
				(font
					(size 1.27 1.27)
				)
				(justify mirror)
			)
		)
		(duplicate_pad_numbers_are_jumpers no)
		(fp_line
			(start 3.549904 3.549904)
			(end 3.549904 3.0226)
			(stroke
				(width 0.1524)
				(type default)
			)
			(layer "B.SilkS")
		)
		(fp_line
			(start 3.549904 -0.0254)
			(end 3.549904 -1.4732)
			(stroke
				(width 0.1524)
				(type default)
			)
			(layer "B.SilkS")
		)
		(fp_line
			(start 3.549904 -3.0226)
			(end 3.549904 -3.549904)
			(stroke
				(width 0.1524)
				(type default)
			)
			(layer "B.SilkS")
		)
		(fp_line
			(start 3.549904 -3.549904)
			(end 3.0226 -3.549904)
			(stroke
				(width 0.1524)
				(type default)
			)
			(layer "B.SilkS")
		)
		(fp_line
			(start 3.0226 3.549904)
			(end 3.549904 3.549904)
			(stroke
				(width 0.1524)
				(type default)
			)
			(layer "B.SilkS")
		)
		(fp_line
			(start 2.4638 -3.549904)
			(end 1.03124 -3.549904)
			(stroke
				(width 0.1524)
				(type default)
			)
			(layer "B.SilkS")
		)
		(fp_line
			(start 1.03124 3.549904)
			(end 2.4638 3.549904)
			(stroke
				(width 0.1524)
				(type default)
			)
			(layer "B.SilkS")
		)
		(fp_line
			(start -3.0226 -3.549904)
			(end -3.549904 -3.549904)
			(stroke
				(width 0.1524)
				(type default)
			)
			(layer "B.SilkS")
		)
		(fp_line
			(start -3.549904 3.549904)
			(end -3.0226 3.549904)
			(stroke
				(width 0.1524)
				(type default)
			)
			(layer "B.SilkS")
		)
		(fp_line
			(start -3.549904 3.0226)
			(end -3.549904 3.549904)
			(stroke
				(width 0.1524)
				(type default)
			)
			(layer "B.SilkS")
		)
		(fp_line
			(start -3.549904 -3.549904)
			(end -3.549904 -3.0226)
			(stroke
				(width 0.1524)
				(type default)
			)
			(layer "B.SilkS")
		)
		(fp_poly
			(pts
				(xy 4.134104 -3.041904) (xy 3.549904 -3.041904) (xy 3.549904 -3.626104) (xy 4.134104 -3.626104)
			)
			(stroke
				(width 0)
				(type default)
			)
			(fill yes)
			(layer "B.SilkS")
		)
		(fp_line
			(start 3.549904 3.549904)
			(end 3.549904 -3.549904)
			(stroke
				(width 0.1)
				(type default)
			)
			(layer "B.Fab")
		)
		(fp_line
			(start 3.549904 -3.549904)
			(end -3.549904 -3.549904)
			(stroke
				(width 0.1)
				(type default)
			)
			(layer "B.Fab")
		)
		(fp_line
			(start -3.549904 3.549904)
			(end 3.549904 3.549904)
			(stroke
				(width 0.1)
				(type default)
			)
			(layer "B.Fab")
		)
		(fp_line
			(start -3.549904 -3.549904)
			(end -3.549904 3.549904)
			(stroke
				(width 0.1)
				(type default)
			)
			(layer "B.Fab")
		)
		(fp_poly
			(pts
				(xy 4.134104 -3.041904) (xy 3.549904 -3.041904) (xy 3.549904 -3.626104) (xy 4.134104 -3.626104)
			)
			(stroke
				(width 0)
				(type default)
			)
			(fill yes)
			(layer "B.Fab")
		)
		(pad "1" smd rect
			(at 3.425444 -2.750058 90)
			(size 0.2794 0.7112)
			(layers "B.Cu" "B.Mask" "B.Paste")
			(net "P52V_HS2")
		)
		(pad "2" smd rect
			(at 3.400044 -2.249932 90)
			(size 0.2794 0.762)
			(layers "B.Cu" "B.Mask" "B.Paste")
			(net "P52V_HS2_4287_GATE2_R")
		)
		(pad "3" smd rect
			(at 3.400044 -1.75006 90)
			(size 0.2794 0.762)
			(layers "B.Cu" "B.Mask" "B.Paste")
			(net "P52V_HS2_4287_GATE_R")
		)
		(pad "4" smd rect
			(at 3.400044 0.249936 90)
			(size 0.2794 0.762)
			(layers "B.Cu" "B.Mask" "B.Paste")
			(net "P52V_HS2_4287_ADC_N")
		)
		(pad "5" smd rect
			(at 3.400044 0.750062 90)
			(size 0.2794 0.762)
			(layers "B.Cu" "B.Mask" "B.Paste")
			(net "P52V_HS2_4287_S1N")
		)
		(pad "6" smd rect
			(at 3.400044 1.249934 90)
			(size 0.2794 0.762)
			(layers "B.Cu" "B.Mask" "B.Paste")
			(net "P52V_HS2_4287_S1P")
		)
		(pad "7" smd rect
			(at 3.400044 1.75006 90)
			(size 0.2794 0.762)
			(layers "B.Cu" "B.Mask" "B.Paste")
			(net "P52V_HS2_4287_ADC_P")
		)
		(pad "8" smd rect
			(at 3.400044 2.249932 90)
			(size 0.2794 0.762)
			(layers "B.Cu" "B.Mask" "B.Paste")
			(net "P52V_HS2_4287_S2N")
		)
		(pad "9" smd rect
			(at 3.425444 2.750058 90)
			(size 0.2794 0.7112)
			(layers "B.Cu" "B.Mask" "B.Paste")
			(net "P52V_HS2_4287_S2P")
		)
		(pad "10" smd rect
			(at 2.750058 3.425444)
			(size 0.2794 0.7112)
			(layers "B.Cu" "B.Mask" "B.Paste")
			(net "P52V_2")
		)
		(pad "11" smd rect
			(at 0.750062 3.400044)
			(size 0.2794 0.762)
			(layers "B.Cu" "B.Mask" "B.Paste")
			(net "P52V_HS2_UVLO_EN")
		)
		(pad "12" smd rect
			(at 0.249936 3.400044)
			(size 0.2794 0.762)
			(layers "B.Cu" "B.Mask" "B.Paste")
			(net "P52V_HS2_OV")
		)
		(pad "13" smd rect
			(at -0.249936 3.400044)
			(size 0.2794 0.762)
			(layers "B.Cu" "B.Mask" "B.Paste")
			(net "P52V_HS2_INTVCC")
		)
		(pad "14" smd rect
			(at -0.750062 3.400044)
			(size 0.2794 0.762)
			(layers "B.Cu" "B.Mask" "B.Paste")
			(net "GND1_FIELD_SIGNAL")
		)
		(pad "15" smd rect
			(at -1.249934 3.400044)
			(size 0.2794 0.762)
			(layers "B.Cu" "B.Mask" "B.Paste")
			(net "P52V_HS2_DVCC")
		)
		(pad "16" smd rect
			(at -1.75006 3.400044)
			(size 0.2794 0.762)
			(layers "B.Cu" "B.Mask" "B.Paste")
			(net "P52V_HS2_ADR0")
		)
		(pad "17" smd rect
			(at -2.249932 3.400044)
			(size 0.2794 0.762)
			(layers "B.Cu" "B.Mask" "B.Paste")
			(net "P52V_HS2_ADR1")
		)
		(pad "18" smd rect
			(at -2.750058 3.425444)
			(size 0.2794 0.7112)
			(layers "B.Cu" "B.Mask" "B.Paste")
			(net "Net_410")
		)
		(pad "19" smd rect
			(at -3.425444 2.750058 90)
			(size 0.2794 0.7112)
			(layers "B.Cu" "B.Mask" "B.Paste")
			(net "P52V_HS2_MODE")
		)
		(pad "20" smd rect
			(at -3.400044 2.249932 90)
			(size 0.2794 0.762)
			(layers "B.Cu" "B.Mask" "B.Paste")
			(net "P52V_HS2_TMR")
		)
		(pad "21" smd rect
			(at -3.400044 1.75006 90)
			(size 0.2794 0.762)
			(layers "B.Cu" "B.Mask" "B.Paste")
			(net "P52V_HS2_CLKIN")
		)
		(pad "22" smd rect
			(at -3.400044 1.249934 90)
			(size 0.2794 0.762)
			(layers "B.Cu" "B.Mask" "B.Paste")
			(net "Net_414")
		)
		(pad "23" smd rect
			(at -3.400044 0.750062 90)
			(size 0.2794 0.762)
			(layers "B.Cu" "B.Mask" "B.Paste")
			(net "P52V_HS2_EN")
		)
		(pad "24" smd rect
			(at -3.400044 0.249936 90)
			(size 0.2794 0.762)
			(layers "B.Cu" "B.Mask" "B.Paste")
			(net "P52V_HS2_SIO")
		)
		(pad "25" smd rect
			(at -3.400044 -0.249936 90)
			(size 0.2794 0.762)
			(layers "B.Cu" "B.Mask" "B.Paste")
			(net "P52V_HS2_SCK")
		)
		(pad "26" smd rect
			(at -3.400044 -0.750062 90)
			(size 0.2794 0.762)
			(layers "B.Cu" "B.Mask" "B.Paste")
			(net "P52V_HS2_CS")
		)
		(pad "27" smd rect
			(at -3.400044 -1.249934 90)
			(size 0.2794 0.762)
			(layers "B.Cu" "B.Mask" "B.Paste")
			(net "SMB_P52V_PDB_SCL_R4")
		)
		(pad "28" smd rect
			(at -3.400044 -1.75006 90)
			(size 0.2794 0.762)
			(layers "B.Cu" "B.Mask" "B.Paste")
			(net "SMB_P52V_HS2_SDAI")
		)
		(pad "29" smd rect
			(at -3.400044 -2.249932 90)
			(size 0.2794 0.762)
			(layers "B.Cu" "B.Mask" "B.Paste")
			(net "SMB_P52V_HS2_SDAO")
		)
		(pad "30" smd rect
			(at -3.425444 -2.750058 90)
			(size 0.2794 0.7112)
			(layers "B.Cu" "B.Mask" "B.Paste")
			(net "Net_411")
		)
		(pad "31" smd rect
			(at -2.750058 -3.425444)
			(size 0.2794 0.7112)
			(layers "B.Cu" "B.Mask" "B.Paste")
			(net "Net_412")
		)
		(pad "32" smd rect
			(at -2.249932 -3.400044)
			(size 0.2794 0.762)
			(layers "B.Cu" "B.Mask" "B.Paste")
			(net "Net_413")
		)
		(pad "33" smd rect
			(at -1.75006 -3.400044)
			(size 0.2794 0.762)
			(layers "B.Cu" "B.Mask" "B.Paste")
			(net "GND1_FIELD_SIGNAL")
		)
		(pad "34" smd rect
			(at -1.249934 -3.400044)
			(size 0.2794 0.762)
			(layers "B.Cu" "B.Mask" "B.Paste")
			(net "GND1_FIELD_SIGNAL")
		)
		(pad "35" smd rect
			(at -0.750062 -3.400044)
			(size 0.2794 0.762)
			(layers "B.Cu" "B.Mask" "B.Paste")
			(net "P52V_HS2_TEMP")
		)
		(pad "36" smd rect
			(at -0.249936 -3.400044)
			(size 0.2794 0.762)
			(layers "B.Cu" "B.Mask" "B.Paste")
			(net "P52V_HS2_FLT")
		)
		(pad "37" smd rect
			(at 0.249936 -3.400044)
			(size 0.2794 0.762)
			(layers "B.Cu" "B.Mask" "B.Paste")
			(net "PWRGD_P52V_HS2_4287_PG_N")
		)
		(pad "38" smd rect
			(at 0.750062 -3.400044)
			(size 0.2794 0.762)
			(layers "B.Cu" "B.Mask" "B.Paste")
			(net "P52V_HS2_FB")
		)
		(pad "39" smd rect
			(at 2.750058 -3.425444)
			(size 0.2794 0.7112)
			(layers "B.Cu" "B.Mask" "B.Paste")
			(net "P52V_HS2_VDSFB")
		)
		(pad "40" smd circle
			(at -0.87503 0)
			(size 0 0)
			(layers "B.Cu" "B.Mask" "B.Paste")
			(net "GND1_FIELD_SIGNAL")
		)
		(zone
			(layer "B.Cu")
			(hatch none 0.5)
			(connect_pads
				(clearance 0)
			)
			(min_thickness 0.25)
			(keepout
				(tracks not_allowed)
				(vias allowed)
				(pads allowed)
				(copperpour not_allowed)
				(footprints allowed)
			)
			(placement
				(enabled no)
				(sheetname "")
			)
			(fill
				(thermal_gap 0.5)
				(thermal_bridge_width 0.5)
				(island_removal_mode 0)
			)
			(polygon
				(pts
					(xy 151.129492 -67.66052) (xy 151.129492 -69.4436) (xy 153.081736 -69.4436) (xy 153.081736 -67.7164)
					(xy 153.462736 -67.3354) (xy 156.866336 -67.3354) (xy 156.866336 -72.8726) (xy 153.081736 -72.8726)
					(xy 153.081736 -69.469) (xy 151.129492 -69.469) (xy 151.129492 -72.55002) (xy 151.078692 -72.55002)
					(xy 151.078692 -73.123044) (xy 153.150316 -73.123044) (xy 153.150316 -73.072244) (xy 156.543756 -73.072244)
					(xy 156.543756 -73.123044) (xy 157.11678 -73.123044) (xy 157.11678 -72.55002) (xy 157.06598 -72.55002)
					(xy 157.06598 -67.65798) (xy 157.11678 -67.65798) (xy 157.11678 -67.084956) (xy 156.543756 -67.084956)
					(xy 156.543756 -67.135756) (xy 153.150316 -67.135756) (xy 153.150316 -67.084956) (xy 151.078692 -67.084956)
					(xy 151.078692 -67.66052)
				)
			)
		)
	)
	(footprint ""
		(layer "B.Cu")
		(at 284.7594 -64.516)
		(property "Reference" "PC551"
			(at 0 0 0)
			(layer "B.SilkS")
			(hide yes)
			(effects
				(font
					(size 1.27 1.27)
				)
				(justify mirror)
			)
		)
		(property "Value" ""
			(at 0 0 0)
			(layer "B.Fab")
			(effects
				(font
					(size 1.27 1.27)
				)
				(justify mirror)
			)
		)
		(duplicate_pad_numbers_are_jumpers no)
		(fp_line
			(start -0.7874 -0.4064)
			(end -0.7874 0.4064)
			(stroke
				(width 0.1524)
				(type default)
			)
			(layer "B.SilkS")
		)
		(fp_line
			(start -0.7874 0.4064)
			(end 0.7874 0.4064)
			(stroke
				(width 0.1524)
				(type default)
			)
			(layer "B.SilkS")
		)
		(fp_line
			(start 0.7874 -0.4064)
			(end -0.7874 -0.4064)
			(stroke
				(width 0.1524)
				(type default)
			)
			(layer "B.SilkS")
		)
		(fp_line
			(start 0.7874 0.4064)
			(end 0.7874 -0.4064)
			(stroke
				(width 0.1524)
				(type default)
			)
			(layer "B.SilkS")
		)
		(fp_line
			(start -0.67945 -0.3048)
			(end -0.67945 0.3048)
			(stroke
				(width 0.1)
				(type default)
			)
			(layer "B.Fab")
		)
		(fp_line
			(start -0.67945 0.3048)
			(end -0.120396 0.3048)
			(stroke
				(width 0.1)
				(type default)
			)
			(layer "B.Fab")
		)
		(fp_line
			(start -0.12065 -0.3048)
			(end -0.67945 -0.3048)
			(stroke
				(width 0.1)
				(type default)
			)
			(layer "B.Fab")
		)
		(fp_line
			(start -0.12065 -0.2794)
			(end -0.12065 -0.3048)
			(stroke
				(width 0.1)
				(type default)
			)
			(layer "B.Fab")
		)
		(fp_line
			(start -0.120396 0.2794)
			(end 0.12065 0.2794)
			(stroke
				(width 0.1)
				(type default)
			)
			(layer "B.Fab")
		)
		(fp_line
			(start -0.120396 0.3048)
			(end -0.120396 0.2794)
			(stroke
				(width 0.1)
				(type default)
			)
			(layer "B.Fab")
		)
		(fp_line
			(start 0.12065 -0.305054)
			(end 0.12065 -0.2794)
			(stroke
				(width 0.1)
				(type default)
			)
			(layer "B.Fab")
		)
		(fp_line
			(start 0.12065 -0.2794)
			(end -0.12065 -0.2794)
			(stroke
				(width 0.1)
				(type default)
			)
			(layer "B.Fab")
		)
		(fp_line
			(start 0.12065 0.2794)
			(end 0.12065 0.3048)
			(stroke
				(width 0.1)
				(type default)
			)
			(layer "B.Fab")
		)
		(fp_line
			(start 0.12065 0.3048)
			(end 0.67945 0.3048)
			(stroke
				(width 0.1)
				(type default)
			)
			(layer "B.Fab")
		)
		(fp_line
			(start 0.67945 -0.305054)
			(end 0.12065 -0.305054)
			(stroke
				(width 0.1)
				(type default)
			)
			(layer "B.Fab")
		)
		(fp_line
			(start 0.67945 0.3048)
			(end 0.67945 -0.305054)
			(stroke
				(width 0.1)
				(type default)
			)
			(layer "B.Fab")
		)
		(pad "1" smd circle
			(at 0.40005 0 180)
			(size 0 0)
			(layers "B.Cu" "B.Mask" "B.Paste")
			(net "HS1_TMR1")
		)
		(pad "2" smd circle
			(at -0.40005 0 180)
			(size 0 0)
			(layers "B.Cu" "B.Mask" "B.Paste")
			(net "GND_FIELD_SIGNAL")
		)
	)
	(footprint ""
		(layer "B.Cu")
		(at 341.503 -47.244 90)
		(property "Reference" "PC82"
			(at 0 0 90)
			(layer "B.SilkS")
			(hide yes)
			(effects
				(font
					(size 1.27 1.27)
				)
				(justify mirror)
			)
		)
		(property "Value" ""
			(at 0 0 90)
			(layer "B.Fab")
			(effects
				(font
					(size 1.27 1.27)
				)
				(justify mirror)
			)
		)
		(duplicate_pad_numbers_are_jumpers no)
		(fp_line
			(start 1.2954 -0.5842)
			(end -1.2954 -0.5842)
			(stroke
				(width 0.1524)
				(type default)
			)
			(layer "B.SilkS")
		)
		(fp_line
			(start -1.2954 -0.5842)
			(end -1.2954 0.5842)
			(stroke
				(width 0.1524)
				(type default)
			)
			(layer "B.SilkS")
		)
		(fp_line
			(start 1.2954 0.5842)
			(end 1.2954 -0.5842)
			(stroke
				(width 0.1524)
				(type default)
			)
			(layer "B.SilkS")
		)
		(fp_line
			(start -1.2954 0.5842)
			(end 1.2954 0.5842)
			(stroke
				(width 0.1524)
				(type default)
			)
			(layer "B.SilkS")
		)
		(fp_line
			(start 0.8636 -0.4572)
			(end -0.8636 -0.4572)
			(stroke
				(width 0.1)
				(type default)
			)
			(layer "B.Fab")
		)
		(fp_line
			(start -0.8636 -0.4572)
			(end -0.8636 -0.4064)
			(stroke
				(width 0.1)
				(type default)
			)
			(layer "B.Fab")
		)
		(fp_line
			(start 1.1938 -0.4064)
			(end 0.8636 -0.4064)
			(stroke
				(width 0.1)
				(type default)
			)
			(layer "B.Fab")
		)
		(fp_line
			(start 0.8636 -0.4064)
			(end 0.8636 -0.4572)
			(stroke
				(width 0.1)
				(type default)
			)
			(layer "B.Fab")
		)
		(fp_line
			(start -0.8636 -0.4064)
			(end -1.1938 -0.4064)
			(stroke
				(width 0.1)
				(type default)
			)
			(layer "B.Fab")
		)
		(fp_line
			(start -1.1938 -0.4064)
			(end -1.1938 0.4064)
			(stroke
				(width 0.1)
				(type default)
			)
			(layer "B.Fab")
		)
		(fp_line
			(start 1.1938 0.4064)
			(end 1.1938 -0.4064)
			(stroke
				(width 0.1)
				(type default)
			)
			(layer "B.Fab")
		)
		(fp_line
			(start 0.8636 0.4064)
			(end 1.1938 0.4064)
			(stroke
				(width 0.1)
				(type default)
			)
			(layer "B.Fab")
		)
		(fp_line
			(start -0.8636 0.4064)
			(end -0.8636 0.4572)
			(stroke
				(width 0.1)
				(type default)
			)
			(layer "B.Fab")
		)
		(fp_line
			(start -1.1938 0.4064)
			(end -0.8636 0.4064)
			(stroke
				(width 0.1)
				(type default)
			)
			(layer "B.Fab")
		)
		(fp_line
			(start 0.8636 0.4572)
			(end 0.8636 0.4064)
			(stroke
				(width 0.1)
				(type default)
			)
			(layer "B.Fab")
		)
		(fp_line
			(start -0.8636 0.4572)
			(end 0.8636 0.4572)
			(stroke
				(width 0.1)
				(type default)
			)
			(layer "B.Fab")
		)
		(pad "1" smd rect
			(at 0.7366 0)
			(size 0.7112 0.8128)
			(layers "B.Cu" "B.Mask" "B.Paste")
			(net "P52V_HS1_4287_GATE_R")
		)
		(pad "2" smd rect
			(at -0.7366 0)
			(size 0.7112 0.8128)
			(layers "B.Cu" "B.Mask" "B.Paste")
			(net "P52V_HS1")
		)
	)
	(footprint ""
		(layer "B.Cu")
		(at 106.045 -52.324 90)
		(property "Reference" "PC594"
			(at 0 0 90)
			(layer "B.SilkS")
			(hide yes)
			(effects
				(font
					(size 1.27 1.27)
				)
				(justify mirror)
			)
		)
		(property "Value" ""
			(at 0 0 90)
			(layer "B.Fab")
			(effects
				(font
					(size 1.27 1.27)
				)
				(justify mirror)
			)
		)
		(duplicate_pad_numbers_are_jumpers no)
		(fp_line
			(start 1.2954 -0.5842)
			(end -1.2954 -0.5842)
			(stroke
				(width 0.1524)
				(type default)
			)
			(layer "B.SilkS")
		)
		(fp_line
			(start -1.2954 -0.5842)
			(end -1.2954 0.5842)
			(stroke
				(width 0.1524)
				(type default)
			)
			(layer "B.SilkS")
		)
		(fp_line
			(start 1.2954 0.5842)
			(end 1.2954 -0.5842)
			(stroke
				(width 0.1524)
				(type default)
			)
			(layer "B.SilkS")
		)
		(fp_line
			(start -1.2954 0.5842)
			(end 1.2954 0.5842)
			(stroke
				(width 0.1524)
				(type default)
			)
			(layer "B.SilkS")
		)
		(fp_line
			(start 0.8636 -0.4572)
			(end -0.8636 -0.4572)
			(stroke
				(width 0.1)
				(type default)
			)
			(layer "B.Fab")
		)
		(fp_line
			(start -0.8636 -0.4572)
			(end -0.8636 -0.4064)
			(stroke
				(width 0.1)
				(type default)
			)
			(layer "B.Fab")
		)
		(fp_line
			(start 1.1938 -0.4064)
			(end 0.8636 -0.4064)
			(stroke
				(width 0.1)
				(type default)
			)
			(layer "B.Fab")
		)
		(fp_line
			(start 0.8636 -0.4064)
			(end 0.8636 -0.4572)
			(stroke
				(width 0.1)
				(type default)
			)
			(layer "B.Fab")
		)
		(fp_line
			(start -0.8636 -0.4064)
			(end -1.1938 -0.4064)
			(stroke
				(width 0.1)
				(type default)
			)
			(layer "B.Fab")
		)
		(fp_line
			(start -1.1938 -0.4064)
			(end -1.1938 0.4064)
			(stroke
				(width 0.1)
				(type default)
			)
			(layer "B.Fab")
		)
		(fp_line
			(start 1.1938 0.4064)
			(end 1.1938 -0.4064)
			(stroke
				(width 0.1)
				(type default)
			)
			(layer "B.Fab")
		)
		(fp_line
			(start 0.8636 0.4064)
			(end 1.1938 0.4064)
			(stroke
				(width 0.1)
				(type default)
			)
			(layer "B.Fab")
		)
		(fp_line
			(start -0.8636 0.4064)
			(end -0.8636 0.4572)
			(stroke
				(width 0.1)
				(type default)
			)
			(layer "B.Fab")
		)
		(fp_line
			(start -1.1938 0.4064)
			(end -0.8636 0.4064)
			(stroke
				(width 0.1)
				(type default)
			)
			(layer "B.Fab")
		)
		(fp_line
			(start 0.8636 0.4572)
			(end 0.8636 0.4064)
			(stroke
				(width 0.1)
				(type default)
			)
			(layer "B.Fab")
		)
		(fp_line
			(start -0.8636 0.4572)
			(end 0.8636 0.4572)
			(stroke
				(width 0.1)
				(type default)
			)
			(layer "B.Fab")
		)
		(pad "1" smd rect
			(at 0.7366 0)
			(size 0.7112 0.8128)
			(layers "B.Cu" "B.Mask" "B.Paste")
			(net "P52V_HS2_4287_GATE_R")
		)
		(pad "2" smd rect
			(at -0.7366 0)
			(size 0.7112 0.8128)
			(layers "B.Cu" "B.Mask" "B.Paste")
			(net "P52V_HS2")
		)
	)
	(footprint ""
		(layer "B.Cu")
		(at 106.045 -43.815 -90)
		(property "Reference" "PR7003"
			(at 0 0 90)
			(layer "B.SilkS")
			(hide yes)
			(effects
				(font
					(size 1.27 1.27)
				)
				(justify mirror)
			)
		)
		(property "Value" ""
			(at 0 0 90)
			(layer "B.Fab")
			(effects
				(font
					(size 1.27 1.27)
				)
				(justify mirror)
			)
		)
		(duplicate_pad_numbers_are_jumpers no)
		(fp_line
			(start -1.2954 0.5842)
			(end 1.2954 0.5842)
			(stroke
				(width 0.1524)
				(type default)
			)
			(layer "B.SilkS")
		)
		(fp_line
			(start 1.2954 0.5842)
			(end 1.2954 -0.5842)
			(stroke
				(width 0.1524)
				(type default)
			)
			(layer "B.SilkS")
		)
		(fp_line
			(start -1.2954 -0.5842)
			(end -1.2954 0.5842)
			(stroke
				(width 0.1524)
				(type default)
			)
			(layer "B.SilkS")
		)
		(fp_line
			(start 1.2954 -0.5842)
			(end -1.2954 -0.5842)
			(stroke
				(width 0.1524)
				(type default)
			)
			(layer "B.SilkS")
		)
		(fp_line
			(start -0.8636 0.4572)
			(end 0.8636 0.4572)
			(stroke
				(width 0.1)
				(type default)
			)
			(layer "B.Fab")
		)
		(fp_line
			(start 0.8636 0.4572)
			(end 0.8636 0.4318)
			(stroke
				(width 0.1)
				(type default)
			)
			(layer "B.Fab")
		)
		(fp_line
			(start 0.8636 0.4318)
			(end 0.8636 0.4064)
			(stroke
				(width 0.1)
				(type default)
			)
			(layer "B.Fab")
		)
		(fp_line
			(start -1.1938 0.4064)
			(end -0.8636 0.4064)
			(stroke
				(width 0.1)
				(type default)
			)
			(layer "B.Fab")
		)
		(fp_line
			(start -0.8636 0.4064)
			(end -0.8636 0.4572)
			(stroke
				(width 0.1)
				(type default)
			)
			(layer "B.Fab")
		)
		(fp_line
			(start 0.8636 0.4064)
			(end 1.1938 0.4064)
			(stroke
				(width 0.1)
				(type default)
			)
			(layer "B.Fab")
		)
		(fp_line
			(start 1.1938 0.4064)
			(end 1.1938 -0.406654)
			(stroke
				(width 0.1)
				(type default)
			)
			(layer "B.Fab")
		)
		(fp_line
			(start -1.1938 -0.406654)
			(end -1.1938 0.4064)
			(stroke
				(width 0.1)
				(type default)
			)
			(layer "B.Fab")
		)
		(fp_line
			(start -0.8636 -0.406654)
			(end -1.1938 -0.406654)
			(stroke
				(width 0.1)
				(type default)
			)
			(layer "B.Fab")
		)
		(fp_line
			(start 0.8636 -0.406654)
			(end 0.8636 -0.4572)
			(stroke
				(width 0.1)
				(type default)
			)
			(layer "B.Fab")
		)
		(fp_line
			(start 1.1938 -0.406654)
			(end 0.8636 -0.406654)
			(stroke
				(width 0.1)
				(type default)
			)
			(layer "B.Fab")
		)
		(fp_line
			(start -0.8636 -0.4572)
			(end -0.8636 -0.406654)
			(stroke
				(width 0.1)
				(type default)
			)
			(layer "B.Fab")
		)
		(fp_line
			(start 0.8636 -0.4572)
			(end -0.8636 -0.4572)
			(stroke
				(width 0.1)
				(type default)
			)
			(layer "B.Fab")
		)
		(pad "1" smd rect
			(at 0.7366 0 180)
			(size 0.7112 0.8128)
			(layers "B.Cu" "B.Mask" "B.Paste")
			(net "P52V_HS2_4287_GATE2_R")
		)
		(pad "2" smd rect
			(at -0.7366 0 180)
			(size 0.7112 0.8128)
			(layers "B.Cu" "B.Mask" "B.Paste")
			(net "P52V_HS2_4287_GATE2_RC")
		)
	)
	(footprint ""
		(layer "B.Cu")
		(at 297.3324 -79.248)
		(property "Reference" "PR23"
			(at 0 0 0)
			(layer "B.SilkS")
			(hide yes)
			(effects
				(font
					(size 1.27 1.27)
				)
				(justify mirror)
			)
		)
		(property "Value" ""
			(at 0 0 0)
			(layer "B.Fab")
			(effects
				(font
					(size 1.27 1.27)
				)
				(justify mirror)
			)
		)
		(duplicate_pad_numbers_are_jumpers no)
		(fp_line
			(start -1.651 -0.8382)
			(end -1.651 0.8382)
			(stroke
				(width 0.1524)
				(type default)
			)
			(layer "B.SilkS")
		)
		(fp_line
			(start -1.651 0.8382)
			(end 1.651 0.8382)
			(stroke
				(width 0.1524)
				(type default)
			)
			(layer "B.SilkS")
		)
		(fp_line
			(start 1.651 -0.8382)
			(end -1.651 -0.8382)
			(stroke
				(width 0.1524)
				(type default)
			)
			(layer "B.SilkS")
		)
		(fp_line
			(start 1.651 0.8382)
			(end 1.651 -0.8382)
			(stroke
				(width 0.1524)
				(type default)
			)
			(layer "B.SilkS")
		)
		(fp_line
			(start -1.560576 -0.7366)
			(end -1.524 -0.7366)
			(stroke
				(width 0.1)
				(type default)
			)
			(layer "B.Fab")
		)
		(fp_line
			(start -1.560576 0.7366)
			(end -1.560576 -0.7366)
			(stroke
				(width 0.1)
				(type default)
			)
			(layer "B.Fab")
		)
		(fp_line
			(start -1.524 -0.7366)
			(end 1.524 -0.7366)
			(stroke
				(width 0.1)
				(type default)
			)
			(layer "B.Fab")
		)
		(fp_line
			(start -1.524 0.7366)
			(end -1.560576 0.7366)
			(stroke
				(width 0.1)
				(type default)
			)
			(layer "B.Fab")
		)
		(fp_line
			(start 1.524 -0.7366)
			(end 1.559814 -0.7366)
			(stroke
				(width 0.1)
				(type default)
			)
			(layer "B.Fab")
		)
		(fp_line
			(start 1.524 0.7366)
			(end -1.524 0.7366)
			(stroke
				(width 0.1)
				(type default)
			)
			(layer "B.Fab")
		)
		(fp_line
			(start 1.559814 -0.7366)
			(end 1.559814 0.7366)
			(stroke
				(width 0.1)
				(type default)
			)
			(layer "B.Fab")
		)
		(fp_line
			(start 1.559814 0.7366)
			(end 1.524 0.7366)
			(stroke
				(width 0.1)
				(type default)
			)
			(layer "B.Fab")
		)
		(pad "1" smd rect
			(at 0.94996 0)
			(size 1.1176 1.3716)
			(layers "B.Cu" "B.Mask" "B.Paste")
			(net "P52V_HS1")
		)
		(pad "2" smd rect
			(at -0.94996 0)
			(size 1.1176 1.3716)
			(layers "B.Cu" "B.Mask" "B.Paste")
			(net "P52V_HS1_FB")
		)
	)
	(footprint ""
		(layer "B.Cu")
		(at 177.592736 -77.851 180)
		(property "Reference" "PR7025"
			(at 0 0 0)
			(layer "B.SilkS")
			(hide yes)
			(effects
				(font
					(size 1.27 1.27)
				)
				(justify mirror)
			)
		)
		(property "Value" ""
			(at 0 0 0)
			(layer "B.Fab")
			(effects
				(font
					(size 1.27 1.27)
				)
				(justify mirror)
			)
		)
		(duplicate_pad_numbers_are_jumpers no)
		(fp_line
			(start 0.7874 0.4064)
			(end 0.7874 -0.4064)
			(stroke
				(width 0.1524)
				(type default)
			)
			(layer "B.SilkS")
		)
		(fp_line
			(start 0.7874 -0.4064)
			(end -0.7874 -0.4064)
			(stroke
				(width 0.1524)
				(type default)
			)
			(layer "B.SilkS")
		)
		(fp_line
			(start -0.7874 0.4064)
			(end 0.7874 0.4064)
			(stroke
				(width 0.1524)
				(type default)
			)
			(layer "B.SilkS")
		)
		(fp_line
			(start -0.7874 -0.4064)
			(end -0.7874 0.4064)
			(stroke
				(width 0.1524)
				(type default)
			)
			(layer "B.SilkS")
		)
		(fp_line
			(start 0.67945 0.3048)
			(end 0.67945 -0.305054)
			(stroke
				(width 0.1)
				(type default)
			)
			(layer "B.Fab")
		)
		(fp_line
			(start 0.67945 -0.305054)
			(end 0.12065 -0.305054)
			(stroke
				(width 0.1)
				(type default)
			)
			(layer "B.Fab")
		)
		(fp_line
			(start 0.12065 0.3048)
			(end 0.67945 0.3048)
			(stroke
				(width 0.1)
				(type default)
			)
			(layer "B.Fab")
		)
		(fp_line
			(start 0.12065 0.2794)
			(end 0.12065 0.3048)
			(stroke
				(width 0.1)
				(type default)
			)
			(layer "B.Fab")
		)
		(fp_line
			(start 0.12065 -0.2794)
			(end -0.12065 -0.2794)
			(stroke
				(width 0.1)
				(type default)
			)
			(layer "B.Fab")
		)
		(fp_line
			(start 0.12065 -0.305054)
			(end 0.12065 -0.2794)
			(stroke
				(width 0.1)
				(type default)
			)
			(layer "B.Fab")
		)
		(fp_line
			(start -0.120396 0.3048)
			(end -0.120396 0.2794)
			(stroke
				(width 0.1)
				(type default)
			)
			(layer "B.Fab")
		)
		(fp_line
			(start -0.120396 0.2794)
			(end 0.12065 0.2794)
			(stroke
				(width 0.1)
				(type default)
			)
			(layer "B.Fab")
		)
		(fp_line
			(start -0.12065 -0.2794)
			(end -0.12065 -0.3048)
			(stroke
				(width 0.1)
				(type default)
			)
			(layer "B.Fab")
		)
		(fp_line
			(start -0.12065 -0.3048)
			(end -0.67945 -0.3048)
			(stroke
				(width 0.1)
				(type default)
			)
			(layer "B.Fab")
		)
		(fp_line
			(start -0.67945 0.3048)
			(end -0.120396 0.3048)
			(stroke
				(width 0.1)
				(type default)
			)
			(layer "B.Fab")
		)
		(fp_line
			(start -0.67945 -0.3048)
			(end -0.67945 0.3048)
			(stroke
				(width 0.1)
				(type default)
			)
			(layer "B.Fab")
		)
		(pad "1" smd circle
			(at 0.40005 0)
			(size 0 0)
			(layers "B.Cu" "B.Mask" "B.Paste")
			(net "P52V_HS2_PWRGIN")
		)
		(pad "2" smd circle
			(at -0.40005 0)
			(size 0 0)
			(layers "B.Cu" "B.Mask" "B.Paste")
			(net "GND1_FIELD_SIGNAL")
		)
	)
	(footprint ""
		(layer "B.Cu")
		(at 297.307 -90.17 -90)
		(property "Reference" "C105"
			(at 0 0 90)
			(layer "B.SilkS")
			(hide yes)
			(effects
				(font
					(size 1.27 1.27)
				)
				(justify mirror)
			)
		)
		(property "Value" ""
			(at 0 0 90)
			(layer "B.Fab")
			(effects
				(font
					(size 1.27 1.27)
				)
				(justify mirror)
			)
		)
		(duplicate_pad_numbers_are_jumpers no)
		(fp_line
			(start -0.7874 0.4064)
			(end 0.7874 0.4064)
			(stroke
				(width 0.1524)
				(type default)
			)
			(layer "B.SilkS")
		)
		(fp_line
			(start 0.7874 0.4064)
			(end 0.7874 -0.4064)
			(stroke
				(width 0.1524)
				(type default)
			)
			(layer "B.SilkS")
		)
		(fp_line
			(start -0.7874 -0.4064)
			(end -0.7874 0.4064)
			(stroke
				(width 0.1524)
				(type default)
			)
			(layer "B.SilkS")
		)
		(fp_line
			(start 0.7874 -0.4064)
			(end -0.7874 -0.4064)
			(stroke
				(width 0.1524)
				(type default)
			)
			(layer "B.SilkS")
		)
		(fp_line
			(start -0.67945 0.3048)
			(end -0.120396 0.3048)
			(stroke
				(width 0.1)
				(type default)
			)
			(layer "B.Fab")
		)
		(fp_line
			(start -0.120396 0.3048)
			(end -0.120396 0.2794)
			(stroke
				(width 0.1)
				(type default)
			)
			(layer "B.Fab")
		)
		(fp_line
			(start 0.12065 0.3048)
			(end 0.67945 0.3048)
			(stroke
				(width 0.1)
				(type default)
			)
			(layer "B.Fab")
		)
		(fp_line
			(start 0.67945 0.3048)
			(end 0.67945 -0.305054)
			(stroke
				(width 0.1)
				(type default)
			)
			(layer "B.Fab")
		)
		(fp_line
			(start -0.120396 0.2794)
			(end 0.12065 0.2794)
			(stroke
				(width 0.1)
				(type default)
			)
			(layer "B.Fab")
		)
		(fp_line
			(start 0.12065 0.2794)
			(end 0.12065 0.3048)
			(stroke
				(width 0.1)
				(type default)
			)
			(layer "B.Fab")
		)
		(fp_line
			(start -0.12065 -0.2794)
			(end -0.12065 -0.3048)
			(stroke
				(width 0.1)
				(type default)
			)
			(layer "B.Fab")
		)
		(fp_line
			(start 0.12065 -0.2794)
			(end -0.12065 -0.2794)
			(stroke
				(width 0.1)
				(type default)
			)
			(layer "B.Fab")
		)
		(fp_line
			(start -0.67945 -0.3048)
			(end -0.67945 0.3048)
			(stroke
				(width 0.1)
				(type default)
			)
			(layer "B.Fab")
		)
		(fp_line
			(start -0.12065 -0.3048)
			(end -0.67945 -0.3048)
			(stroke
				(width 0.1)
				(type default)
			)
			(layer "B.Fab")
		)
		(fp_line
			(start 0.12065 -0.305054)
			(end 0.12065 -0.2794)
			(stroke
				(width 0.1)
				(type default)
			)
			(layer "B.Fab")
		)
		(fp_line
			(start 0.67945 -0.305054)
			(end 0.12065 -0.305054)
			(stroke
				(width 0.1)
				(type default)
			)
			(layer "B.Fab")
		)
		(pad "1" smd circle
			(at 0.40005 0 90)
			(size 0 0)
			(layers "B.Cu" "B.Mask" "B.Paste")
			(net "GND")
		)
		(pad "2" smd circle
			(at -0.40005 0 90)
			(size 0 0)
			(layers "B.Cu" "B.Mask" "B.Paste")
			(net "P3V3_AUX")
		)
	)
	(footprint ""
		(layer "B.Cu")
		(at 267.3604 -62.738 180)
		(property "Reference" "PC13"
			(at 0 0 0)
			(layer "B.SilkS")
			(hide yes)
			(effects
				(font
					(size 1.27 1.27)
				)
				(justify mirror)
			)
		)
		(property "Value" ""
			(at 0 0 0)
			(layer "B.Fab")
			(effects
				(font
					(size 1.27 1.27)
				)
				(justify mirror)
			)
		)
		(duplicate_pad_numbers_are_jumpers no)
		(fp_line
			(start 1.524 0.762)
			(end 1.524 -0.762)
			(stroke
				(width 0.1524)
				(type default)
			)
			(layer "B.SilkS")
		)
		(fp_line
			(start 1.524 -0.762)
			(end -1.524 -0.762)
			(stroke
				(width 0.1524)
				(type default)
			)
			(layer "B.SilkS")
		)
		(fp_line
			(start -1.524 0.762)
			(end 1.524 0.762)
			(stroke
				(width 0.1524)
				(type default)
			)
			(layer "B.SilkS")
		)
		(fp_line
			(start -1.524 -0.762)
			(end -1.524 0.762)
			(stroke
				(width 0.1524)
				(type default)
			)
			(layer "B.SilkS")
		)
		(fp_line
			(start 1.1049 0.724916)
			(end -1.1049 0.724916)
			(stroke
				(width 0.1)
				(type default)
			)
			(layer "B.Fab")
		)
		(fp_line
			(start 1.1049 -0.724916)
			(end 1.1049 0.724916)
			(stroke
				(width 0.1)
				(type default)
			)
			(layer "B.Fab")
		)
		(fp_line
			(start -1.1049 0.724916)
			(end -1.1049 -0.724916)
			(stroke
				(width 0.1)
				(type default)
			)
			(layer "B.Fab")
		)
		(fp_line
			(start -1.1049 -0.724916)
			(end 1.1049 -0.724916)
			(stroke
				(width 0.1)
				(type default)
			)
			(layer "B.Fab")
		)
		(pad "1" smd rect
			(at 0.889 0 180)
			(size 1.016 1.27)
			(layers "B.Cu" "B.Mask" "B.Paste")
			(net "P52V_HS1_DV_DT")
		)
		(pad "2" smd rect
			(at -0.889 0 180)
			(size 1.016 1.27)
			(layers "B.Cu" "B.Mask" "B.Paste")
			(net "GND_FIELD_SIGNAL")
		)
	)
	(footprint ""
		(layer "B.Cu")
		(at 337.3374 -39.37 90)
		(property "Reference" "R5863"
			(at 0 0 90)
			(layer "B.SilkS")
			(hide yes)
			(effects
				(font
					(size 1.27 1.27)
				)
				(justify mirror)
			)
		)
		(property "Value" ""
			(at 0 0 90)
			(layer "B.Fab")
			(effects
				(font
					(size 1.27 1.27)
				)
				(justify mirror)
			)
		)
		(duplicate_pad_numbers_are_jumpers no)
		(fp_line
			(start 0.7874 -0.4064)
			(end -0.7874 -0.4064)
			(stroke
				(width 0.1524)
				(type default)
			)
			(layer "B.SilkS")
		)
		(fp_line
			(start -0.7874 -0.4064)
			(end -0.7874 0.4064)
			(stroke
				(width 0.1524)
				(type default)
			)
			(layer "B.SilkS")
		)
		(fp_line
			(start 0.7874 0.4064)
			(end 0.7874 -0.4064)
			(stroke
				(width 0.1524)
				(type default)
			)
			(layer "B.SilkS")
		)
		(fp_line
			(start -0.7874 0.4064)
			(end 0.7874 0.4064)
			(stroke
				(width 0.1524)
				(type default)
			)
			(layer "B.SilkS")
		)
		(fp_line
			(start 0.67945 -0.305054)
			(end 0.12065 -0.305054)
			(stroke
				(width 0.1)
				(type default)
			)
			(layer "B.Fab")
		)
		(fp_line
			(start 0.12065 -0.305054)
			(end 0.12065 -0.2794)
			(stroke
				(width 0.1)
				(type default)
			)
			(layer "B.Fab")
		)
		(fp_line
			(start -0.12065 -0.3048)
			(end -0.67945 -0.3048)
			(stroke
				(width 0.1)
				(type default)
			)
			(layer "B.Fab")
		)
		(fp_line
			(start -0.67945 -0.3048)
			(end -0.67945 0.3048)
			(stroke
				(width 0.1)
				(type default)
			)
			(layer "B.Fab")
		)
		(fp_line
			(start 0.12065 -0.2794)
			(end -0.12065 -0.2794)
			(stroke
				(width 0.1)
				(type default)
			)
			(layer "B.Fab")
		)
		(fp_line
			(start -0.12065 -0.2794)
			(end -0.12065 -0.3048)
			(stroke
				(width 0.1)
				(type default)
			)
			(layer "B.Fab")
		)
		(fp_line
			(start 0.12065 0.2794)
			(end 0.12065 0.3048)
			(stroke
				(width 0.1)
				(type default)
			)
			(layer "B.Fab")
		)
		(fp_line
			(start -0.120396 0.2794)
			(end 0.12065 0.2794)
			(stroke
				(width 0.1)
				(type default)
			)
			(layer "B.Fab")
		)
		(fp_line
			(start 0.67945 0.3048)
			(end 0.67945 -0.305054)
			(stroke
				(width 0.1)
				(type default)
			)
			(layer "B.Fab")
		)
		(fp_line
			(start 0.12065 0.3048)
			(end 0.67945 0.3048)
			(stroke
				(width 0.1)
				(type default)
			)
			(layer "B.Fab")
		)
		(fp_line
			(start -0.120396 0.3048)
			(end -0.120396 0.2794)
			(stroke
				(width 0.1)
				(type default)
			)
			(layer "B.Fab")
		)
		(fp_line
			(start -0.67945 0.3048)
			(end -0.120396 0.3048)
			(stroke
				(width 0.1)
				(type default)
			)
			(layer "B.Fab")
		)
		(pad "1" smd circle
			(at 0.40005 0 270)
			(size 0 0)
			(layers "B.Cu" "B.Mask" "B.Paste")
			(net "P52V_HS1_GATE2_R")
		)
		(pad "2" smd circle
			(at -0.40005 0 270)
			(size 0 0)
			(layers "B.Cu" "B.Mask" "B.Paste")
			(net "P52V_HS1_4287_GATE2_R")
		)
	)
	(footprint ""
		(layer "B.Cu")
		(at 277.9014 -70.612 180)
		(property "Reference" "PC591"
			(at 0 0 0)
			(layer "B.SilkS")
			(hide yes)
			(effects
				(font
					(size 1.27 1.27)
				)
				(justify mirror)
			)
		)
		(property "Value" ""
			(at 0 0 0)
			(layer "B.Fab")
			(effects
				(font
					(size 1.27 1.27)
				)
				(justify mirror)
			)
		)
		(duplicate_pad_numbers_are_jumpers no)
		(fp_line
			(start 1.2954 0.5842)
			(end 1.2954 -0.5842)
			(stroke
				(width 0.1524)
				(type default)
			)
			(layer "B.SilkS")
		)
		(fp_line
			(start 1.2954 -0.5842)
			(end -1.2954 -0.5842)
			(stroke
				(width 0.1524)
				(type default)
			)
			(layer "B.SilkS")
		)
		(fp_line
			(start -1.2954 0.5842)
			(end 1.2954 0.5842)
			(stroke
				(width 0.1524)
				(type default)
			)
			(layer "B.SilkS")
		)
		(fp_line
			(start -1.2954 -0.5842)
			(end -1.2954 0.5842)
			(stroke
				(width 0.1524)
				(type default)
			)
			(layer "B.SilkS")
		)
		(fp_line
			(start 1.1938 0.4064)
			(end 1.1938 -0.4064)
			(stroke
				(width 0.1)
				(type default)
			)
			(layer "B.Fab")
		)
		(fp_line
			(start 1.1938 -0.4064)
			(end 0.8636 -0.4064)
			(stroke
				(width 0.1)
				(type default)
			)
			(layer "B.Fab")
		)
		(fp_line
			(start 0.8636 0.4572)
			(end 0.8636 0.4064)
			(stroke
				(width 0.1)
				(type default)
			)
			(layer "B.Fab")
		)
		(fp_line
			(start 0.8636 0.4064)
			(end 1.1938 0.4064)
			(stroke
				(width 0.1)
				(type default)
			)
			(layer "B.Fab")
		)
		(fp_line
			(start 0.8636 -0.4064)
			(end 0.8636 -0.4572)
			(stroke
				(width 0.1)
				(type default)
			)
			(layer "B.Fab")
		)
		(fp_line
			(start 0.8636 -0.4572)
			(end -0.8636 -0.4572)
			(stroke
				(width 0.1)
				(type default)
			)
			(layer "B.Fab")
		)
		(fp_line
			(start -0.8636 0.4572)
			(end 0.8636 0.4572)
			(stroke
				(width 0.1)
				(type default)
			)
			(layer "B.Fab")
		)
		(fp_line
			(start -0.8636 0.4064)
			(end -0.8636 0.4572)
			(stroke
				(width 0.1)
				(type default)
			)
			(layer "B.Fab")
		)
		(fp_line
			(start -0.8636 -0.4064)
			(end -1.1938 -0.4064)
			(stroke
				(width 0.1)
				(type default)
			)
			(layer "B.Fab")
		)
		(fp_line
			(start -0.8636 -0.4572)
			(end -0.8636 -0.4064)
			(stroke
				(width 0.1)
				(type default)
			)
			(layer "B.Fab")
		)
		(fp_line
			(start -1.1938 0.4064)
			(end -0.8636 0.4064)
			(stroke
				(width 0.1)
				(type default)
			)
			(layer "B.Fab")
		)
		(fp_line
			(start -1.1938 -0.4064)
			(end -1.1938 0.4064)
			(stroke
				(width 0.1)
				(type default)
			)
			(layer "B.Fab")
		)
		(pad "1" smd rect
			(at 0.7366 0 90)
			(size 0.7112 0.8128)
			(layers "B.Cu" "B.Mask" "B.Paste")
			(net "P52V_HS1_VCAP")
		)
		(pad "2" smd rect
			(at -0.7366 0 90)
			(size 0.7112 0.8128)
			(layers "B.Cu" "B.Mask" "B.Paste")
			(net "GND_FIELD_SIGNAL")
		)
	)
	(footprint ""
		(layer "B.Cu")
		(at 293.5224 -70.104)
		(property "Reference" "PU1"
			(at 6.1976 -5.05333 0)
			(unlocked yes)
			(layer "B.SilkS")
			(effects
				(font
					(size 0.7874 0.5842)
					(thickness 0.1524)
				)
				(justify left mirror)
			)
		)
		(property "Value" ""
			(at 0 0 0)
			(layer "B.Fab")
			(effects
				(font
					(size 1.27 1.27)
				)
				(justify mirror)
			)
		)
		(duplicate_pad_numbers_are_jumpers no)
		(fp_line
			(start -3.549904 -3.549904)
			(end -3.549904 -3.0226)
			(stroke
				(width 0.1524)
				(type default)
			)
			(layer "B.SilkS")
		)
		(fp_line
			(start -3.549904 3.0226)
			(end -3.549904 3.549904)
			(stroke
				(width 0.1524)
				(type default)
			)
			(layer "B.SilkS")
		)
		(fp_line
			(start -3.549904 3.549904)
			(end -3.0226 3.549904)
			(stroke
				(width 0.1524)
				(type default)
			)
			(layer "B.SilkS")
		)
		(fp_line
			(start -3.0226 -3.549904)
			(end -3.549904 -3.549904)
			(stroke
				(width 0.1524)
				(type default)
			)
			(layer "B.SilkS")
		)
		(fp_line
			(start 1.03124 3.549904)
			(end 2.4638 3.549904)
			(stroke
				(width 0.1524)
				(type default)
			)
			(layer "B.SilkS")
		)
		(fp_line
			(start 2.4638 -3.549904)
			(end 1.03124 -3.549904)
			(stroke
				(width 0.1524)
				(type default)
			)
			(layer "B.SilkS")
		)
		(fp_line
			(start 3.0226 3.549904)
			(end 3.549904 3.549904)
			(stroke
				(width 0.1524)
				(type default)
			)
			(layer "B.SilkS")
		)
		(fp_line
			(start 3.549904 -3.549904)
			(end 3.0226 -3.549904)
			(stroke
				(width 0.1524)
				(type default)
			)
			(layer "B.SilkS")
		)
		(fp_line
			(start 3.549904 -3.0226)
			(end 3.549904 -3.549904)
			(stroke
				(width 0.1524)
				(type default)
			)
			(layer "B.SilkS")
		)
		(fp_line
			(start 3.549904 -0.0254)
			(end 3.549904 -1.4732)
			(stroke
				(width 0.1524)
				(type default)
			)
			(layer "B.SilkS")
		)
		(fp_line
			(start 3.549904 3.549904)
			(end 3.549904 3.0226)
			(stroke
				(width 0.1524)
				(type default)
			)
			(layer "B.SilkS")
		)
		(fp_poly
			(pts
				(xy 4.134104 -3.041904) (xy 3.549904 -3.041904) (xy 3.549904 -3.626104) (xy 4.134104 -3.626104)
			)
			(stroke
				(width 0)
				(type default)
			)
			(fill yes)
			(layer "B.SilkS")
		)
		(fp_line
			(start -3.549904 -3.549904)
			(end -3.549904 3.549904)
			(stroke
				(width 0.1)
				(type default)
			)
			(layer "B.Fab")
		)
		(fp_line
			(start -3.549904 3.549904)
			(end 3.549904 3.549904)
			(stroke
				(width 0.1)
				(type default)
			)
			(layer "B.Fab")
		)
		(fp_line
			(start 3.549904 -3.549904)
			(end -3.549904 -3.549904)
			(stroke
				(width 0.1)
				(type default)
			)
			(layer "B.Fab")
		)
		(fp_line
			(start 3.549904 3.549904)
			(end 3.549904 -3.549904)
			(stroke
				(width 0.1)
				(type default)
			)
			(layer "B.Fab")
		)
		(fp_poly
			(pts
				(xy 4.134104 -3.041904) (xy 3.549904 -3.041904) (xy 3.549904 -3.626104) (xy 4.134104 -3.626104)
			)
			(stroke
				(width 0)
				(type default)
			)
			(fill yes)
			(layer "B.Fab")
		)
		(pad "1" smd rect
			(at 3.425444 -2.750058 270)
			(size 0.2794 0.7112)
			(layers "B.Cu" "B.Mask" "B.Paste")
			(net "P52V_HS1")
		)
		(pad "2" smd rect
			(at 3.400044 -2.249932 270)
			(size 0.2794 0.762)
			(layers "B.Cu" "B.Mask" "B.Paste")
			(net "P52V_HS1_4287_GATE2_R")
		)
		(pad "3" smd rect
			(at 3.400044 -1.75006 270)
			(size 0.2794 0.762)
			(layers "B.Cu" "B.Mask" "B.Paste")
			(net "P52V_HS1_4287_GATE_R")
		)
		(pad "4" smd rect
			(at 3.400044 0.249936 270)
			(size 0.2794 0.762)
			(layers "B.Cu" "B.Mask" "B.Paste")
			(net "P52V_HS_4287_ADC_N")
		)
		(pad "5" smd rect
			(at 3.400044 0.750062 270)
			(size 0.2794 0.762)
			(layers "B.Cu" "B.Mask" "B.Paste")
			(net "P52V_HS_4287_S1N")
		)
		(pad "6" smd rect
			(at 3.400044 1.249934 270)
			(size 0.2794 0.762)
			(layers "B.Cu" "B.Mask" "B.Paste")
			(net "P52V_HS_4287_S1P")
		)
		(pad "7" smd rect
			(at 3.400044 1.75006 270)
			(size 0.2794 0.762)
			(layers "B.Cu" "B.Mask" "B.Paste")
			(net "P52V_HS_4287_ADC_P")
		)
		(pad "8" smd rect
			(at 3.400044 2.249932 270)
			(size 0.2794 0.762)
			(layers "B.Cu" "B.Mask" "B.Paste")
			(net "P52V_HS_4287_S2N")
		)
		(pad "9" smd rect
			(at 3.425444 2.750058 270)
			(size 0.2794 0.7112)
			(layers "B.Cu" "B.Mask" "B.Paste")
			(net "P52V_HS_4287_S2P")
		)
		(pad "10" smd rect
			(at 2.750058 3.425444 180)
			(size 0.2794 0.7112)
			(layers "B.Cu" "B.Mask" "B.Paste")
			(net "P52V_1")
		)
		(pad "11" smd rect
			(at 0.750062 3.400044 180)
			(size 0.2794 0.762)
			(layers "B.Cu" "B.Mask" "B.Paste")
			(net "P52V_HS1_UVLO_EN")
		)
		(pad "12" smd rect
			(at 0.249936 3.400044 180)
			(size 0.2794 0.762)
			(layers "B.Cu" "B.Mask" "B.Paste")
			(net "P52V_HS1_OV")
		)
		(pad "13" smd rect
			(at -0.249936 3.400044 180)
			(size 0.2794 0.762)
			(layers "B.Cu" "B.Mask" "B.Paste")
			(net "P52V_HS1_INTVCC")
		)
		(pad "14" smd rect
			(at -0.750062 3.400044 180)
			(size 0.2794 0.762)
			(layers "B.Cu" "B.Mask" "B.Paste")
			(net "GND_FIELD_SIGNAL")
		)
		(pad "15" smd rect
			(at -1.249934 3.400044 180)
			(size 0.2794 0.762)
			(layers "B.Cu" "B.Mask" "B.Paste")
			(net "P52V_HS1_DVCC")
		)
		(pad "16" smd rect
			(at -1.75006 3.400044 180)
			(size 0.2794 0.762)
			(layers "B.Cu" "B.Mask" "B.Paste")
			(net "P52V_HS1_ADR0")
		)
		(pad "17" smd rect
			(at -2.249932 3.400044 180)
			(size 0.2794 0.762)
			(layers "B.Cu" "B.Mask" "B.Paste")
			(net "P52V_HS1_ADR1")
		)
		(pad "18" smd rect
			(at -2.750058 3.425444 180)
			(size 0.2794 0.7112)
			(layers "B.Cu" "B.Mask" "B.Paste")
			(net "Net_401")
		)
		(pad "19" smd rect
			(at -3.425444 2.750058 270)
			(size 0.2794 0.7112)
			(layers "B.Cu" "B.Mask" "B.Paste")
			(net "P52V_HS1_MODE")
		)
		(pad "20" smd rect
			(at -3.400044 2.249932 270)
			(size 0.2794 0.762)
			(layers "B.Cu" "B.Mask" "B.Paste")
			(net "P52V_HS1_TMR")
		)
		(pad "21" smd rect
			(at -3.400044 1.75006 270)
			(size 0.2794 0.762)
			(layers "B.Cu" "B.Mask" "B.Paste")
			(net "P52V_HS1_CLKIN")
		)
		(pad "22" smd rect
			(at -3.400044 1.249934 270)
			(size 0.2794 0.762)
			(layers "B.Cu" "B.Mask" "B.Paste")
			(net "Net_405")
		)
		(pad "23" smd rect
			(at -3.400044 0.750062 270)
			(size 0.2794 0.762)
			(layers "B.Cu" "B.Mask" "B.Paste")
			(net "P52V_HS1_EN")
		)
		(pad "24" smd rect
			(at -3.400044 0.249936 270)
			(size 0.2794 0.762)
			(layers "B.Cu" "B.Mask" "B.Paste")
			(net "P52V_HS1_SIO")
		)
		(pad "25" smd rect
			(at -3.400044 -0.249936 270)
			(size 0.2794 0.762)
			(layers "B.Cu" "B.Mask" "B.Paste")
			(net "P52V_HS1_SCK")
		)
		(pad "26" smd rect
			(at -3.400044 -0.750062 270)
			(size 0.2794 0.762)
			(layers "B.Cu" "B.Mask" "B.Paste")
			(net "P52V_HS1_CS")
		)
		(pad "27" smd rect
			(at -3.400044 -1.249934 270)
			(size 0.2794 0.762)
			(layers "B.Cu" "B.Mask" "B.Paste")
			(net "SMB_P52V_PDB_SCL_R3")
		)
		(pad "28" smd rect
			(at -3.400044 -1.75006 270)
			(size 0.2794 0.762)
			(layers "B.Cu" "B.Mask" "B.Paste")
			(net "SMB_P52V_HS1_SDAI")
		)
		(pad "29" smd rect
			(at -3.400044 -2.249932 270)
			(size 0.2794 0.762)
			(layers "B.Cu" "B.Mask" "B.Paste")
			(net "SMB_P52V_HS1_SDAO")
		)
		(pad "30" smd rect
			(at -3.425444 -2.750058 270)
			(size 0.2794 0.7112)
			(layers "B.Cu" "B.Mask" "B.Paste")
			(net "Net_402")
		)
		(pad "31" smd rect
			(at -2.750058 -3.425444 180)
			(size 0.2794 0.7112)
			(layers "B.Cu" "B.Mask" "B.Paste")
			(net "Net_403")
		)
		(pad "32" smd rect
			(at -2.249932 -3.400044 180)
			(size 0.2794 0.762)
			(layers "B.Cu" "B.Mask" "B.Paste")
			(net "Net_404")
		)
		(pad "33" smd rect
			(at -1.75006 -3.400044 180)
			(size 0.2794 0.762)
			(layers "B.Cu" "B.Mask" "B.Paste")
			(net "GND_FIELD_SIGNAL")
		)
		(pad "34" smd rect
			(at -1.249934 -3.400044 180)
			(size 0.2794 0.762)
			(layers "B.Cu" "B.Mask" "B.Paste")
			(net "GND_FIELD_SIGNAL")
		)
		(pad "35" smd rect
			(at -0.750062 -3.400044 180)
			(size 0.2794 0.762)
			(layers "B.Cu" "B.Mask" "B.Paste")
			(net "P52V_HS1_TEMP")
		)
		(pad "36" smd rect
			(at -0.249936 -3.400044 180)
			(size 0.2794 0.762)
			(layers "B.Cu" "B.Mask" "B.Paste")
			(net "P52V_HS1_FLT")
		)
		(pad "37" smd rect
			(at 0.249936 -3.400044 180)
			(size 0.2794 0.762)
			(layers "B.Cu" "B.Mask" "B.Paste")
			(net "PWRGD_P52V_HS1_4287_PG_N")
		)
		(pad "38" smd rect
			(at 0.750062 -3.400044 180)
			(size 0.2794 0.762)
			(layers "B.Cu" "B.Mask" "B.Paste")
			(net "P52V_HS1_FB")
		)
		(pad "39" smd rect
			(at 2.750058 -3.425444 180)
			(size 0.2794 0.7112)
			(layers "B.Cu" "B.Mask" "B.Paste")
			(net "P52V_HS1_VDSFB")
		)
		(pad "40" smd circle
			(at -0.87503 0 180)
			(size 0 0)
			(layers "B.Cu" "B.Mask" "B.Paste")
			(net "GND_FIELD_SIGNAL")
		)
		(zone
			(layer "B.Cu")
			(hatch none 0.5)
			(connect_pads
				(clearance 0)
			)
			(min_thickness 0.25)
			(keepout
				(tracks not_allowed)
				(vias allowed)
				(pads allowed)
				(copperpour not_allowed)
				(footprints allowed)
			)
			(placement
				(enabled no)
				(sheetname "")
			)
			(fill
				(thermal_gap 0.5)
				(thermal_bridge_width 0.5)
				(island_removal_mode 0)
			)
			(polygon
				(pts
					(xy 296.490644 -72.54748) (xy 296.490644 -70.7644) (xy 294.5384 -70.7644) (xy 294.5384 -72.4916)
					(xy 294.1574 -72.8726) (xy 290.7538 -72.8726) (xy 290.7538 -67.3354) (xy 294.5384 -67.3354) (xy 294.5384 -70.739)
					(xy 296.490644 -70.739) (xy 296.490644 -67.65798) (xy 296.541444 -67.65798) (xy 296.541444 -67.084956)
					(xy 294.46982 -67.084956) (xy 294.46982 -67.135756) (xy 291.07638 -67.135756) (xy 291.07638 -67.084956)
					(xy 290.503356 -67.084956) (xy 290.503356 -67.65798) (xy 290.554156 -67.65798) (xy 290.554156 -72.55002)
					(xy 290.503356 -72.55002) (xy 290.503356 -73.123044) (xy 291.07638 -73.123044) (xy 291.07638 -73.072244)
					(xy 294.46982 -73.072244) (xy 294.46982 -73.123044) (xy 296.541444 -73.123044) (xy 296.541444 -72.54748)
				)
			)
		)
	)
	(footprint ""
		(layer "B.Cu")
		(at 260.6294 -53.975)
		(property "Reference" "R413"
			(at 0 0 0)
			(layer "B.SilkS")
			(hide yes)
			(effects
				(font
					(size 1.27 1.27)
				)
				(justify mirror)
			)
		)
		(property "Value" ""
			(at 0 0 0)
			(layer "B.Fab")
			(effects
				(font
					(size 1.27 1.27)
				)
				(justify mirror)
			)
		)
		(duplicate_pad_numbers_are_jumpers no)
		(fp_line
			(start -0.7874 -0.4064)
			(end -0.7874 0.4064)
			(stroke
				(width 0.1524)
				(type default)
			)
			(layer "B.SilkS")
		)
		(fp_line
			(start -0.7874 0.4064)
			(end 0.7874 0.4064)
			(stroke
				(width 0.1524)
				(type default)
			)
			(layer "B.SilkS")
		)
		(fp_line
			(start 0.7874 -0.4064)
			(end -0.7874 -0.4064)
			(stroke
				(width 0.1524)
				(type default)
			)
			(layer "B.SilkS")
		)
		(fp_line
			(start 0.7874 0.4064)
			(end 0.7874 -0.4064)
			(stroke
				(width 0.1524)
				(type default)
			)
			(layer "B.SilkS")
		)
		(fp_line
			(start -0.67945 -0.3048)
			(end -0.67945 0.3048)
			(stroke
				(width 0.1)
				(type default)
			)
			(layer "B.Fab")
		)
		(fp_line
			(start -0.67945 0.3048)
			(end -0.120396 0.3048)
			(stroke
				(width 0.1)
				(type default)
			)
			(layer "B.Fab")
		)
		(fp_line
			(start -0.12065 -0.3048)
			(end -0.67945 -0.3048)
			(stroke
				(width 0.1)
				(type default)
			)
			(layer "B.Fab")
		)
		(fp_line
			(start -0.12065 -0.2794)
			(end -0.12065 -0.3048)
			(stroke
				(width 0.1)
				(type default)
			)
			(layer "B.Fab")
		)
		(fp_line
			(start -0.120396 0.2794)
			(end 0.12065 0.2794)
			(stroke
				(width 0.1)
				(type default)
			)
			(layer "B.Fab")
		)
		(fp_line
			(start -0.120396 0.3048)
			(end -0.120396 0.2794)
			(stroke
				(width 0.1)
				(type default)
			)
			(layer "B.Fab")
		)
		(fp_line
			(start 0.12065 -0.305054)
			(end 0.12065 -0.2794)
			(stroke
				(width 0.1)
				(type default)
			)
			(layer "B.Fab")
		)
		(fp_line
			(start 0.12065 -0.2794)
			(end -0.12065 -0.2794)
			(stroke
				(width 0.1)
				(type default)
			)
			(layer "B.Fab")
		)
		(fp_line
			(start 0.12065 0.2794)
			(end 0.12065 0.3048)
			(stroke
				(width 0.1)
				(type default)
			)
			(layer "B.Fab")
		)
		(fp_line
			(start 0.12065 0.3048)
			(end 0.67945 0.3048)
			(stroke
				(width 0.1)
				(type default)
			)
			(layer "B.Fab")
		)
		(fp_line
			(start 0.67945 -0.305054)
			(end 0.12065 -0.305054)
			(stroke
				(width 0.1)
				(type default)
			)
			(layer "B.Fab")
		)
		(fp_line
			(start 0.67945 0.3048)
			(end 0.67945 -0.305054)
			(stroke
				(width 0.1)
				(type default)
			)
			(layer "B.Fab")
		)
		(pad "1" smd circle
			(at 0.40005 0 180)
			(size 0 0)
			(layers "B.Cu" "B.Mask" "B.Paste")
			(net "GPU_HSC1_BUF_EN")
		)
		(pad "2" smd circle
			(at -0.40005 0 180)
			(size 0 0)
			(layers "B.Cu" "B.Mask" "B.Paste")
			(net "FM_HS1_EN_FUSE")
		)
	)
	(footprint ""
		(layer "B.Cu")
		(at 341.4014 -51.9176)
		(property "Reference" "PC8"
			(at 0 0 0)
			(layer "B.SilkS")
			(hide yes)
			(effects
				(font
					(size 1.27 1.27)
				)
				(justify mirror)
			)
		)
		(property "Value" ""
			(at 0 0 0)
			(layer "B.Fab")
			(effects
				(font
					(size 1.27 1.27)
				)
				(justify mirror)
			)
		)
		(duplicate_pad_numbers_are_jumpers no)
		(fp_line
			(start -1.2954 -0.5842)
			(end -1.2954 0.5842)
			(stroke
				(width 0.1524)
				(type default)
			)
			(layer "B.SilkS")
		)
		(fp_line
			(start -1.2954 0.5842)
			(end 1.2954 0.5842)
			(stroke
				(width 0.1524)
				(type default)
			)
			(layer "B.SilkS")
		)
		(fp_line
			(start 1.2954 -0.5842)
			(end -1.2954 -0.5842)
			(stroke
				(width 0.1524)
				(type default)
			)
			(layer "B.SilkS")
		)
		(fp_line
			(start 1.2954 0.5842)
			(end 1.2954 -0.5842)
			(stroke
				(width 0.1524)
				(type default)
			)
			(layer "B.SilkS")
		)
		(fp_line
			(start -1.1938 -0.4064)
			(end -1.1938 0.4064)
			(stroke
				(width 0.1)
				(type default)
			)
			(layer "B.Fab")
		)
		(fp_line
			(start -1.1938 0.4064)
			(end -0.8636 0.4064)
			(stroke
				(width 0.1)
				(type default)
			)
			(layer "B.Fab")
		)
		(fp_line
			(start -0.8636 -0.4572)
			(end -0.8636 -0.4064)
			(stroke
				(width 0.1)
				(type default)
			)
			(layer "B.Fab")
		)
		(fp_line
			(start -0.8636 -0.4064)
			(end -1.1938 -0.4064)
			(stroke
				(width 0.1)
				(type default)
			)
			(layer "B.Fab")
		)
		(fp_line
			(start -0.8636 0.4064)
			(end -0.8636 0.4572)
			(stroke
				(width 0.1)
				(type default)
			)
			(layer "B.Fab")
		)
		(fp_line
			(start -0.8636 0.4572)
			(end 0.8636 0.4572)
			(stroke
				(width 0.1)
				(type default)
			)
			(layer "B.Fab")
		)
		(fp_line
			(start 0.8636 -0.4572)
			(end -0.8636 -0.4572)
			(stroke
				(width 0.1)
				(type default)
			)
			(layer "B.Fab")
		)
		(fp_line
			(start 0.8636 -0.4064)
			(end 0.8636 -0.4572)
			(stroke
				(width 0.1)
				(type default)
			)
			(layer "B.Fab")
		)
		(fp_line
			(start 0.8636 0.4064)
			(end 1.1938 0.4064)
			(stroke
				(width 0.1)
				(type default)
			)
			(layer "B.Fab")
		)
		(fp_line
			(start 0.8636 0.4572)
			(end 0.8636 0.4064)
			(stroke
				(width 0.1)
				(type default)
			)
			(layer "B.Fab")
		)
		(fp_line
			(start 1.1938 -0.4064)
			(end 0.8636 -0.4064)
			(stroke
				(width 0.1)
				(type default)
			)
			(layer "B.Fab")
		)
		(fp_line
			(start 1.1938 0.4064)
			(end 1.1938 -0.4064)
			(stroke
				(width 0.1)
				(type default)
			)
			(layer "B.Fab")
		)
		(pad "1" smd rect
			(at 0.7366 0 270)
			(size 0.7112 0.8128)
			(layers "B.Cu" "B.Mask" "B.Paste")
			(net "GND")
		)
		(pad "2" smd rect
			(at -0.7366 0 270)
			(size 0.7112 0.8128)
			(layers "B.Cu" "B.Mask" "B.Paste")
			(net "P52V_HS1_GATE_R1")
		)
	)
	(footprint ""
		(layer "B.Cu")
		(at 413.639 -37.084 180)
		(property "Reference" "R5934"
			(at 0 0 0)
			(layer "B.SilkS")
			(hide yes)
			(effects
				(font
					(size 1.27 1.27)
				)
				(justify mirror)
			)
		)
		(property "Value" ""
			(at 0 0 0)
			(layer "B.Fab")
			(effects
				(font
					(size 1.27 1.27)
				)
				(justify mirror)
			)
		)
		(duplicate_pad_numbers_are_jumpers no)
		(fp_line
			(start 0.7874 0.4064)
			(end 0.7874 -0.4064)
			(stroke
				(width 0.1524)
				(type default)
			)
			(layer "B.SilkS")
		)
		(fp_line
			(start 0.7874 -0.4064)
			(end -0.7874 -0.4064)
			(stroke
				(width 0.1524)
				(type default)
			)
			(layer "B.SilkS")
		)
		(fp_line
			(start -0.7874 0.4064)
			(end 0.7874 0.4064)
			(stroke
				(width 0.1524)
				(type default)
			)
			(layer "B.SilkS")
		)
		(fp_line
			(start -0.7874 -0.4064)
			(end -0.7874 0.4064)
			(stroke
				(width 0.1524)
				(type default)
			)
			(layer "B.SilkS")
		)
		(fp_line
			(start 0.67945 0.3048)
			(end 0.67945 -0.305054)
			(stroke
				(width 0.1)
				(type default)
			)
			(layer "B.Fab")
		)
		(fp_line
			(start 0.67945 -0.305054)
			(end 0.12065 -0.305054)
			(stroke
				(width 0.1)
				(type default)
			)
			(layer "B.Fab")
		)
		(fp_line
			(start 0.12065 0.3048)
			(end 0.67945 0.3048)
			(stroke
				(width 0.1)
				(type default)
			)
			(layer "B.Fab")
		)
		(fp_line
			(start 0.12065 0.2794)
			(end 0.12065 0.3048)
			(stroke
				(width 0.1)
				(type default)
			)
			(layer "B.Fab")
		)
		(fp_line
			(start 0.12065 -0.2794)
			(end -0.12065 -0.2794)
			(stroke
				(width 0.1)
				(type default)
			)
			(layer "B.Fab")
		)
		(fp_line
			(start 0.12065 -0.305054)
			(end 0.12065 -0.2794)
			(stroke
				(width 0.1)
				(type default)
			)
			(layer "B.Fab")
		)
		(fp_line
			(start -0.120396 0.3048)
			(end -0.120396 0.2794)
			(stroke
				(width 0.1)
				(type default)
			)
			(layer "B.Fab")
		)
		(fp_line
			(start -0.120396 0.2794)
			(end 0.12065 0.2794)
			(stroke
				(width 0.1)
				(type default)
			)
			(layer "B.Fab")
		)
		(fp_line
			(start -0.12065 -0.2794)
			(end -0.12065 -0.3048)
			(stroke
				(width 0.1)
				(type default)
			)
			(layer "B.Fab")
		)
		(fp_line
			(start -0.12065 -0.3048)
			(end -0.67945 -0.3048)
			(stroke
				(width 0.1)
				(type default)
			)
			(layer "B.Fab")
		)
		(fp_line
			(start -0.67945 0.3048)
			(end -0.120396 0.3048)
			(stroke
				(width 0.1)
				(type default)
			)
			(layer "B.Fab")
		)
		(fp_line
			(start -0.67945 -0.3048)
			(end -0.67945 0.3048)
			(stroke
				(width 0.1)
				(type default)
			)
			(layer "B.Fab")
		)
		(pad "1" smd circle
			(at 0.40005 0)
			(size 0 0)
			(layers "B.Cu" "B.Mask" "B.Paste")
			(net "P3V3_AUX")
		)
		(pad "2" smd circle
			(at -0.40005 0)
			(size 0 0)
			(layers "B.Cu" "B.Mask" "B.Paste")
			(net "PCA9555_2_A2")
		)
	)
	(footprint ""
		(layer "B.Cu")
		(at 343.535 -49.276 180)
		(property "Reference" "PC584"
			(at 0 0 0)
			(layer "B.SilkS")
			(hide yes)
			(effects
				(font
					(size 1.27 1.27)
				)
				(justify mirror)
			)
		)
		(property "Value" ""
			(at 0 0 0)
			(layer "B.Fab")
			(effects
				(font
					(size 1.27 1.27)
				)
				(justify mirror)
			)
		)
		(duplicate_pad_numbers_are_jumpers no)
		(fp_line
			(start 1.2954 0.5842)
			(end 1.2954 -0.5842)
			(stroke
				(width 0.1524)
				(type default)
			)
			(layer "B.SilkS")
		)
		(fp_line
			(start 1.2954 -0.5842)
			(end -1.2954 -0.5842)
			(stroke
				(width 0.1524)
				(type default)
			)
			(layer "B.SilkS")
		)
		(fp_line
			(start -1.2954 0.5842)
			(end 1.2954 0.5842)
			(stroke
				(width 0.1524)
				(type default)
			)
			(layer "B.SilkS")
		)
		(fp_line
			(start -1.2954 -0.5842)
			(end -1.2954 0.5842)
			(stroke
				(width 0.1524)
				(type default)
			)
			(layer "B.SilkS")
		)
		(fp_line
			(start 1.1938 0.4064)
			(end 1.1938 -0.4064)
			(stroke
				(width 0.1)
				(type default)
			)
			(layer "B.Fab")
		)
		(fp_line
			(start 1.1938 -0.4064)
			(end 0.8636 -0.4064)
			(stroke
				(width 0.1)
				(type default)
			)
			(layer "B.Fab")
		)
		(fp_line
			(start 0.8636 0.4572)
			(end 0.8636 0.4064)
			(stroke
				(width 0.1)
				(type default)
			)
			(layer "B.Fab")
		)
		(fp_line
			(start 0.8636 0.4064)
			(end 1.1938 0.4064)
			(stroke
				(width 0.1)
				(type default)
			)
			(layer "B.Fab")
		)
		(fp_line
			(start 0.8636 -0.4064)
			(end 0.8636 -0.4572)
			(stroke
				(width 0.1)
				(type default)
			)
			(layer "B.Fab")
		)
		(fp_line
			(start 0.8636 -0.4572)
			(end -0.8636 -0.4572)
			(stroke
				(width 0.1)
				(type default)
			)
			(layer "B.Fab")
		)
		(fp_line
			(start -0.8636 0.4572)
			(end 0.8636 0.4572)
			(stroke
				(width 0.1)
				(type default)
			)
			(layer "B.Fab")
		)
		(fp_line
			(start -0.8636 0.4064)
			(end -0.8636 0.4572)
			(stroke
				(width 0.1)
				(type default)
			)
			(layer "B.Fab")
		)
		(fp_line
			(start -0.8636 -0.4064)
			(end -1.1938 -0.4064)
			(stroke
				(width 0.1)
				(type default)
			)
			(layer "B.Fab")
		)
		(fp_line
			(start -0.8636 -0.4572)
			(end -0.8636 -0.4064)
			(stroke
				(width 0.1)
				(type default)
			)
			(layer "B.Fab")
		)
		(fp_line
			(start -1.1938 0.4064)
			(end -0.8636 0.4064)
			(stroke
				(width 0.1)
				(type default)
			)
			(layer "B.Fab")
		)
		(fp_line
			(start -1.1938 -0.4064)
			(end -1.1938 0.4064)
			(stroke
				(width 0.1)
				(type default)
			)
			(layer "B.Fab")
		)
		(pad "1" smd rect
			(at 0.7366 0 90)
			(size 0.7112 0.8128)
			(layers "B.Cu" "B.Mask" "B.Paste")
			(net "P52V_HS1_GATE_RC")
		)
		(pad "2" smd rect
			(at -0.7366 0 90)
			(size 0.7112 0.8128)
			(layers "B.Cu" "B.Mask" "B.Paste")
			(net "P52V_HS1")
		)
	)
	(footprint ""
		(layer "B.Cu")
		(at 111.2774 -44.3484 -90)
		(property "Reference" "R5867"
			(at 0 0 90)
			(layer "B.SilkS")
			(hide yes)
			(effects
				(font
					(size 1.27 1.27)
				)
				(justify mirror)
			)
		)
		(property "Value" ""
			(at 0 0 90)
			(layer "B.Fab")
			(effects
				(font
					(size 1.27 1.27)
				)
				(justify mirror)
			)
		)
		(duplicate_pad_numbers_are_jumpers no)
		(fp_line
			(start -0.7874 0.4064)
			(end 0.7874 0.4064)
			(stroke
				(width 0.1524)
				(type default)
			)
			(layer "B.SilkS")
		)
		(fp_line
			(start 0.7874 0.4064)
			(end 0.7874 -0.4064)
			(stroke
				(width 0.1524)
				(type default)
			)
			(layer "B.SilkS")
		)
		(fp_line
			(start -0.7874 -0.4064)
			(end -0.7874 0.4064)
			(stroke
				(width 0.1524)
				(type default)
			)
			(layer "B.SilkS")
		)
		(fp_line
			(start 0.7874 -0.4064)
			(end -0.7874 -0.4064)
			(stroke
				(width 0.1524)
				(type default)
			)
			(layer "B.SilkS")
		)
		(fp_line
			(start -0.67945 0.3048)
			(end -0.120396 0.3048)
			(stroke
				(width 0.1)
				(type default)
			)
			(layer "B.Fab")
		)
		(fp_line
			(start -0.120396 0.3048)
			(end -0.120396 0.2794)
			(stroke
				(width 0.1)
				(type default)
			)
			(layer "B.Fab")
		)
		(fp_line
			(start 0.12065 0.3048)
			(end 0.67945 0.3048)
			(stroke
				(width 0.1)
				(type default)
			)
			(layer "B.Fab")
		)
		(fp_line
			(start 0.67945 0.3048)
			(end 0.67945 -0.305054)
			(stroke
				(width 0.1)
				(type default)
			)
			(layer "B.Fab")
		)
		(fp_line
			(start -0.120396 0.2794)
			(end 0.12065 0.2794)
			(stroke
				(width 0.1)
				(type default)
			)
			(layer "B.Fab")
		)
		(fp_line
			(start 0.12065 0.2794)
			(end 0.12065 0.3048)
			(stroke
				(width 0.1)
				(type default)
			)
			(layer "B.Fab")
		)
		(fp_line
			(start -0.12065 -0.2794)
			(end -0.12065 -0.3048)
			(stroke
				(width 0.1)
				(type default)
			)
			(layer "B.Fab")
		)
		(fp_line
			(start 0.12065 -0.2794)
			(end -0.12065 -0.2794)
			(stroke
				(width 0.1)
				(type default)
			)
			(layer "B.Fab")
		)
		(fp_line
			(start -0.67945 -0.3048)
			(end -0.67945 0.3048)
			(stroke
				(width 0.1)
				(type default)
			)
			(layer "B.Fab")
		)
		(fp_line
			(start -0.12065 -0.3048)
			(end -0.67945 -0.3048)
			(stroke
				(width 0.1)
				(type default)
			)
			(layer "B.Fab")
		)
		(fp_line
			(start 0.12065 -0.305054)
			(end 0.12065 -0.2794)
			(stroke
				(width 0.1)
				(type default)
			)
			(layer "B.Fab")
		)
		(fp_line
			(start 0.67945 -0.305054)
			(end 0.12065 -0.305054)
			(stroke
				(width 0.1)
				(type default)
			)
			(layer "B.Fab")
		)
		(pad "1" smd circle
			(at 0.40005 0 90)
			(size 0 0)
			(layers "B.Cu" "B.Mask" "B.Paste")
			(net "P52V_HS2_1272_GATE")
		)
		(pad "2" smd circle
			(at -0.40005 0 90)
			(size 0 0)
			(layers "B.Cu" "B.Mask" "B.Paste")
			(net "P52V_HS2_GATE2_R")
		)
	)
	(footprint ""
		(layer "B.Cu")
		(at 285.369 -92.075 180)
		(property "Reference" "U34"
			(at -5.1435 -1.56337 0)
			(unlocked yes)
			(layer "B.SilkS")
			(effects
				(font
					(size 0.7874 0.5842)
					(thickness 0.1524)
				)
				(justify left mirror)
			)
		)
		(property "Value" ""
			(at 0 0 0)
			(layer "B.Fab")
			(effects
				(font
					(size 1.27 1.27)
				)
				(justify mirror)
			)
		)
		(duplicate_pad_numbers_are_jumpers no)
		(fp_line
			(start 1.733296 1.549908)
			(end -1.733296 1.549908)
			(stroke
				(width 0.1524)
				(type default)
			)
			(layer "B.SilkS")
		)
		(fp_line
			(start 1.733296 -1.549908)
			(end 1.733296 1.549908)
			(stroke
				(width 0.1524)
				(type default)
			)
			(layer "B.SilkS")
		)
		(fp_line
			(start 0.660908 -1.549908)
			(end 1.733296 -1.549908)
			(stroke
				(width 0.1524)
				(type default)
			)
			(layer "B.SilkS")
		)
		(fp_line
			(start 0 -0.889)
			(end 0.660908 -1.549908)
			(stroke
				(width 0.1524)
				(type default)
			)
			(layer "B.SilkS")
		)
		(fp_line
			(start -0.660908 -1.549908)
			(end 0 -0.889)
			(stroke
				(width 0.1524)
				(type default)
			)
			(layer "B.SilkS")
		)
		(fp_line
			(start -1.733296 1.549908)
			(end -1.733296 -1.549908)
			(stroke
				(width 0.1524)
				(type default)
			)
			(layer "B.SilkS")
		)
		(fp_line
			(start -1.733296 -1.549908)
			(end -0.660908 -1.549908)
			(stroke
				(width 0.1524)
				(type default)
			)
			(layer "B.SilkS")
		)
		(fp_poly
			(pts
				(xy 1.016 -2.286) (xy 1.524 -2.286) (xy 1.27 -1.778)
			)
			(stroke
				(width 0)
				(type default)
			)
			(fill yes)
			(layer "B.SilkS")
		)
		(fp_line
			(start 0.849884 1.549908)
			(end -0.849884 1.549908)
			(stroke
				(width 0.1)
				(type default)
			)
			(layer "B.Fab")
		)
		(fp_line
			(start 0.849884 -1.549908)
			(end 0.849884 1.549908)
			(stroke
				(width 0.1)
				(type default)
			)
			(layer "B.Fab")
		)
		(fp_line
			(start -0.849884 1.549908)
			(end -0.849884 -1.549908)
			(stroke
				(width 0.1)
				(type default)
			)
			(layer "B.Fab")
		)
		(fp_line
			(start -0.849884 -1.549908)
			(end 0.849884 -1.549908)
			(stroke
				(width 0.1)
				(type default)
			)
			(layer "B.Fab")
		)
		(fp_poly
			(pts
				(xy 2.4384 -1.20396) (xy 2.4384 -0.69596) (xy 1.9304 -0.94996)
			)
			(stroke
				(width 0)
				(type default)
			)
			(fill yes)
			(layer "B.Fab")
		)
		(pad "1" smd rect
			(at 1.199896 -0.94996 90)
			(size 0.5588 0.8128)
			(layers "B.Cu" "B.Mask" "B.Paste")
			(net "FM_HS1_EN_BUSBAR")
		)
		(pad "2" smd rect
			(at 1.199896 0 90)
			(size 0.5588 0.8128)
			(layers "B.Cu" "B.Mask" "B.Paste")
			(net "FM_HS1_EN_FUSE")
		)
		(pad "3" smd rect
			(at 1.199896 0.94996 90)
			(size 0.5588 0.8128)
			(layers "B.Cu" "B.Mask" "B.Paste")
			(net "GND")
		)
		(pad "4" smd rect
			(at -1.199896 0.94996 90)
			(size 0.5588 0.8128)
			(layers "B.Cu" "B.Mask" "B.Paste")
			(net "P52V_HS1_EN")
		)
		(pad "5" smd rect
			(at -1.199896 -0.94996 90)
			(size 0.5588 0.8128)
			(layers "B.Cu" "B.Mask" "B.Paste")
			(net "P3V3_AND")
		)
	)
	(footprint ""
		(layer "B.Cu")
		(at 285.9024 -73.025 180)
		(property "Reference" "R5855"
			(at 0 0 0)
			(layer "B.SilkS")
			(hide yes)
			(effects
				(font
					(size 1.27 1.27)
				)
				(justify mirror)
			)
		)
		(property "Value" ""
			(at 0 0 0)
			(layer "B.Fab")
			(effects
				(font
					(size 1.27 1.27)
				)
				(justify mirror)
			)
		)
		(duplicate_pad_numbers_are_jumpers no)
		(fp_line
			(start 0.7874 0.4064)
			(end 0.7874 -0.4064)
			(stroke
				(width 0.1524)
				(type default)
			)
			(layer "B.SilkS")
		)
		(fp_line
			(start 0.7874 -0.4064)
			(end -0.7874 -0.4064)
			(stroke
				(width 0.1524)
				(type default)
			)
			(layer "B.SilkS")
		)
		(fp_line
			(start -0.7874 0.4064)
			(end 0.7874 0.4064)
			(stroke
				(width 0.1524)
				(type default)
			)
			(layer "B.SilkS")
		)
		(fp_line
			(start -0.7874 -0.4064)
			(end -0.7874 0.4064)
			(stroke
				(width 0.1524)
				(type default)
			)
			(layer "B.SilkS")
		)
		(fp_line
			(start 0.67945 0.3048)
			(end 0.67945 -0.305054)
			(stroke
				(width 0.1)
				(type default)
			)
			(layer "B.Fab")
		)
		(fp_line
			(start 0.67945 -0.305054)
			(end 0.12065 -0.305054)
			(stroke
				(width 0.1)
				(type default)
			)
			(layer "B.Fab")
		)
		(fp_line
			(start 0.12065 0.3048)
			(end 0.67945 0.3048)
			(stroke
				(width 0.1)
				(type default)
			)
			(layer "B.Fab")
		)
		(fp_line
			(start 0.12065 0.2794)
			(end 0.12065 0.3048)
			(stroke
				(width 0.1)
				(type default)
			)
			(layer "B.Fab")
		)
		(fp_line
			(start 0.12065 -0.2794)
			(end -0.12065 -0.2794)
			(stroke
				(width 0.1)
				(type default)
			)
			(layer "B.Fab")
		)
		(fp_line
			(start 0.12065 -0.305054)
			(end 0.12065 -0.2794)
			(stroke
				(width 0.1)
				(type default)
			)
			(layer "B.Fab")
		)
		(fp_line
			(start -0.120396 0.3048)
			(end -0.120396 0.2794)
			(stroke
				(width 0.1)
				(type default)
			)
			(layer "B.Fab")
		)
		(fp_line
			(start -0.120396 0.2794)
			(end 0.12065 0.2794)
			(stroke
				(width 0.1)
				(type default)
			)
			(layer "B.Fab")
		)
		(fp_line
			(start -0.12065 -0.2794)
			(end -0.12065 -0.3048)
			(stroke
				(width 0.1)
				(type default)
			)
			(layer "B.Fab")
		)
		(fp_line
			(start -0.12065 -0.3048)
			(end -0.67945 -0.3048)
			(stroke
				(width 0.1)
				(type default)
			)
			(layer "B.Fab")
		)
		(fp_line
			(start -0.67945 0.3048)
			(end -0.120396 0.3048)
			(stroke
				(width 0.1)
				(type default)
			)
			(layer "B.Fab")
		)
		(fp_line
			(start -0.67945 -0.3048)
			(end -0.67945 0.3048)
			(stroke
				(width 0.1)
				(type default)
			)
			(layer "B.Fab")
		)
		(pad "1" smd circle
			(at 0.40005 0)
			(size 0 0)
			(layers "B.Cu" "B.Mask" "B.Paste")
			(net "SMB_P52V_PDB_SDA")
		)
		(pad "2" smd circle
			(at -0.40005 0)
			(size 0 0)
			(layers "B.Cu" "B.Mask" "B.Paste")
			(net "SMB_P52V_HS1_SDAI")
		)
	)
	(footprint ""
		(layer "B.Cu")
		(at 287.9344 -78.486)
		(property "Reference" "U31"
			(at 3.50393 -1.905 270)
			(unlocked yes)
			(layer "B.SilkS")
			(effects
				(font
					(size 0.7874 0.5842)
					(thickness 0.1524)
				)
				(justify left mirror)
			)
		)
		(property "Value" ""
			(at 0 0 0)
			(layer "B.Fab")
			(effects
				(font
					(size 1.27 1.27)
				)
				(justify mirror)
			)
		)
		(duplicate_pad_numbers_are_jumpers no)
		(fp_line
			(start -2.249932 -1.549908)
			(end -0.737108 -1.549908)
			(stroke
				(width 0.1524)
				(type default)
			)
			(layer "B.SilkS")
		)
		(fp_line
			(start -2.249932 1.549908)
			(end -2.249932 -1.549908)
			(stroke
				(width 0.1524)
				(type default)
			)
			(layer "B.SilkS")
		)
		(fp_line
			(start -0.737108 -1.549908)
			(end 0 -0.8128)
			(stroke
				(width 0.1524)
				(type default)
			)
			(layer "B.SilkS")
		)
		(fp_line
			(start 0 -0.8128)
			(end 0.737108 -1.549908)
			(stroke
				(width 0.1524)
				(type default)
			)
			(layer "B.SilkS")
		)
		(fp_line
			(start 0.737108 -1.549908)
			(end 2.249932 -1.549908)
			(stroke
				(width 0.1524)
				(type default)
			)
			(layer "B.SilkS")
		)
		(fp_line
			(start 2.249932 -1.549908)
			(end 2.249932 1.549908)
			(stroke
				(width 0.1524)
				(type default)
			)
			(layer "B.SilkS")
		)
		(fp_line
			(start 2.249932 1.549908)
			(end -2.249932 1.549908)
			(stroke
				(width 0.1524)
				(type default)
			)
			(layer "B.SilkS")
		)
		(fp_poly
			(pts
				(xy 4.7498 -0.467106) (xy 4.7498 -1.483106) (xy 3.7338 -0.975106)
			)
			(stroke
				(width 0)
				(type default)
			)
			(fill yes)
			(layer "B.SilkS")
		)
		(fp_line
			(start -2.249932 -1.549908)
			(end 2.249932 -1.549908)
			(stroke
				(width 0.1)
				(type default)
			)
			(layer "B.Fab")
		)
		(fp_line
			(start -2.249932 1.549908)
			(end -2.249932 -1.549908)
			(stroke
				(width 0.1)
				(type default)
			)
			(layer "B.Fab")
		)
		(fp_line
			(start 2.249932 -1.549908)
			(end 2.249932 1.549908)
			(stroke
				(width 0.1)
				(type default)
			)
			(layer "B.Fab")
		)
		(fp_line
			(start 2.249932 1.549908)
			(end -2.249932 1.549908)
			(stroke
				(width 0.1)
				(type default)
			)
			(layer "B.Fab")
		)
		(fp_poly
			(pts
				(xy 4.7498 -0.467106) (xy 4.7498 -1.483106) (xy 3.7338 -0.975106)
			)
			(stroke
				(width 0)
				(type default)
			)
			(fill yes)
			(layer "B.Fab")
		)
		(pad "1" smd rect
			(at 3.052572 -0.975106 270)
			(size 0.381 1.1684)
			(layers "B.Cu" "B.Mask" "B.Paste")
			(net "P52V_HS1_CS")
		)
		(pad "2" smd rect
			(at 3.052572 -0.32512 270)
			(size 0.381 1.1684)
			(layers "B.Cu" "B.Mask" "B.Paste")
			(net "P52V_HS1_SIO")
		)
		(pad "3" smd rect
			(at 3.052572 0.32512 270)
			(size 0.381 1.1684)
			(layers "B.Cu" "B.Mask" "B.Paste")
			(net "P52V_HS1_DVCC")
		)
		(pad "4" smd rect
			(at 3.052572 0.975106 270)
			(size 0.381 1.1684)
			(layers "B.Cu" "B.Mask" "B.Paste")
			(net "GND")
		)
		(pad "5" smd rect
			(at -3.052572 0.975106 270)
			(size 0.381 1.1684)
			(layers "B.Cu" "B.Mask" "B.Paste")
			(net "P52V_HS1_SIO")
		)
		(pad "6" smd rect
			(at -3.052572 0.32512 270)
			(size 0.381 1.1684)
			(layers "B.Cu" "B.Mask" "B.Paste")
			(net "P52V_HS1_SCK")
		)
		(pad "7" smd rect
			(at -3.052572 -0.32512 270)
			(size 0.381 1.1684)
			(layers "B.Cu" "B.Mask" "B.Paste")
			(net "P52V_HS1_DVCC")
		)
		(pad "8" smd rect
			(at -3.052572 -0.975106 270)
			(size 0.381 1.1684)
			(layers "B.Cu" "B.Mask" "B.Paste")
			(net "P52V_HS1_DVCC")
		)
	)
	(footprint ""
		(layer "B.Cu")
		(at 293.2684 -76.454 -90)
		(property "Reference" "PC6"
			(at 0 0 90)
			(layer "B.SilkS")
			(hide yes)
			(effects
				(font
					(size 1.27 1.27)
				)
				(justify mirror)
			)
		)
		(property "Value" ""
			(at 0 0 90)
			(layer "B.Fab")
			(effects
				(font
					(size 1.27 1.27)
				)
				(justify mirror)
			)
		)
		(duplicate_pad_numbers_are_jumpers no)
		(fp_line
			(start -0.7874 0.4064)
			(end 0.7874 0.4064)
			(stroke
				(width 0.1524)
				(type default)
			)
			(layer "B.SilkS")
		)
		(fp_line
			(start 0.7874 0.4064)
			(end 0.7874 -0.4064)
			(stroke
				(width 0.1524)
				(type default)
			)
			(layer "B.SilkS")
		)
		(fp_line
			(start -0.7874 -0.4064)
			(end -0.7874 0.4064)
			(stroke
				(width 0.1524)
				(type default)
			)
			(layer "B.SilkS")
		)
		(fp_line
			(start 0.7874 -0.4064)
			(end -0.7874 -0.4064)
			(stroke
				(width 0.1524)
				(type default)
			)
			(layer "B.SilkS")
		)
		(fp_line
			(start -0.67945 0.3048)
			(end -0.120396 0.3048)
			(stroke
				(width 0.1)
				(type default)
			)
			(layer "B.Fab")
		)
		(fp_line
			(start -0.120396 0.3048)
			(end -0.120396 0.2794)
			(stroke
				(width 0.1)
				(type default)
			)
			(layer "B.Fab")
		)
		(fp_line
			(start 0.12065 0.3048)
			(end 0.67945 0.3048)
			(stroke
				(width 0.1)
				(type default)
			)
			(layer "B.Fab")
		)
		(fp_line
			(start 0.67945 0.3048)
			(end 0.67945 -0.305054)
			(stroke
				(width 0.1)
				(type default)
			)
			(layer "B.Fab")
		)
		(fp_line
			(start -0.120396 0.2794)
			(end 0.12065 0.2794)
			(stroke
				(width 0.1)
				(type default)
			)
			(layer "B.Fab")
		)
		(fp_line
			(start 0.12065 0.2794)
			(end 0.12065 0.3048)
			(stroke
				(width 0.1)
				(type default)
			)
			(layer "B.Fab")
		)
		(fp_line
			(start -0.12065 -0.2794)
			(end -0.12065 -0.3048)
			(stroke
				(width 0.1)
				(type default)
			)
			(layer "B.Fab")
		)
		(fp_line
			(start 0.12065 -0.2794)
			(end -0.12065 -0.2794)
			(stroke
				(width 0.1)
				(type default)
			)
			(layer "B.Fab")
		)
		(fp_line
			(start -0.67945 -0.3048)
			(end -0.67945 0.3048)
			(stroke
				(width 0.1)
				(type default)
			)
			(layer "B.Fab")
		)
		(fp_line
			(start -0.12065 -0.3048)
			(end -0.67945 -0.3048)
			(stroke
				(width 0.1)
				(type default)
			)
			(layer "B.Fab")
		)
		(fp_line
			(start 0.12065 -0.305054)
			(end 0.12065 -0.2794)
			(stroke
				(width 0.1)
				(type default)
			)
			(layer "B.Fab")
		)
		(fp_line
			(start 0.67945 -0.305054)
			(end 0.12065 -0.305054)
			(stroke
				(width 0.1)
				(type default)
			)
			(layer "B.Fab")
		)
		(pad "1" smd circle
			(at 0.40005 0 90)
			(size 0 0)
			(layers "B.Cu" "B.Mask" "B.Paste")
			(net "P52V_HS1_TEMP")
		)
		(pad "2" smd circle
			(at -0.40005 0 90)
			(size 0 0)
			(layers "B.Cu" "B.Mask" "B.Paste")
			(net "GND_FIELD_SIGNAL")
		)
	)
	(footprint ""
		(layer "B.Cu")
		(at 285.9024 -66.929 180)
		(property "Reference" "PR11"
			(at 0 0 0)
			(layer "B.SilkS")
			(hide yes)
			(effects
				(font
					(size 1.27 1.27)
				)
				(justify mirror)
			)
		)
		(property "Value" ""
			(at 0 0 0)
			(layer "B.Fab")
			(effects
				(font
					(size 1.27 1.27)
				)
				(justify mirror)
			)
		)
		(duplicate_pad_numbers_are_jumpers no)
		(fp_line
			(start 0.7874 0.4064)
			(end 0.7874 -0.4064)
			(stroke
				(width 0.1524)
				(type default)
			)
			(layer "B.SilkS")
		)
		(fp_line
			(start 0.7874 -0.4064)
			(end -0.7874 -0.4064)
			(stroke
				(width 0.1524)
				(type default)
			)
			(layer "B.SilkS")
		)
		(fp_line
			(start -0.7874 0.4064)
			(end 0.7874 0.4064)
			(stroke
				(width 0.1524)
				(type default)
			)
			(layer "B.SilkS")
		)
		(fp_line
			(start -0.7874 -0.4064)
			(end -0.7874 0.4064)
			(stroke
				(width 0.1524)
				(type default)
			)
			(layer "B.SilkS")
		)
		(fp_line
			(start 0.67945 0.3048)
			(end 0.67945 -0.305054)
			(stroke
				(width 0.1)
				(type default)
			)
			(layer "B.Fab")
		)
		(fp_line
			(start 0.67945 -0.305054)
			(end 0.12065 -0.305054)
			(stroke
				(width 0.1)
				(type default)
			)
			(layer "B.Fab")
		)
		(fp_line
			(start 0.12065 0.3048)
			(end 0.67945 0.3048)
			(stroke
				(width 0.1)
				(type default)
			)
			(layer "B.Fab")
		)
		(fp_line
			(start 0.12065 0.2794)
			(end 0.12065 0.3048)
			(stroke
				(width 0.1)
				(type default)
			)
			(layer "B.Fab")
		)
		(fp_line
			(start 0.12065 -0.2794)
			(end -0.12065 -0.2794)
			(stroke
				(width 0.1)
				(type default)
			)
			(layer "B.Fab")
		)
		(fp_line
			(start 0.12065 -0.305054)
			(end 0.12065 -0.2794)
			(stroke
				(width 0.1)
				(type default)
			)
			(layer "B.Fab")
		)
		(fp_line
			(start -0.120396 0.3048)
			(end -0.120396 0.2794)
			(stroke
				(width 0.1)
				(type default)
			)
			(layer "B.Fab")
		)
		(fp_line
			(start -0.120396 0.2794)
			(end 0.12065 0.2794)
			(stroke
				(width 0.1)
				(type default)
			)
			(layer "B.Fab")
		)
		(fp_line
			(start -0.12065 -0.2794)
			(end -0.12065 -0.3048)
			(stroke
				(width 0.1)
				(type default)
			)
			(layer "B.Fab")
		)
		(fp_line
			(start -0.12065 -0.3048)
			(end -0.67945 -0.3048)
			(stroke
				(width 0.1)
				(type default)
			)
			(layer "B.Fab")
		)
		(fp_line
			(start -0.67945 0.3048)
			(end -0.120396 0.3048)
			(stroke
				(width 0.1)
				(type default)
			)
			(layer "B.Fab")
		)
		(fp_line
			(start -0.67945 -0.3048)
			(end -0.67945 0.3048)
			(stroke
				(width 0.1)
				(type default)
			)
			(layer "B.Fab")
		)
		(pad "1" smd circle
			(at 0.40005 0)
			(size 0 0)
			(layers "B.Cu" "B.Mask" "B.Paste")
			(net "GND_FIELD_SIGNAL")
		)
		(pad "2" smd circle
			(at -0.40005 0)
			(size 0 0)
			(layers "B.Cu" "B.Mask" "B.Paste")
			(net "P52V_HS1_CLKIN")
		)
	)
	(footprint ""
		(layer "B.Cu")
		(at 158.034736 -77.216 -90)
		(property "Reference" "PR7016"
			(at 0 0 90)
			(layer "B.SilkS")
			(hide yes)
			(effects
				(font
					(size 1.27 1.27)
				)
				(justify mirror)
			)
		)
		(property "Value" ""
			(at 0 0 90)
			(layer "B.Fab")
			(effects
				(font
					(size 1.27 1.27)
				)
				(justify mirror)
			)
		)
		(duplicate_pad_numbers_are_jumpers no)
		(fp_line
			(start -0.7874 0.4064)
			(end 0.7874 0.4064)
			(stroke
				(width 0.1524)
				(type default)
			)
			(layer "B.SilkS")
		)
		(fp_line
			(start 0.7874 0.4064)
			(end 0.7874 -0.4064)
			(stroke
				(width 0.1524)
				(type default)
			)
			(layer "B.SilkS")
		)
		(fp_line
			(start -0.7874 -0.4064)
			(end -0.7874 0.4064)
			(stroke
				(width 0.1524)
				(type default)
			)
			(layer "B.SilkS")
		)
		(fp_line
			(start 0.7874 -0.4064)
			(end -0.7874 -0.4064)
			(stroke
				(width 0.1524)
				(type default)
			)
			(layer "B.SilkS")
		)
		(fp_line
			(start -0.67945 0.3048)
			(end -0.120396 0.3048)
			(stroke
				(width 0.1)
				(type default)
			)
			(layer "B.Fab")
		)
		(fp_line
			(start -0.120396 0.3048)
			(end -0.120396 0.2794)
			(stroke
				(width 0.1)
				(type default)
			)
			(layer "B.Fab")
		)
		(fp_line
			(start 0.12065 0.3048)
			(end 0.67945 0.3048)
			(stroke
				(width 0.1)
				(type default)
			)
			(layer "B.Fab")
		)
		(fp_line
			(start 0.67945 0.3048)
			(end 0.67945 -0.305054)
			(stroke
				(width 0.1)
				(type default)
			)
			(layer "B.Fab")
		)
		(fp_line
			(start -0.120396 0.2794)
			(end 0.12065 0.2794)
			(stroke
				(width 0.1)
				(type default)
			)
			(layer "B.Fab")
		)
		(fp_line
			(start 0.12065 0.2794)
			(end 0.12065 0.3048)
			(stroke
				(width 0.1)
				(type default)
			)
			(layer "B.Fab")
		)
		(fp_line
			(start -0.12065 -0.2794)
			(end -0.12065 -0.3048)
			(stroke
				(width 0.1)
				(type default)
			)
			(layer "B.Fab")
		)
		(fp_line
			(start 0.12065 -0.2794)
			(end -0.12065 -0.2794)
			(stroke
				(width 0.1)
				(type default)
			)
			(layer "B.Fab")
		)
		(fp_line
			(start -0.67945 -0.3048)
			(end -0.67945 0.3048)
			(stroke
				(width 0.1)
				(type default)
			)
			(layer "B.Fab")
		)
		(fp_line
			(start -0.12065 -0.3048)
			(end -0.67945 -0.3048)
			(stroke
				(width 0.1)
				(type default)
			)
			(layer "B.Fab")
		)
		(fp_line
			(start 0.12065 -0.305054)
			(end 0.12065 -0.2794)
			(stroke
				(width 0.1)
				(type default)
			)
			(layer "B.Fab")
		)
		(fp_line
			(start 0.67945 -0.305054)
			(end 0.12065 -0.305054)
			(stroke
				(width 0.1)
				(type default)
			)
			(layer "B.Fab")
		)
		(pad "1" smd circle
			(at 0.40005 0 90)
			(size 0 0)
			(layers "B.Cu" "B.Mask" "B.Paste")
			(net "P52V_HS2_MODE")
		)
		(pad "2" smd circle
			(at -0.40005 0 90)
			(size 0 0)
			(layers "B.Cu" "B.Mask" "B.Paste")
			(net "P52V_HS2_INTVCC")
		)
	)
	(footprint ""
		(layer "B.Cu")
		(at 295.402 -87.884 90)
		(property "Reference" "R5942"
			(at 0 0 90)
			(layer "B.SilkS")
			(hide yes)
			(effects
				(font
					(size 1.27 1.27)
				)
				(justify mirror)
			)
		)
		(property "Value" ""
			(at 0 0 90)
			(layer "B.Fab")
			(effects
				(font
					(size 1.27 1.27)
				)
				(justify mirror)
			)
		)
		(duplicate_pad_numbers_are_jumpers no)
		(fp_line
			(start 0.7874 -0.4064)
			(end -0.7874 -0.4064)
			(stroke
				(width 0.1524)
				(type default)
			)
			(layer "B.SilkS")
		)
		(fp_line
			(start -0.7874 -0.4064)
			(end -0.7874 0.4064)
			(stroke
				(width 0.1524)
				(type default)
			)
			(layer "B.SilkS")
		)
		(fp_line
			(start 0.7874 0.4064)
			(end 0.7874 -0.4064)
			(stroke
				(width 0.1524)
				(type default)
			)
			(layer "B.SilkS")
		)
		(fp_line
			(start -0.7874 0.4064)
			(end 0.7874 0.4064)
			(stroke
				(width 0.1524)
				(type default)
			)
			(layer "B.SilkS")
		)
		(fp_line
			(start 0.67945 -0.305054)
			(end 0.12065 -0.305054)
			(stroke
				(width 0.1)
				(type default)
			)
			(layer "B.Fab")
		)
		(fp_line
			(start 0.12065 -0.305054)
			(end 0.12065 -0.2794)
			(stroke
				(width 0.1)
				(type default)
			)
			(layer "B.Fab")
		)
		(fp_line
			(start -0.12065 -0.3048)
			(end -0.67945 -0.3048)
			(stroke
				(width 0.1)
				(type default)
			)
			(layer "B.Fab")
		)
		(fp_line
			(start -0.67945 -0.3048)
			(end -0.67945 0.3048)
			(stroke
				(width 0.1)
				(type default)
			)
			(layer "B.Fab")
		)
		(fp_line
			(start 0.12065 -0.2794)
			(end -0.12065 -0.2794)
			(stroke
				(width 0.1)
				(type default)
			)
			(layer "B.Fab")
		)
		(fp_line
			(start -0.12065 -0.2794)
			(end -0.12065 -0.3048)
			(stroke
				(width 0.1)
				(type default)
			)
			(layer "B.Fab")
		)
		(fp_line
			(start 0.12065 0.2794)
			(end 0.12065 0.3048)
			(stroke
				(width 0.1)
				(type default)
			)
			(layer "B.Fab")
		)
		(fp_line
			(start -0.120396 0.2794)
			(end 0.12065 0.2794)
			(stroke
				(width 0.1)
				(type default)
			)
			(layer "B.Fab")
		)
		(fp_line
			(start 0.67945 0.3048)
			(end 0.67945 -0.305054)
			(stroke
				(width 0.1)
				(type default)
			)
			(layer "B.Fab")
		)
		(fp_line
			(start 0.12065 0.3048)
			(end 0.67945 0.3048)
			(stroke
				(width 0.1)
				(type default)
			)
			(layer "B.Fab")
		)
		(fp_line
			(start -0.120396 0.3048)
			(end -0.120396 0.2794)
			(stroke
				(width 0.1)
				(type default)
			)
			(layer "B.Fab")
		)
		(fp_line
			(start -0.67945 0.3048)
			(end -0.120396 0.3048)
			(stroke
				(width 0.1)
				(type default)
			)
			(layer "B.Fab")
		)
		(pad "1" smd circle
			(at 0.40005 0 270)
			(size 0 0)
			(layers "B.Cu" "B.Mask" "B.Paste")
			(net "P3V3_AUX")
		)
		(pad "2" smd circle
			(at -0.40005 0 270)
			(size 0 0)
			(layers "B.Cu" "B.Mask" "B.Paste")
			(net "FM_HS1_EN_BUSBAR_BUF")
		)
	)
	(footprint ""
		(layer "B.Cu")
		(at 290.9824 -62.992 -90)
		(property "Reference" "R157"
			(at 0 0 90)
			(layer "B.SilkS")
			(hide yes)
			(effects
				(font
					(size 1.27 1.27)
				)
				(justify mirror)
			)
		)
		(property "Value" ""
			(at 0 0 90)
			(layer "B.Fab")
			(effects
				(font
					(size 1.27 1.27)
				)
				(justify mirror)
			)
		)
		(duplicate_pad_numbers_are_jumpers no)
		(fp_line
			(start -0.7874 0.4064)
			(end 0.7874 0.4064)
			(stroke
				(width 0.1524)
				(type default)
			)
			(layer "B.SilkS")
		)
		(fp_line
			(start 0.7874 0.4064)
			(end 0.7874 -0.4064)
			(stroke
				(width 0.1524)
				(type default)
			)
			(layer "B.SilkS")
		)
		(fp_line
			(start -0.7874 -0.4064)
			(end -0.7874 0.4064)
			(stroke
				(width 0.1524)
				(type default)
			)
			(layer "B.SilkS")
		)
		(fp_line
			(start 0.7874 -0.4064)
			(end -0.7874 -0.4064)
			(stroke
				(width 0.1524)
				(type default)
			)
			(layer "B.SilkS")
		)
		(fp_line
			(start -0.67945 0.3048)
			(end -0.120396 0.3048)
			(stroke
				(width 0.1)
				(type default)
			)
			(layer "B.Fab")
		)
		(fp_line
			(start -0.120396 0.3048)
			(end -0.120396 0.2794)
			(stroke
				(width 0.1)
				(type default)
			)
			(layer "B.Fab")
		)
		(fp_line
			(start 0.12065 0.3048)
			(end 0.67945 0.3048)
			(stroke
				(width 0.1)
				(type default)
			)
			(layer "B.Fab")
		)
		(fp_line
			(start 0.67945 0.3048)
			(end 0.67945 -0.305054)
			(stroke
				(width 0.1)
				(type default)
			)
			(layer "B.Fab")
		)
		(fp_line
			(start -0.120396 0.2794)
			(end 0.12065 0.2794)
			(stroke
				(width 0.1)
				(type default)
			)
			(layer "B.Fab")
		)
		(fp_line
			(start 0.12065 0.2794)
			(end 0.12065 0.3048)
			(stroke
				(width 0.1)
				(type default)
			)
			(layer "B.Fab")
		)
		(fp_line
			(start -0.12065 -0.2794)
			(end -0.12065 -0.3048)
			(stroke
				(width 0.1)
				(type default)
			)
			(layer "B.Fab")
		)
		(fp_line
			(start 0.12065 -0.2794)
			(end -0.12065 -0.2794)
			(stroke
				(width 0.1)
				(type default)
			)
			(layer "B.Fab")
		)
		(fp_line
			(start -0.67945 -0.3048)
			(end -0.67945 0.3048)
			(stroke
				(width 0.1)
				(type default)
			)
			(layer "B.Fab")
		)
		(fp_line
			(start -0.12065 -0.3048)
			(end -0.67945 -0.3048)
			(stroke
				(width 0.1)
				(type default)
			)
			(layer "B.Fab")
		)
		(fp_line
			(start 0.12065 -0.305054)
			(end 0.12065 -0.2794)
			(stroke
				(width 0.1)
				(type default)
			)
			(layer "B.Fab")
		)
		(fp_line
			(start 0.67945 -0.305054)
			(end 0.12065 -0.305054)
			(stroke
				(width 0.1)
				(type default)
			)
			(layer "B.Fab")
		)
		(pad "1" smd circle
			(at 0.40005 0 90)
			(size 0 0)
			(layers "B.Cu" "B.Mask" "B.Paste")
			(net "P52V_HS1_INTVCC")
		)
		(pad "2" smd circle
			(at -0.40005 0 90)
			(size 0 0)
			(layers "B.Cu" "B.Mask" "B.Paste")
			(net "P52V_HS1_ADR1")
		)
	)
	(footprint ""
		(layer "B.Cu")
		(at 278.4094 -68.961)
		(property "Reference" "R81"
			(at 0 0 0)
			(layer "B.SilkS")
			(hide yes)
			(effects
				(font
					(size 1.27 1.27)
				)
				(justify mirror)
			)
		)
		(property "Value" ""
			(at 0 0 0)
			(layer "B.Fab")
			(effects
				(font
					(size 1.27 1.27)
				)
				(justify mirror)
			)
		)
		(duplicate_pad_numbers_are_jumpers no)
		(fp_line
			(start -0.7874 -0.4064)
			(end -0.7874 0.4064)
			(stroke
				(width 0.1524)
				(type default)
			)
			(layer "B.SilkS")
		)
		(fp_line
			(start -0.7874 0.4064)
			(end 0.7874 0.4064)
			(stroke
				(width 0.1524)
				(type default)
			)
			(layer "B.SilkS")
		)
		(fp_line
			(start 0.7874 -0.4064)
			(end -0.7874 -0.4064)
			(stroke
				(width 0.1524)
				(type default)
			)
			(layer "B.SilkS")
		)
		(fp_line
			(start 0.7874 0.4064)
			(end 0.7874 -0.4064)
			(stroke
				(width 0.1524)
				(type default)
			)
			(layer "B.SilkS")
		)
		(fp_line
			(start -0.67945 -0.3048)
			(end -0.67945 0.3048)
			(stroke
				(width 0.1)
				(type default)
			)
			(layer "B.Fab")
		)
		(fp_line
			(start -0.67945 0.3048)
			(end -0.120396 0.3048)
			(stroke
				(width 0.1)
				(type default)
			)
			(layer "B.Fab")
		)
		(fp_line
			(start -0.12065 -0.3048)
			(end -0.67945 -0.3048)
			(stroke
				(width 0.1)
				(type default)
			)
			(layer "B.Fab")
		)
		(fp_line
			(start -0.12065 -0.2794)
			(end -0.12065 -0.3048)
			(stroke
				(width 0.1)
				(type default)
			)
			(layer "B.Fab")
		)
		(fp_line
			(start -0.120396 0.2794)
			(end 0.12065 0.2794)
			(stroke
				(width 0.1)
				(type default)
			)
			(layer "B.Fab")
		)
		(fp_line
			(start -0.120396 0.3048)
			(end -0.120396 0.2794)
			(stroke
				(width 0.1)
				(type default)
			)
			(layer "B.Fab")
		)
		(fp_line
			(start 0.12065 -0.305054)
			(end 0.12065 -0.2794)
			(stroke
				(width 0.1)
				(type default)
			)
			(layer "B.Fab")
		)
		(fp_line
			(start 0.12065 -0.2794)
			(end -0.12065 -0.2794)
			(stroke
				(width 0.1)
				(type default)
			)
			(layer "B.Fab")
		)
		(fp_line
			(start 0.12065 0.2794)
			(end 0.12065 0.3048)
			(stroke
				(width 0.1)
				(type default)
			)
			(layer "B.Fab")
		)
		(fp_line
			(start 0.12065 0.3048)
			(end 0.67945 0.3048)
			(stroke
				(width 0.1)
				(type default)
			)
			(layer "B.Fab")
		)
		(fp_line
			(start 0.67945 -0.305054)
			(end 0.12065 -0.305054)
			(stroke
				(width 0.1)
				(type default)
			)
			(layer "B.Fab")
		)
		(fp_line
			(start 0.67945 0.3048)
			(end 0.67945 -0.305054)
			(stroke
				(width 0.1)
				(type default)
			)
			(layer "B.Fab")
		)
		(pad "1" smd circle
			(at 0.40005 0 180)
			(size 0 0)
			(layers "B.Cu" "B.Mask" "B.Paste")
			(net "SMB_P52V_PDB_SCL")
		)
		(pad "2" smd circle
			(at -0.40005 0 180)
			(size 0 0)
			(layers "B.Cu" "B.Mask" "B.Paste")
			(net "SMB_P52V_PDB_SCL_R1")
		)
	)
	(footprint ""
		(layer "B.Cu")
		(at 284.7594 -65.659)
		(property "Reference" "PC7"
			(at 0 0 0)
			(layer "B.SilkS")
			(hide yes)
			(effects
				(font
					(size 1.27 1.27)
				)
				(justify mirror)
			)
		)
		(property "Value" ""
			(at 0 0 0)
			(layer "B.Fab")
			(effects
				(font
					(size 1.27 1.27)
				)
				(justify mirror)
			)
		)
		(duplicate_pad_numbers_are_jumpers no)
		(fp_line
			(start -0.7874 -0.4064)
			(end -0.7874 0.4064)
			(stroke
				(width 0.1524)
				(type default)
			)
			(layer "B.SilkS")
		)
		(fp_line
			(start -0.7874 0.4064)
			(end 0.7874 0.4064)
			(stroke
				(width 0.1524)
				(type default)
			)
			(layer "B.SilkS")
		)
		(fp_line
			(start 0.7874 -0.4064)
			(end -0.7874 -0.4064)
			(stroke
				(width 0.1524)
				(type default)
			)
			(layer "B.SilkS")
		)
		(fp_line
			(start 0.7874 0.4064)
			(end 0.7874 -0.4064)
			(stroke
				(width 0.1524)
				(type default)
			)
			(layer "B.SilkS")
		)
		(fp_line
			(start -0.67945 -0.3048)
			(end -0.67945 0.3048)
			(stroke
				(width 0.1)
				(type default)
			)
			(layer "B.Fab")
		)
		(fp_line
			(start -0.67945 0.3048)
			(end -0.120396 0.3048)
			(stroke
				(width 0.1)
				(type default)
			)
			(layer "B.Fab")
		)
		(fp_line
			(start -0.12065 -0.3048)
			(end -0.67945 -0.3048)
			(stroke
				(width 0.1)
				(type default)
			)
			(layer "B.Fab")
		)
		(fp_line
			(start -0.12065 -0.2794)
			(end -0.12065 -0.3048)
			(stroke
				(width 0.1)
				(type default)
			)
			(layer "B.Fab")
		)
		(fp_line
			(start -0.120396 0.2794)
			(end 0.12065 0.2794)
			(stroke
				(width 0.1)
				(type default)
			)
			(layer "B.Fab")
		)
		(fp_line
			(start -0.120396 0.3048)
			(end -0.120396 0.2794)
			(stroke
				(width 0.1)
				(type default)
			)
			(layer "B.Fab")
		)
		(fp_line
			(start 0.12065 -0.305054)
			(end 0.12065 -0.2794)
			(stroke
				(width 0.1)
				(type default)
			)
			(layer "B.Fab")
		)
		(fp_line
			(start 0.12065 -0.2794)
			(end -0.12065 -0.2794)
			(stroke
				(width 0.1)
				(type default)
			)
			(layer "B.Fab")
		)
		(fp_line
			(start 0.12065 0.2794)
			(end 0.12065 0.3048)
			(stroke
				(width 0.1)
				(type default)
			)
			(layer "B.Fab")
		)
		(fp_line
			(start 0.12065 0.3048)
			(end 0.67945 0.3048)
			(stroke
				(width 0.1)
				(type default)
			)
			(layer "B.Fab")
		)
		(fp_line
			(start 0.67945 -0.305054)
			(end 0.12065 -0.305054)
			(stroke
				(width 0.1)
				(type default)
			)
			(layer "B.Fab")
		)
		(fp_line
			(start 0.67945 0.3048)
			(end 0.67945 -0.305054)
			(stroke
				(width 0.1)
				(type default)
			)
			(layer "B.Fab")
		)
		(pad "1" smd circle
			(at 0.40005 0 180)
			(size 0 0)
			(layers "B.Cu" "B.Mask" "B.Paste")
			(net "P52V_HS1_TMR")
		)
		(pad "2" smd circle
			(at -0.40005 0 180)
			(size 0 0)
			(layers "B.Cu" "B.Mask" "B.Paste")
			(net "GND_FIELD_SIGNAL")
		)
	)
	(footprint ""
		(layer "B.Cu")
		(at 169.718736 -69.596)
		(property "Reference" "PC611"
			(at 0 0 0)
			(layer "B.SilkS")
			(hide yes)
			(effects
				(font
					(size 1.27 1.27)
				)
				(justify mirror)
			)
		)
		(property "Value" ""
			(at 0 0 0)
			(layer "B.Fab")
			(effects
				(font
					(size 1.27 1.27)
				)
				(justify mirror)
			)
		)
		(duplicate_pad_numbers_are_jumpers no)
		(fp_line
			(start -1.2954 -0.5842)
			(end -1.2954 0.5842)
			(stroke
				(width 0.1524)
				(type default)
			)
			(layer "B.SilkS")
		)
		(fp_line
			(start -1.2954 0.5842)
			(end 1.2954 0.5842)
			(stroke
				(width 0.1524)
				(type default)
			)
			(layer "B.SilkS")
		)
		(fp_line
			(start 1.2954 -0.5842)
			(end -1.2954 -0.5842)
			(stroke
				(width 0.1524)
				(type default)
			)
			(layer "B.SilkS")
		)
		(fp_line
			(start 1.2954 0.5842)
			(end 1.2954 -0.5842)
			(stroke
				(width 0.1524)
				(type default)
			)
			(layer "B.SilkS")
		)
		(fp_line
			(start -1.1938 -0.4064)
			(end -1.1938 0.4064)
			(stroke
				(width 0.1)
				(type default)
			)
			(layer "B.Fab")
		)
		(fp_line
			(start -1.1938 0.4064)
			(end -0.8636 0.4064)
			(stroke
				(width 0.1)
				(type default)
			)
			(layer "B.Fab")
		)
		(fp_line
			(start -0.8636 -0.4572)
			(end -0.8636 -0.4064)
			(stroke
				(width 0.1)
				(type default)
			)
			(layer "B.Fab")
		)
		(fp_line
			(start -0.8636 -0.4064)
			(end -1.1938 -0.4064)
			(stroke
				(width 0.1)
				(type default)
			)
			(layer "B.Fab")
		)
		(fp_line
			(start -0.8636 0.4064)
			(end -0.8636 0.4572)
			(stroke
				(width 0.1)
				(type default)
			)
			(layer "B.Fab")
		)
		(fp_line
			(start -0.8636 0.4572)
			(end 0.8636 0.4572)
			(stroke
				(width 0.1)
				(type default)
			)
			(layer "B.Fab")
		)
		(fp_line
			(start 0.8636 -0.4572)
			(end -0.8636 -0.4572)
			(stroke
				(width 0.1)
				(type default)
			)
			(layer "B.Fab")
		)
		(fp_line
			(start 0.8636 -0.4064)
			(end 0.8636 -0.4572)
			(stroke
				(width 0.1)
				(type default)
			)
			(layer "B.Fab")
		)
		(fp_line
			(start 0.8636 0.4064)
			(end 1.1938 0.4064)
			(stroke
				(width 0.1)
				(type default)
			)
			(layer "B.Fab")
		)
		(fp_line
			(start 0.8636 0.4572)
			(end 0.8636 0.4064)
			(stroke
				(width 0.1)
				(type default)
			)
			(layer "B.Fab")
		)
		(fp_line
			(start 1.1938 -0.4064)
			(end 0.8636 -0.4064)
			(stroke
				(width 0.1)
				(type default)
			)
			(layer "B.Fab")
		)
		(fp_line
			(start 1.1938 0.4064)
			(end 1.1938 -0.4064)
			(stroke
				(width 0.1)
				(type default)
			)
			(layer "B.Fab")
		)
		(pad "1" smd rect
			(at 0.7366 0 270)
			(size 0.7112 0.8128)
			(layers "B.Cu" "B.Mask" "B.Paste")
			(net "P52V_HS2_VCAP")
		)
		(pad "2" smd rect
			(at -0.7366 0 270)
			(size 0.7112 0.8128)
			(layers "B.Cu" "B.Mask" "B.Paste")
			(net "GND1_FIELD_SIGNAL")
		)
	)
	(footprint ""
		(layer "B.Cu")
		(at 168.829736 -64.643)
		(property "Reference" "PR7030"
			(at 0 0 0)
			(layer "B.SilkS")
			(hide yes)
			(effects
				(font
					(size 1.27 1.27)
				)
				(justify mirror)
			)
		)
		(property "Value" ""
			(at 0 0 0)
			(layer "B.Fab")
			(effects
				(font
					(size 1.27 1.27)
				)
				(justify mirror)
			)
		)
		(duplicate_pad_numbers_are_jumpers no)
		(fp_line
			(start -0.7874 -0.4064)
			(end -0.7874 0.4064)
			(stroke
				(width 0.1524)
				(type default)
			)
			(layer "B.SilkS")
		)
		(fp_line
			(start -0.7874 0.4064)
			(end 0.7874 0.4064)
			(stroke
				(width 0.1524)
				(type default)
			)
			(layer "B.SilkS")
		)
		(fp_line
			(start 0.7874 -0.4064)
			(end -0.7874 -0.4064)
			(stroke
				(width 0.1524)
				(type default)
			)
			(layer "B.SilkS")
		)
		(fp_line
			(start 0.7874 0.4064)
			(end 0.7874 -0.4064)
			(stroke
				(width 0.1524)
				(type default)
			)
			(layer "B.SilkS")
		)
		(fp_line
			(start -0.67945 -0.3048)
			(end -0.67945 0.3048)
			(stroke
				(width 0.1)
				(type default)
			)
			(layer "B.Fab")
		)
		(fp_line
			(start -0.67945 0.3048)
			(end -0.120396 0.3048)
			(stroke
				(width 0.1)
				(type default)
			)
			(layer "B.Fab")
		)
		(fp_line
			(start -0.12065 -0.3048)
			(end -0.67945 -0.3048)
			(stroke
				(width 0.1)
				(type default)
			)
			(layer "B.Fab")
		)
		(fp_line
			(start -0.12065 -0.2794)
			(end -0.12065 -0.3048)
			(stroke
				(width 0.1)
				(type default)
			)
			(layer "B.Fab")
		)
		(fp_line
			(start -0.120396 0.2794)
			(end 0.12065 0.2794)
			(stroke
				(width 0.1)
				(type default)
			)
			(layer "B.Fab")
		)
		(fp_line
			(start -0.120396 0.3048)
			(end -0.120396 0.2794)
			(stroke
				(width 0.1)
				(type default)
			)
			(layer "B.Fab")
		)
		(fp_line
			(start 0.12065 -0.305054)
			(end 0.12065 -0.2794)
			(stroke
				(width 0.1)
				(type default)
			)
			(layer "B.Fab")
		)
		(fp_line
			(start 0.12065 -0.2794)
			(end -0.12065 -0.2794)
			(stroke
				(width 0.1)
				(type default)
			)
			(layer "B.Fab")
		)
		(fp_line
			(start 0.12065 0.2794)
			(end 0.12065 0.3048)
			(stroke
				(width 0.1)
				(type default)
			)
			(layer "B.Fab")
		)
		(fp_line
			(start 0.12065 0.3048)
			(end 0.67945 0.3048)
			(stroke
				(width 0.1)
				(type default)
			)
			(layer "B.Fab")
		)
		(fp_line
			(start 0.67945 -0.305054)
			(end 0.12065 -0.305054)
			(stroke
				(width 0.1)
				(type default)
			)
			(layer "B.Fab")
		)
		(fp_line
			(start 0.67945 0.3048)
			(end 0.67945 -0.305054)
			(stroke
				(width 0.1)
				(type default)
			)
			(layer "B.Fab")
		)
		(pad "1" smd circle
			(at 0.40005 0 180)
			(size 0 0)
			(layers "B.Cu" "B.Mask" "B.Paste")
			(net "P52V_HS2_ISET")
		)
		(pad "2" smd circle
			(at -0.40005 0 180)
			(size 0 0)
			(layers "B.Cu" "B.Mask" "B.Paste")
			(net "GND1_FIELD_SIGNAL")
		)
	)
	(footprint ""
		(layer "B.Cu")
		(at 172.7454 -63.754 90)
		(property "Reference" "PR6979"
			(at 0 0 90)
			(layer "B.SilkS")
			(hide yes)
			(effects
				(font
					(size 1.27 1.27)
				)
				(justify mirror)
			)
		)
		(property "Value" ""
			(at 0 0 90)
			(layer "B.Fab")
			(effects
				(font
					(size 1.27 1.27)
				)
				(justify mirror)
			)
		)
		(duplicate_pad_numbers_are_jumpers no)
		(fp_line
			(start 0.7874 -0.4064)
			(end -0.7874 -0.4064)
			(stroke
				(width 0.1524)
				(type default)
			)
			(layer "B.SilkS")
		)
		(fp_line
			(start -0.7874 -0.4064)
			(end -0.7874 0.4064)
			(stroke
				(width 0.1524)
				(type default)
			)
			(layer "B.SilkS")
		)
		(fp_line
			(start 0.7874 0.4064)
			(end 0.7874 -0.4064)
			(stroke
				(width 0.1524)
				(type default)
			)
			(layer "B.SilkS")
		)
		(fp_line
			(start -0.7874 0.4064)
			(end 0.7874 0.4064)
			(stroke
				(width 0.1524)
				(type default)
			)
			(layer "B.SilkS")
		)
		(fp_line
			(start 0.67945 -0.305054)
			(end 0.12065 -0.305054)
			(stroke
				(width 0.1)
				(type default)
			)
			(layer "B.Fab")
		)
		(fp_line
			(start 0.12065 -0.305054)
			(end 0.12065 -0.2794)
			(stroke
				(width 0.1)
				(type default)
			)
			(layer "B.Fab")
		)
		(fp_line
			(start -0.12065 -0.3048)
			(end -0.67945 -0.3048)
			(stroke
				(width 0.1)
				(type default)
			)
			(layer "B.Fab")
		)
		(fp_line
			(start -0.67945 -0.3048)
			(end -0.67945 0.3048)
			(stroke
				(width 0.1)
				(type default)
			)
			(layer "B.Fab")
		)
		(fp_line
			(start 0.12065 -0.2794)
			(end -0.12065 -0.2794)
			(stroke
				(width 0.1)
				(type default)
			)
			(layer "B.Fab")
		)
		(fp_line
			(start -0.12065 -0.2794)
			(end -0.12065 -0.3048)
			(stroke
				(width 0.1)
				(type default)
			)
			(layer "B.Fab")
		)
		(fp_line
			(start 0.12065 0.2794)
			(end 0.12065 0.3048)
			(stroke
				(width 0.1)
				(type default)
			)
			(layer "B.Fab")
		)
		(fp_line
			(start -0.120396 0.2794)
			(end 0.12065 0.2794)
			(stroke
				(width 0.1)
				(type default)
			)
			(layer "B.Fab")
		)
		(fp_line
			(start 0.67945 0.3048)
			(end 0.67945 -0.305054)
			(stroke
				(width 0.1)
				(type default)
			)
			(layer "B.Fab")
		)
		(fp_line
			(start 0.12065 0.3048)
			(end 0.67945 0.3048)
			(stroke
				(width 0.1)
				(type default)
			)
			(layer "B.Fab")
		)
		(fp_line
			(start -0.120396 0.3048)
			(end -0.120396 0.2794)
			(stroke
				(width 0.1)
				(type default)
			)
			(layer "B.Fab")
		)
		(fp_line
			(start -0.67945 0.3048)
			(end -0.120396 0.3048)
			(stroke
				(width 0.1)
				(type default)
			)
			(layer "B.Fab")
		)
		(pad "1" smd circle
			(at 0.40005 0 270)
			(size 0 0)
			(layers "B.Cu" "B.Mask" "B.Paste")
			(net "P52V_HS2_OV")
		)
		(pad "2" smd circle
			(at -0.40005 0 270)
			(size 0 0)
			(layers "B.Cu" "B.Mask" "B.Paste")
			(net "GND1_FIELD_SIGNAL")
		)
	)
	(footprint ""
		(layer "B.Cu")
		(at 104.013 -54.356)
		(property "Reference" "PC596"
			(at 0 0 0)
			(layer "B.SilkS")
			(hide yes)
			(effects
				(font
					(size 1.27 1.27)
				)
				(justify mirror)
			)
		)
		(property "Value" ""
			(at 0 0 0)
			(layer "B.Fab")
			(effects
				(font
					(size 1.27 1.27)
				)
				(justify mirror)
			)
		)
		(duplicate_pad_numbers_are_jumpers no)
		(fp_line
			(start -1.2954 -0.5842)
			(end -1.2954 0.5842)
			(stroke
				(width 0.1524)
				(type default)
			)
			(layer "B.SilkS")
		)
		(fp_line
			(start -1.2954 0.5842)
			(end 1.2954 0.5842)
			(stroke
				(width 0.1524)
				(type default)
			)
			(layer "B.SilkS")
		)
		(fp_line
			(start 1.2954 -0.5842)
			(end -1.2954 -0.5842)
			(stroke
				(width 0.1524)
				(type default)
			)
			(layer "B.SilkS")
		)
		(fp_line
			(start 1.2954 0.5842)
			(end 1.2954 -0.5842)
			(stroke
				(width 0.1524)
				(type default)
			)
			(layer "B.SilkS")
		)
		(fp_line
			(start -1.1938 -0.4064)
			(end -1.1938 0.4064)
			(stroke
				(width 0.1)
				(type default)
			)
			(layer "B.Fab")
		)
		(fp_line
			(start -1.1938 0.4064)
			(end -0.8636 0.4064)
			(stroke
				(width 0.1)
				(type default)
			)
			(layer "B.Fab")
		)
		(fp_line
			(start -0.8636 -0.4572)
			(end -0.8636 -0.4064)
			(stroke
				(width 0.1)
				(type default)
			)
			(layer "B.Fab")
		)
		(fp_line
			(start -0.8636 -0.4064)
			(end -1.1938 -0.4064)
			(stroke
				(width 0.1)
				(type default)
			)
			(layer "B.Fab")
		)
		(fp_line
			(start -0.8636 0.4064)
			(end -0.8636 0.4572)
			(stroke
				(width 0.1)
				(type default)
			)
			(layer "B.Fab")
		)
		(fp_line
			(start -0.8636 0.4572)
			(end 0.8636 0.4572)
			(stroke
				(width 0.1)
				(type default)
			)
			(layer "B.Fab")
		)
		(fp_line
			(start 0.8636 -0.4572)
			(end -0.8636 -0.4572)
			(stroke
				(width 0.1)
				(type default)
			)
			(layer "B.Fab")
		)
		(fp_line
			(start 0.8636 -0.4064)
			(end 0.8636 -0.4572)
			(stroke
				(width 0.1)
				(type default)
			)
			(layer "B.Fab")
		)
		(fp_line
			(start 0.8636 0.4064)
			(end 1.1938 0.4064)
			(stroke
				(width 0.1)
				(type default)
			)
			(layer "B.Fab")
		)
		(fp_line
			(start 0.8636 0.4572)
			(end 0.8636 0.4064)
			(stroke
				(width 0.1)
				(type default)
			)
			(layer "B.Fab")
		)
		(fp_line
			(start 1.1938 -0.4064)
			(end 0.8636 -0.4064)
			(stroke
				(width 0.1)
				(type default)
			)
			(layer "B.Fab")
		)
		(fp_line
			(start 1.1938 0.4064)
			(end 1.1938 -0.4064)
			(stroke
				(width 0.1)
				(type default)
			)
			(layer "B.Fab")
		)
		(pad "1" smd rect
			(at 0.7366 0 270)
			(size 0.7112 0.8128)
			(layers "B.Cu" "B.Mask" "B.Paste")
			(net "P52V_HS2_GATE_RC")
		)
		(pad "2" smd rect
			(at -0.7366 0 270)
			(size 0.7112 0.8128)
			(layers "B.Cu" "B.Mask" "B.Paste")
			(net "P52V_HS2")
		)
	)
	(footprint ""
		(layer "B.Cu")
		(at 169.083736 -56.007 -90)
		(property "Reference" "PR7023"
			(at 0 0 90)
			(layer "B.SilkS")
			(hide yes)
			(effects
				(font
					(size 1.27 1.27)
				)
				(justify mirror)
			)
		)
		(property "Value" ""
			(at 0 0 90)
			(layer "B.Fab")
			(effects
				(font
					(size 1.27 1.27)
				)
				(justify mirror)
			)
		)
		(duplicate_pad_numbers_are_jumpers no)
		(fp_line
			(start -1.651 0.8382)
			(end 1.651 0.8382)
			(stroke
				(width 0.1524)
				(type default)
			)
			(layer "B.SilkS")
		)
		(fp_line
			(start 1.651 0.8382)
			(end 1.651 -0.8382)
			(stroke
				(width 0.1524)
				(type default)
			)
			(layer "B.SilkS")
		)
		(fp_line
			(start -1.651 -0.8382)
			(end -1.651 0.8382)
			(stroke
				(width 0.1524)
				(type default)
			)
			(layer "B.SilkS")
		)
		(fp_line
			(start 1.651 -0.8382)
			(end -1.651 -0.8382)
			(stroke
				(width 0.1524)
				(type default)
			)
			(layer "B.SilkS")
		)
		(fp_line
			(start -1.560576 0.7366)
			(end -1.560576 -0.7366)
			(stroke
				(width 0.1)
				(type default)
			)
			(layer "B.Fab")
		)
		(fp_line
			(start -1.524 0.7366)
			(end -1.560576 0.7366)
			(stroke
				(width 0.1)
				(type default)
			)
			(layer "B.Fab")
		)
		(fp_line
			(start 1.524 0.7366)
			(end -1.524 0.7366)
			(stroke
				(width 0.1)
				(type default)
			)
			(layer "B.Fab")
		)
		(fp_line
			(start 1.559814 0.7366)
			(end 1.524 0.7366)
			(stroke
				(width 0.1)
				(type default)
			)
			(layer "B.Fab")
		)
		(fp_line
			(start -1.560576 -0.7366)
			(end -1.524 -0.7366)
			(stroke
				(width 0.1)
				(type default)
			)
			(layer "B.Fab")
		)
		(fp_line
			(start -1.524 -0.7366)
			(end 1.524 -0.7366)
			(stroke
				(width 0.1)
				(type default)
			)
			(layer "B.Fab")
		)
		(fp_line
			(start 1.524 -0.7366)
			(end 1.559814 -0.7366)
			(stroke
				(width 0.1)
				(type default)
			)
			(layer "B.Fab")
		)
		(fp_line
			(start 1.559814 -0.7366)
			(end 1.559814 0.7366)
			(stroke
				(width 0.1)
				(type default)
			)
			(layer "B.Fab")
		)
		(pad "1" smd rect
			(at 0.94996 0 270)
			(size 1.1176 1.3716)
			(layers "B.Cu" "B.Mask" "B.Paste")
			(net "P52V_2")
		)
		(pad "2" smd rect
			(at -0.94996 0 270)
			(size 1.1176 1.3716)
			(layers "B.Cu" "B.Mask" "B.Paste")
			(net "P52V_HS2_ISET")
		)
	)
	(footprint ""
		(layer "B.Cu")
		(at 279.5524 -79.248)
		(property "Reference" "PR19"
			(at 0 0 0)
			(layer "B.SilkS")
			(hide yes)
			(effects
				(font
					(size 1.27 1.27)
				)
				(justify mirror)
			)
		)
		(property "Value" ""
			(at 0 0 0)
			(layer "B.Fab")
			(effects
				(font
					(size 1.27 1.27)
				)
				(justify mirror)
			)
		)
		(duplicate_pad_numbers_are_jumpers no)
		(fp_line
			(start -1.651 -0.8382)
			(end -1.651 0.8382)
			(stroke
				(width 0.1524)
				(type default)
			)
			(layer "B.SilkS")
		)
		(fp_line
			(start -1.651 0.8382)
			(end 1.651 0.8382)
			(stroke
				(width 0.1524)
				(type default)
			)
			(layer "B.SilkS")
		)
		(fp_line
			(start 1.651 -0.8382)
			(end -1.651 -0.8382)
			(stroke
				(width 0.1524)
				(type default)
			)
			(layer "B.SilkS")
		)
		(fp_line
			(start 1.651 0.8382)
			(end 1.651 -0.8382)
			(stroke
				(width 0.1524)
				(type default)
			)
			(layer "B.SilkS")
		)
		(fp_line
			(start -1.560576 -0.7366)
			(end -1.524 -0.7366)
			(stroke
				(width 0.1)
				(type default)
			)
			(layer "B.Fab")
		)
		(fp_line
			(start -1.560576 0.7366)
			(end -1.560576 -0.7366)
			(stroke
				(width 0.1)
				(type default)
			)
			(layer "B.Fab")
		)
		(fp_line
			(start -1.524 -0.7366)
			(end 1.524 -0.7366)
			(stroke
				(width 0.1)
				(type default)
			)
			(layer "B.Fab")
		)
		(fp_line
			(start -1.524 0.7366)
			(end -1.560576 0.7366)
			(stroke
				(width 0.1)
				(type default)
			)
			(layer "B.Fab")
		)
		(fp_line
			(start 1.524 -0.7366)
			(end 1.559814 -0.7366)
			(stroke
				(width 0.1)
				(type default)
			)
			(layer "B.Fab")
		)
		(fp_line
			(start 1.524 0.7366)
			(end -1.524 0.7366)
			(stroke
				(width 0.1)
				(type default)
			)
			(layer "B.Fab")
		)
		(fp_line
			(start 1.559814 -0.7366)
			(end 1.559814 0.7366)
			(stroke
				(width 0.1)
				(type default)
			)
			(layer "B.Fab")
		)
		(fp_line
			(start 1.559814 0.7366)
			(end 1.524 0.7366)
			(stroke
				(width 0.1)
				(type default)
			)
			(layer "B.Fab")
		)
		(pad "1" smd rect
			(at 0.94996 0)
			(size 1.1176 1.3716)
			(layers "B.Cu" "B.Mask" "B.Paste")
			(net "P52V_HS1")
		)
		(pad "2" smd rect
			(at -0.94996 0)
			(size 1.1176 1.3716)
			(layers "B.Cu" "B.Mask" "B.Paste")
			(net "P52V_HS1_ISET")
		)
	)
	(footprint ""
		(layer "B.Cu")
		(at 169.210736 -71.247 180)
		(property "Reference" "R5886"
			(at 0 0 0)
			(layer "B.SilkS")
			(hide yes)
			(effects
				(font
					(size 1.27 1.27)
				)
				(justify mirror)
			)
		)
		(property "Value" ""
			(at 0 0 0)
			(layer "B.Fab")
			(effects
				(font
					(size 1.27 1.27)
				)
				(justify mirror)
			)
		)
		(duplicate_pad_numbers_are_jumpers no)
		(fp_line
			(start 0.7874 0.4064)
			(end 0.7874 -0.4064)
			(stroke
				(width 0.1524)
				(type default)
			)
			(layer "B.SilkS")
		)
		(fp_line
			(start 0.7874 -0.4064)
			(end -0.7874 -0.4064)
			(stroke
				(width 0.1524)
				(type default)
			)
			(layer "B.SilkS")
		)
		(fp_line
			(start -0.7874 0.4064)
			(end 0.7874 0.4064)
			(stroke
				(width 0.1524)
				(type default)
			)
			(layer "B.SilkS")
		)
		(fp_line
			(start -0.7874 -0.4064)
			(end -0.7874 0.4064)
			(stroke
				(width 0.1524)
				(type default)
			)
			(layer "B.SilkS")
		)
		(fp_line
			(start 0.67945 0.3048)
			(end 0.67945 -0.305054)
			(stroke
				(width 0.1)
				(type default)
			)
			(layer "B.Fab")
		)
		(fp_line
			(start 0.67945 -0.305054)
			(end 0.12065 -0.305054)
			(stroke
				(width 0.1)
				(type default)
			)
			(layer "B.Fab")
		)
		(fp_line
			(start 0.12065 0.3048)
			(end 0.67945 0.3048)
			(stroke
				(width 0.1)
				(type default)
			)
			(layer "B.Fab")
		)
		(fp_line
			(start 0.12065 0.2794)
			(end 0.12065 0.3048)
			(stroke
				(width 0.1)
				(type default)
			)
			(layer "B.Fab")
		)
		(fp_line
			(start 0.12065 -0.2794)
			(end -0.12065 -0.2794)
			(stroke
				(width 0.1)
				(type default)
			)
			(layer "B.Fab")
		)
		(fp_line
			(start 0.12065 -0.305054)
			(end 0.12065 -0.2794)
			(stroke
				(width 0.1)
				(type default)
			)
			(layer "B.Fab")
		)
		(fp_line
			(start -0.120396 0.3048)
			(end -0.120396 0.2794)
			(stroke
				(width 0.1)
				(type default)
			)
			(layer "B.Fab")
		)
		(fp_line
			(start -0.120396 0.2794)
			(end 0.12065 0.2794)
			(stroke
				(width 0.1)
				(type default)
			)
			(layer "B.Fab")
		)
		(fp_line
			(start -0.12065 -0.2794)
			(end -0.12065 -0.3048)
			(stroke
				(width 0.1)
				(type default)
			)
			(layer "B.Fab")
		)
		(fp_line
			(start -0.12065 -0.3048)
			(end -0.67945 -0.3048)
			(stroke
				(width 0.1)
				(type default)
			)
			(layer "B.Fab")
		)
		(fp_line
			(start -0.67945 0.3048)
			(end -0.120396 0.3048)
			(stroke
				(width 0.1)
				(type default)
			)
			(layer "B.Fab")
		)
		(fp_line
			(start -0.67945 -0.3048)
			(end -0.67945 0.3048)
			(stroke
				(width 0.1)
				(type default)
			)
			(layer "B.Fab")
		)
		(pad "1" smd circle
			(at 0.40005 0)
			(size 0 0)
			(layers "B.Cu" "B.Mask" "B.Paste")
			(net "SMB_P52V_PDB_SCL")
		)
		(pad "2" smd circle
			(at -0.40005 0)
			(size 0 0)
			(layers "B.Cu" "B.Mask" "B.Paste")
			(net "SMB_P52V_PDB_SCL_R2")
		)
	)
	(footprint ""
		(layer "B.Cu")
		(at 417.900358 -32.759396 90)
		(property "Reference" "C101"
			(at 0 0 90)
			(layer "B.SilkS")
			(hide yes)
			(effects
				(font
					(size 1.27 1.27)
				)
				(justify mirror)
			)
		)
		(property "Value" ""
			(at 0 0 90)
			(layer "B.Fab")
			(effects
				(font
					(size 1.27 1.27)
				)
				(justify mirror)
			)
		)
		(duplicate_pad_numbers_are_jumpers no)
		(fp_line
			(start 0.7874 -0.4064)
			(end -0.7874 -0.4064)
			(stroke
				(width 0.1524)
				(type default)
			)
			(layer "B.SilkS")
		)
		(fp_line
			(start -0.7874 -0.4064)
			(end -0.7874 0.4064)
			(stroke
				(width 0.1524)
				(type default)
			)
			(layer "B.SilkS")
		)
		(fp_line
			(start 0.7874 0.4064)
			(end 0.7874 -0.4064)
			(stroke
				(width 0.1524)
				(type default)
			)
			(layer "B.SilkS")
		)
		(fp_line
			(start -0.7874 0.4064)
			(end 0.7874 0.4064)
			(stroke
				(width 0.1524)
				(type default)
			)
			(layer "B.SilkS")
		)
		(fp_line
			(start 0.67945 -0.305054)
			(end 0.12065 -0.305054)
			(stroke
				(width 0.1)
				(type default)
			)
			(layer "B.Fab")
		)
		(fp_line
			(start 0.12065 -0.305054)
			(end 0.12065 -0.2794)
			(stroke
				(width 0.1)
				(type default)
			)
			(layer "B.Fab")
		)
		(fp_line
			(start -0.12065 -0.3048)
			(end -0.67945 -0.3048)
			(stroke
				(width 0.1)
				(type default)
			)
			(layer "B.Fab")
		)
		(fp_line
			(start -0.67945 -0.3048)
			(end -0.67945 0.3048)
			(stroke
				(width 0.1)
				(type default)
			)
			(layer "B.Fab")
		)
		(fp_line
			(start 0.12065 -0.2794)
			(end -0.12065 -0.2794)
			(stroke
				(width 0.1)
				(type default)
			)
			(layer "B.Fab")
		)
		(fp_line
			(start -0.12065 -0.2794)
			(end -0.12065 -0.3048)
			(stroke
				(width 0.1)
				(type default)
			)
			(layer "B.Fab")
		)
		(fp_line
			(start 0.12065 0.2794)
			(end 0.12065 0.3048)
			(stroke
				(width 0.1)
				(type default)
			)
			(layer "B.Fab")
		)
		(fp_line
			(start -0.120396 0.2794)
			(end 0.12065 0.2794)
			(stroke
				(width 0.1)
				(type default)
			)
			(layer "B.Fab")
		)
		(fp_line
			(start 0.67945 0.3048)
			(end 0.67945 -0.305054)
			(stroke
				(width 0.1)
				(type default)
			)
			(layer "B.Fab")
		)
		(fp_line
			(start 0.12065 0.3048)
			(end 0.67945 0.3048)
			(stroke
				(width 0.1)
				(type default)
			)
			(layer "B.Fab")
		)
		(fp_line
			(start -0.120396 0.3048)
			(end -0.120396 0.2794)
			(stroke
				(width 0.1)
				(type default)
			)
			(layer "B.Fab")
		)
		(fp_line
			(start -0.67945 0.3048)
			(end -0.120396 0.3048)
			(stroke
				(width 0.1)
				(type default)
			)
			(layer "B.Fab")
		)
		(pad "1" smd circle
			(at 0.40005 0 270)
			(size 0 0)
			(layers "B.Cu" "B.Mask" "B.Paste")
			(net "P12V_LED_ISET_R")
		)
		(pad "2" smd circle
			(at -0.40005 0 270)
			(size 0 0)
			(layers "B.Cu" "B.Mask" "B.Paste")
			(net "GND")
		)
	)
	(footprint ""
		(layer "B.Cu")
		(at 161.336736 -70.866 90)
		(property "Reference" "PR7014"
			(at 0 0 90)
			(layer "B.SilkS")
			(hide yes)
			(effects
				(font
					(size 1.27 1.27)
				)
				(justify mirror)
			)
		)
		(property "Value" ""
			(at 0 0 90)
			(layer "B.Fab")
			(effects
				(font
					(size 1.27 1.27)
				)
				(justify mirror)
			)
		)
		(duplicate_pad_numbers_are_jumpers no)
		(fp_line
			(start 0.7874 -0.4064)
			(end -0.7874 -0.4064)
			(stroke
				(width 0.1524)
				(type default)
			)
			(layer "B.SilkS")
		)
		(fp_line
			(start -0.7874 -0.4064)
			(end -0.7874 0.4064)
			(stroke
				(width 0.1524)
				(type default)
			)
			(layer "B.SilkS")
		)
		(fp_line
			(start 0.7874 0.4064)
			(end 0.7874 -0.4064)
			(stroke
				(width 0.1524)
				(type default)
			)
			(layer "B.SilkS")
		)
		(fp_line
			(start -0.7874 0.4064)
			(end 0.7874 0.4064)
			(stroke
				(width 0.1524)
				(type default)
			)
			(layer "B.SilkS")
		)
		(fp_line
			(start 0.67945 -0.305054)
			(end 0.12065 -0.305054)
			(stroke
				(width 0.1)
				(type default)
			)
			(layer "B.Fab")
		)
		(fp_line
			(start 0.12065 -0.305054)
			(end 0.12065 -0.2794)
			(stroke
				(width 0.1)
				(type default)
			)
			(layer "B.Fab")
		)
		(fp_line
			(start -0.12065 -0.3048)
			(end -0.67945 -0.3048)
			(stroke
				(width 0.1)
				(type default)
			)
			(layer "B.Fab")
		)
		(fp_line
			(start -0.67945 -0.3048)
			(end -0.67945 0.3048)
			(stroke
				(width 0.1)
				(type default)
			)
			(layer "B.Fab")
		)
		(fp_line
			(start 0.12065 -0.2794)
			(end -0.12065 -0.2794)
			(stroke
				(width 0.1)
				(type default)
			)
			(layer "B.Fab")
		)
		(fp_line
			(start -0.12065 -0.2794)
			(end -0.12065 -0.3048)
			(stroke
				(width 0.1)
				(type default)
			)
			(layer "B.Fab")
		)
		(fp_line
			(start 0.12065 0.2794)
			(end 0.12065 0.3048)
			(stroke
				(width 0.1)
				(type default)
			)
			(layer "B.Fab")
		)
		(fp_line
			(start -0.120396 0.2794)
			(end 0.12065 0.2794)
			(stroke
				(width 0.1)
				(type default)
			)
			(layer "B.Fab")
		)
		(fp_line
			(start 0.67945 0.3048)
			(end 0.67945 -0.305054)
			(stroke
				(width 0.1)
				(type default)
			)
			(layer "B.Fab")
		)
		(fp_line
			(start 0.12065 0.3048)
			(end 0.67945 0.3048)
			(stroke
				(width 0.1)
				(type default)
			)
			(layer "B.Fab")
		)
		(fp_line
			(start -0.120396 0.3048)
			(end -0.120396 0.2794)
			(stroke
				(width 0.1)
				(type default)
			)
			(layer "B.Fab")
		)
		(fp_line
			(start -0.67945 0.3048)
			(end -0.120396 0.3048)
			(stroke
				(width 0.1)
				(type default)
			)
			(layer "B.Fab")
		)
		(pad "1" smd circle
			(at 0.40005 0 270)
			(size 0 0)
			(layers "B.Cu" "B.Mask" "B.Paste")
			(net "P52V_HS2_INTVCC")
		)
		(pad "2" smd circle
			(at -0.40005 0 270)
			(size 0 0)
			(layers "B.Cu" "B.Mask" "B.Paste")
			(net "P52V_HS2_SCK")
		)
	)
	(footprint ""
		(layer "B.Cu")
		(at 441.325 -47.371 180)
		(property "Reference" "R5941"
			(at 0 0 0)
			(layer "B.SilkS")
			(hide yes)
			(effects
				(font
					(size 1.27 1.27)
				)
				(justify mirror)
			)
		)
		(property "Value" ""
			(at 0 0 0)
			(layer "B.Fab")
			(effects
				(font
					(size 1.27 1.27)
				)
				(justify mirror)
			)
		)
		(duplicate_pad_numbers_are_jumpers no)
		(fp_line
			(start 0.7874 0.4064)
			(end 0.7874 -0.4064)
			(stroke
				(width 0.1524)
				(type default)
			)
			(layer "B.SilkS")
		)
		(fp_line
			(start 0.7874 -0.4064)
			(end -0.7874 -0.4064)
			(stroke
				(width 0.1524)
				(type default)
			)
			(layer "B.SilkS")
		)
		(fp_line
			(start -0.7874 0.4064)
			(end 0.7874 0.4064)
			(stroke
				(width 0.1524)
				(type default)
			)
			(layer "B.SilkS")
		)
		(fp_line
			(start -0.7874 -0.4064)
			(end -0.7874 0.4064)
			(stroke
				(width 0.1524)
				(type default)
			)
			(layer "B.SilkS")
		)
		(fp_line
			(start 0.67945 0.3048)
			(end 0.67945 -0.305054)
			(stroke
				(width 0.1)
				(type default)
			)
			(layer "B.Fab")
		)
		(fp_line
			(start 0.67945 -0.305054)
			(end 0.12065 -0.305054)
			(stroke
				(width 0.1)
				(type default)
			)
			(layer "B.Fab")
		)
		(fp_line
			(start 0.12065 0.3048)
			(end 0.67945 0.3048)
			(stroke
				(width 0.1)
				(type default)
			)
			(layer "B.Fab")
		)
		(fp_line
			(start 0.12065 0.2794)
			(end 0.12065 0.3048)
			(stroke
				(width 0.1)
				(type default)
			)
			(layer "B.Fab")
		)
		(fp_line
			(start 0.12065 -0.2794)
			(end -0.12065 -0.2794)
			(stroke
				(width 0.1)
				(type default)
			)
			(layer "B.Fab")
		)
		(fp_line
			(start 0.12065 -0.305054)
			(end 0.12065 -0.2794)
			(stroke
				(width 0.1)
				(type default)
			)
			(layer "B.Fab")
		)
		(fp_line
			(start -0.120396 0.3048)
			(end -0.120396 0.2794)
			(stroke
				(width 0.1)
				(type default)
			)
			(layer "B.Fab")
		)
		(fp_line
			(start -0.120396 0.2794)
			(end 0.12065 0.2794)
			(stroke
				(width 0.1)
				(type default)
			)
			(layer "B.Fab")
		)
		(fp_line
			(start -0.12065 -0.2794)
			(end -0.12065 -0.3048)
			(stroke
				(width 0.1)
				(type default)
			)
			(layer "B.Fab")
		)
		(fp_line
			(start -0.12065 -0.3048)
			(end -0.67945 -0.3048)
			(stroke
				(width 0.1)
				(type default)
			)
			(layer "B.Fab")
		)
		(fp_line
			(start -0.67945 0.3048)
			(end -0.120396 0.3048)
			(stroke
				(width 0.1)
				(type default)
			)
			(layer "B.Fab")
		)
		(fp_line
			(start -0.67945 -0.3048)
			(end -0.67945 0.3048)
			(stroke
				(width 0.1)
				(type default)
			)
			(layer "B.Fab")
		)
		(pad "1" smd circle
			(at 0.40005 0)
			(size 0 0)
			(layers "B.Cu" "B.Mask" "B.Paste")
			(net "P3V3_HPDB_PG")
		)
		(pad "2" smd circle
			(at -0.40005 0)
			(size 0 0)
			(layers "B.Cu" "B.Mask" "B.Paste")
			(net "P3V3_HPDB_PG_R1")
		)
	)
	(footprint ""
		(layer "B.Cu")
		(at 426.593 -36.957)
		(property "Reference" "R5933"
			(at 0 0 0)
			(layer "B.SilkS")
			(hide yes)
			(effects
				(font
					(size 1.27 1.27)
				)
				(justify mirror)
			)
		)
		(property "Value" ""
			(at 0 0 0)
			(layer "B.Fab")
			(effects
				(font
					(size 1.27 1.27)
				)
				(justify mirror)
			)
		)
		(duplicate_pad_numbers_are_jumpers no)
		(fp_line
			(start -0.7874 -0.4064)
			(end -0.7874 0.4064)
			(stroke
				(width 0.1524)
				(type default)
			)
			(layer "B.SilkS")
		)
		(fp_line
			(start -0.7874 0.4064)
			(end 0.7874 0.4064)
			(stroke
				(width 0.1524)
				(type default)
			)
			(layer "B.SilkS")
		)
		(fp_line
			(start 0.7874 -0.4064)
			(end -0.7874 -0.4064)
			(stroke
				(width 0.1524)
				(type default)
			)
			(layer "B.SilkS")
		)
		(fp_line
			(start 0.7874 0.4064)
			(end 0.7874 -0.4064)
			(stroke
				(width 0.1524)
				(type default)
			)
			(layer "B.SilkS")
		)
		(fp_line
			(start -0.67945 -0.3048)
			(end -0.67945 0.3048)
			(stroke
				(width 0.1)
				(type default)
			)
			(layer "B.Fab")
		)
		(fp_line
			(start -0.67945 0.3048)
			(end -0.120396 0.3048)
			(stroke
				(width 0.1)
				(type default)
			)
			(layer "B.Fab")
		)
		(fp_line
			(start -0.12065 -0.3048)
			(end -0.67945 -0.3048)
			(stroke
				(width 0.1)
				(type default)
			)
			(layer "B.Fab")
		)
		(fp_line
			(start -0.12065 -0.2794)
			(end -0.12065 -0.3048)
			(stroke
				(width 0.1)
				(type default)
			)
			(layer "B.Fab")
		)
		(fp_line
			(start -0.120396 0.2794)
			(end 0.12065 0.2794)
			(stroke
				(width 0.1)
				(type default)
			)
			(layer "B.Fab")
		)
		(fp_line
			(start -0.120396 0.3048)
			(end -0.120396 0.2794)
			(stroke
				(width 0.1)
				(type default)
			)
			(layer "B.Fab")
		)
		(fp_line
			(start 0.12065 -0.305054)
			(end 0.12065 -0.2794)
			(stroke
				(width 0.1)
				(type default)
			)
			(layer "B.Fab")
		)
		(fp_line
			(start 0.12065 -0.2794)
			(end -0.12065 -0.2794)
			(stroke
				(width 0.1)
				(type default)
			)
			(layer "B.Fab")
		)
		(fp_line
			(start 0.12065 0.2794)
			(end 0.12065 0.3048)
			(stroke
				(width 0.1)
				(type default)
			)
			(layer "B.Fab")
		)
		(fp_line
			(start 0.12065 0.3048)
			(end 0.67945 0.3048)
			(stroke
				(width 0.1)
				(type default)
			)
			(layer "B.Fab")
		)
		(fp_line
			(start 0.67945 -0.305054)
			(end 0.12065 -0.305054)
			(stroke
				(width 0.1)
				(type default)
			)
			(layer "B.Fab")
		)
		(fp_line
			(start 0.67945 0.3048)
			(end 0.67945 -0.305054)
			(stroke
				(width 0.1)
				(type default)
			)
			(layer "B.Fab")
		)
		(pad "1" smd circle
			(at 0.40005 0 180)
			(size 0 0)
			(layers "B.Cu" "B.Mask" "B.Paste")
			(net "SMB_PDB_MISC_SCL")
		)
		(pad "2" smd circle
			(at -0.40005 0 180)
			(size 0 0)
			(layers "B.Cu" "B.Mask" "B.Paste")
			(net "SMB_IOEXP_2_SCL")
		)
	)
	(footprint ""
		(layer "B.Cu")
		(at 177.592736 -80.391 90)
		(property "Reference" "PR7022"
			(at 0 0 90)
			(layer "B.SilkS")
			(hide yes)
			(effects
				(font
					(size 1.27 1.27)
				)
				(justify mirror)
			)
		)
		(property "Value" ""
			(at 0 0 90)
			(layer "B.Fab")
			(effects
				(font
					(size 1.27 1.27)
				)
				(justify mirror)
			)
		)
		(duplicate_pad_numbers_are_jumpers no)
		(fp_line
			(start 1.651 -0.8382)
			(end -1.651 -0.8382)
			(stroke
				(width 0.1524)
				(type default)
			)
			(layer "B.SilkS")
		)
		(fp_line
			(start -1.651 -0.8382)
			(end -1.651 0.8382)
			(stroke
				(width 0.1524)
				(type default)
			)
			(layer "B.SilkS")
		)
		(fp_line
			(start 1.651 0.8382)
			(end 1.651 -0.8382)
			(stroke
				(width 0.1524)
				(type default)
			)
			(layer "B.SilkS")
		)
		(fp_line
			(start -1.651 0.8382)
			(end 1.651 0.8382)
			(stroke
				(width 0.1524)
				(type default)
			)
			(layer "B.SilkS")
		)
		(fp_line
			(start 1.559814 -0.7366)
			(end 1.559814 0.7366)
			(stroke
				(width 0.1)
				(type default)
			)
			(layer "B.Fab")
		)
		(fp_line
			(start 1.524 -0.7366)
			(end 1.559814 -0.7366)
			(stroke
				(width 0.1)
				(type default)
			)
			(layer "B.Fab")
		)
		(fp_line
			(start -1.524 -0.7366)
			(end 1.524 -0.7366)
			(stroke
				(width 0.1)
				(type default)
			)
			(layer "B.Fab")
		)
		(fp_line
			(start -1.560576 -0.7366)
			(end -1.524 -0.7366)
			(stroke
				(width 0.1)
				(type default)
			)
			(layer "B.Fab")
		)
		(fp_line
			(start 1.559814 0.7366)
			(end 1.524 0.7366)
			(stroke
				(width 0.1)
				(type default)
			)
			(layer "B.Fab")
		)
		(fp_line
			(start 1.524 0.7366)
			(end -1.524 0.7366)
			(stroke
				(width 0.1)
				(type default)
			)
			(layer "B.Fab")
		)
		(fp_line
			(start -1.524 0.7366)
			(end -1.560576 0.7366)
			(stroke
				(width 0.1)
				(type default)
			)
			(layer "B.Fab")
		)
		(fp_line
			(start -1.560576 0.7366)
			(end -1.560576 -0.7366)
			(stroke
				(width 0.1)
				(type default)
			)
			(layer "B.Fab")
		)
		(pad "1" smd rect
			(at 0.94996 0 90)
			(size 1.1176 1.3716)
			(layers "B.Cu" "B.Mask" "B.Paste")
			(net "P52V_HS2")
		)
		(pad "2" smd rect
			(at -0.94996 0 90)
			(size 1.1176 1.3716)
			(layers "B.Cu" "B.Mask" "B.Paste")
			(net "P52V_HS2_PWRGIN")
		)
	)
	(footprint ""
		(layer "B.Cu")
		(at 153.970736 -62.357 180)
		(property "Reference" "PR7010"
			(at 0 0 0)
			(layer "B.SilkS")
			(hide yes)
			(effects
				(font
					(size 1.27 1.27)
				)
				(justify mirror)
			)
		)
		(property "Value" ""
			(at 0 0 0)
			(layer "B.Fab")
			(effects
				(font
					(size 1.27 1.27)
				)
				(justify mirror)
			)
		)
		(duplicate_pad_numbers_are_jumpers no)
		(fp_line
			(start 0.7874 0.4064)
			(end 0.7874 -0.4064)
			(stroke
				(width 0.1524)
				(type default)
			)
			(layer "B.SilkS")
		)
		(fp_line
			(start 0.7874 -0.4064)
			(end -0.7874 -0.4064)
			(stroke
				(width 0.1524)
				(type default)
			)
			(layer "B.SilkS")
		)
		(fp_line
			(start -0.7874 0.4064)
			(end 0.7874 0.4064)
			(stroke
				(width 0.1524)
				(type default)
			)
			(layer "B.SilkS")
		)
		(fp_line
			(start -0.7874 -0.4064)
			(end -0.7874 0.4064)
			(stroke
				(width 0.1524)
				(type default)
			)
			(layer "B.SilkS")
		)
		(fp_line
			(start 0.67945 0.3048)
			(end 0.67945 -0.305054)
			(stroke
				(width 0.1)
				(type default)
			)
			(layer "B.Fab")
		)
		(fp_line
			(start 0.67945 -0.305054)
			(end 0.12065 -0.305054)
			(stroke
				(width 0.1)
				(type default)
			)
			(layer "B.Fab")
		)
		(fp_line
			(start 0.12065 0.3048)
			(end 0.67945 0.3048)
			(stroke
				(width 0.1)
				(type default)
			)
			(layer "B.Fab")
		)
		(fp_line
			(start 0.12065 0.2794)
			(end 0.12065 0.3048)
			(stroke
				(width 0.1)
				(type default)
			)
			(layer "B.Fab")
		)
		(fp_line
			(start 0.12065 -0.2794)
			(end -0.12065 -0.2794)
			(stroke
				(width 0.1)
				(type default)
			)
			(layer "B.Fab")
		)
		(fp_line
			(start 0.12065 -0.305054)
			(end 0.12065 -0.2794)
			(stroke
				(width 0.1)
				(type default)
			)
			(layer "B.Fab")
		)
		(fp_line
			(start -0.120396 0.3048)
			(end -0.120396 0.2794)
			(stroke
				(width 0.1)
				(type default)
			)
			(layer "B.Fab")
		)
		(fp_line
			(start -0.120396 0.2794)
			(end 0.12065 0.2794)
			(stroke
				(width 0.1)
				(type default)
			)
			(layer "B.Fab")
		)
		(fp_line
			(start -0.12065 -0.2794)
			(end -0.12065 -0.3048)
			(stroke
				(width 0.1)
				(type default)
			)
			(layer "B.Fab")
		)
		(fp_line
			(start -0.12065 -0.3048)
			(end -0.67945 -0.3048)
			(stroke
				(width 0.1)
				(type default)
			)
			(layer "B.Fab")
		)
		(fp_line
			(start -0.67945 0.3048)
			(end -0.120396 0.3048)
			(stroke
				(width 0.1)
				(type default)
			)
			(layer "B.Fab")
		)
		(fp_line
			(start -0.67945 -0.3048)
			(end -0.67945 0.3048)
			(stroke
				(width 0.1)
				(type default)
			)
			(layer "B.Fab")
		)
		(pad "1" smd circle
			(at 0.40005 0)
			(size 0 0)
			(layers "B.Cu" "B.Mask" "B.Paste")
			(net "P52V_HS2_FB")
		)
		(pad "2" smd circle
			(at -0.40005 0)
			(size 0 0)
			(layers "B.Cu" "B.Mask" "B.Paste")
			(net "GND1_FIELD_SIGNAL")
		)
	)
	(footprint ""
		(layer "B.Cu")
		(at 288.29 -92.075 -90)
		(property "Reference" "R5903"
			(at 0 0 90)
			(layer "B.SilkS")
			(hide yes)
			(effects
				(font
					(size 1.27 1.27)
				)
				(justify mirror)
			)
		)
		(property "Value" ""
			(at 0 0 90)
			(layer "B.Fab")
			(effects
				(font
					(size 1.27 1.27)
				)
				(justify mirror)
			)
		)
		(duplicate_pad_numbers_are_jumpers no)
		(fp_line
			(start -0.7874 0.4064)
			(end 0.7874 0.4064)
			(stroke
				(width 0.1524)
				(type default)
			)
			(layer "B.SilkS")
		)
		(fp_line
			(start 0.7874 0.4064)
			(end 0.7874 -0.4064)
			(stroke
				(width 0.1524)
				(type default)
			)
			(layer "B.SilkS")
		)
		(fp_line
			(start -0.7874 -0.4064)
			(end -0.7874 0.4064)
			(stroke
				(width 0.1524)
				(type default)
			)
			(layer "B.SilkS")
		)
		(fp_line
			(start 0.7874 -0.4064)
			(end -0.7874 -0.4064)
			(stroke
				(width 0.1524)
				(type default)
			)
			(layer "B.SilkS")
		)
		(fp_line
			(start -0.67945 0.3048)
			(end -0.120396 0.3048)
			(stroke
				(width 0.1)
				(type default)
			)
			(layer "B.Fab")
		)
		(fp_line
			(start -0.120396 0.3048)
			(end -0.120396 0.2794)
			(stroke
				(width 0.1)
				(type default)
			)
			(layer "B.Fab")
		)
		(fp_line
			(start 0.12065 0.3048)
			(end 0.67945 0.3048)
			(stroke
				(width 0.1)
				(type default)
			)
			(layer "B.Fab")
		)
		(fp_line
			(start 0.67945 0.3048)
			(end 0.67945 -0.305054)
			(stroke
				(width 0.1)
				(type default)
			)
			(layer "B.Fab")
		)
		(fp_line
			(start -0.120396 0.2794)
			(end 0.12065 0.2794)
			(stroke
				(width 0.1)
				(type default)
			)
			(layer "B.Fab")
		)
		(fp_line
			(start 0.12065 0.2794)
			(end 0.12065 0.3048)
			(stroke
				(width 0.1)
				(type default)
			)
			(layer "B.Fab")
		)
		(fp_line
			(start -0.12065 -0.2794)
			(end -0.12065 -0.3048)
			(stroke
				(width 0.1)
				(type default)
			)
			(layer "B.Fab")
		)
		(fp_line
			(start 0.12065 -0.2794)
			(end -0.12065 -0.2794)
			(stroke
				(width 0.1)
				(type default)
			)
			(layer "B.Fab")
		)
		(fp_line
			(start -0.67945 -0.3048)
			(end -0.67945 0.3048)
			(stroke
				(width 0.1)
				(type default)
			)
			(layer "B.Fab")
		)
		(fp_line
			(start -0.12065 -0.3048)
			(end -0.67945 -0.3048)
			(stroke
				(width 0.1)
				(type default)
			)
			(layer "B.Fab")
		)
		(fp_line
			(start 0.12065 -0.305054)
			(end 0.12065 -0.2794)
			(stroke
				(width 0.1)
				(type default)
			)
			(layer "B.Fab")
		)
		(fp_line
			(start 0.67945 -0.305054)
			(end 0.12065 -0.305054)
			(stroke
				(width 0.1)
				(type default)
			)
			(layer "B.Fab")
		)
		(pad "1" smd circle
			(at 0.40005 0 90)
			(size 0 0)
			(layers "B.Cu" "B.Mask" "B.Paste")
			(net "P3V3_AND")
		)
		(pad "2" smd circle
			(at -0.40005 0 90)
			(size 0 0)
			(layers "B.Cu" "B.Mask" "B.Paste")
			(net "GND")
		)
	)
	(footprint ""
		(layer "B.Cu")
		(at 108.7374 -44.3484 -90)
		(property "Reference" "PD18"
			(at 3.87477 -0.9398 0)
			(unlocked yes)
			(layer "B.SilkS")
			(effects
				(font
					(size 0.7874 0.5842)
					(thickness 0.1524)
				)
				(justify left mirror)
			)
		)
		(property "Value" ""
			(at 0 0 90)
			(layer "B.Fab")
			(effects
				(font
					(size 1.27 1.27)
				)
				(justify mirror)
			)
		)
		(duplicate_pad_numbers_are_jumpers no)
		(fp_line
			(start -2.032 0.7112)
			(end 1.651 0.7112)
			(stroke
				(width 0.1524)
				(type default)
			)
			(layer "B.SilkS")
		)
		(fp_line
			(start 1.651 0.7112)
			(end 1.651 -0.7112)
			(stroke
				(width 0.1524)
				(type default)
			)
			(layer "B.SilkS")
		)
		(fp_line
			(start -1.778 0.6858)
			(end -1.778 -0.6858)
			(stroke
				(width 0.1524)
				(type default)
			)
			(layer "B.SilkS")
		)
		(fp_line
			(start 0.299974 0.500126)
			(end -0.199898 0)
			(stroke
				(width 0.1524)
				(type default)
			)
			(layer "B.SilkS")
		)
		(fp_line
			(start -0.199898 0)
			(end 0.299974 -0.500126)
			(stroke
				(width 0.1524)
				(type default)
			)
			(layer "B.SilkS")
		)
		(fp_line
			(start -0.299974 -0.500126)
			(end -0.299974 0.500126)
			(stroke
				(width 0.1524)
				(type default)
			)
			(layer "B.SilkS")
		)
		(fp_line
			(start 0.299974 -0.500126)
			(end 0.299974 0.500126)
			(stroke
				(width 0.1524)
				(type default)
			)
			(layer "B.SilkS")
		)
		(fp_line
			(start -1.905 -0.6858)
			(end -1.905 0.6858)
			(stroke
				(width 0.1524)
				(type default)
			)
			(layer "B.SilkS")
		)
		(fp_line
			(start -1.651 -0.6858)
			(end -1.651 0.6858)
			(stroke
				(width 0.1524)
				(type default)
			)
			(layer "B.SilkS")
		)
		(fp_line
			(start -2.032 -0.7112)
			(end -2.032 0.7112)
			(stroke
				(width 0.1524)
				(type default)
			)
			(layer "B.SilkS")
		)
		(fp_line
			(start 1.651 -0.7112)
			(end -2.032 -0.7112)
			(stroke
				(width 0.1524)
				(type default)
			)
			(layer "B.SilkS")
		)
		(fp_line
			(start -0.899922 0.700024)
			(end 0.899922 0.700024)
			(stroke
				(width 0.1)
				(type default)
			)
			(layer "B.Fab")
		)
		(fp_line
			(start 0.899922 0.700024)
			(end 0.899922 0.175006)
			(stroke
				(width 0.1)
				(type default)
			)
			(layer "B.Fab")
		)
		(fp_line
			(start 0.299974 0.500126)
			(end -0.199898 0)
			(stroke
				(width 0.1)
				(type default)
			)
			(layer "B.Fab")
		)
		(fp_line
			(start -1.35001 0.175006)
			(end -0.899922 0.175006)
			(stroke
				(width 0.1)
				(type default)
			)
			(layer "B.Fab")
		)
		(fp_line
			(start -0.899922 0.175006)
			(end -0.899922 0.700024)
			(stroke
				(width 0.1)
				(type default)
			)
			(layer "B.Fab")
		)
		(fp_line
			(start 0.899922 0.175006)
			(end 1.35001 0.175006)
			(stroke
				(width 0.1)
				(type default)
			)
			(layer "B.Fab")
		)
		(fp_line
			(start 1.35001 0.175006)
			(end 1.35001 -0.225044)
			(stroke
				(width 0.1)
				(type default)
			)
			(layer "B.Fab")
		)
		(fp_line
			(start -0.199898 0)
			(end 0.299974 -0.500126)
			(stroke
				(width 0.1)
				(type default)
			)
			(layer "B.Fab")
		)
		(fp_line
			(start -1.35001 -0.225044)
			(end -1.35001 0.175006)
			(stroke
				(width 0.1)
				(type default)
			)
			(layer "B.Fab")
		)
		(fp_line
			(start -0.899922 -0.225044)
			(end -1.35001 -0.225044)
			(stroke
				(width 0.1)
				(type default)
			)
			(layer "B.Fab")
		)
		(fp_line
			(start 0.899922 -0.225044)
			(end 0.899922 -0.700024)
			(stroke
				(width 0.1)
				(type default)
			)
			(layer "B.Fab")
		)
		(fp_line
			(start 1.35001 -0.225044)
			(end 0.899922 -0.225044)
			(stroke
				(width 0.1)
				(type default)
			)
			(layer "B.Fab")
		)
		(fp_line
			(start -0.299974 -0.500126)
			(end -0.299974 0.500126)
			(stroke
				(width 0.1)
				(type default)
			)
			(layer "B.Fab")
		)
		(fp_line
			(start 0.299974 -0.500126)
			(end 0.299974 0.500126)
			(stroke
				(width 0.1)
				(type default)
			)
			(layer "B.Fab")
		)
		(fp_line
			(start -0.899922 -0.700024)
			(end -0.899922 -0.225044)
			(stroke
				(width 0.1)
				(type default)
			)
			(layer "B.Fab")
		)
		(fp_line
			(start 0.899922 -0.700024)
			(end -0.899922 -0.700024)
			(stroke
				(width 0.1)
				(type default)
			)
			(layer "B.Fab")
		)
		(fp_text user "+"
			(at 3.429 -0.19685 270)
			(unlocked yes)
			(layer "B.SilkS")
			(effects
				(font
					(size 1.905 1.4224)
					(thickness 0.1524)
				)
				(justify left mirror)
			)
		)
		(fp_text user "-"
			(at -1.8288 -0.24765 270)
			(unlocked yes)
			(layer "B.SilkS")
			(effects
				(font
					(size 1.905 1.4224)
					(thickness 0.1524)
				)
				(justify left mirror)
			)
		)
		(fp_text user "+"
			(at 2.794 -0.19685 270)
			(unlocked yes)
			(layer "B.Fab")
			(effects
				(font
					(size 1.905 1.4224)
					(thickness 0.1524)
				)
				(justify left mirror)
			)
		)
		(fp_text user "-"
			(at -1.8288 -0.24765 270)
			(unlocked yes)
			(layer "B.Fab")
			(effects
				(font
					(size 1.905 1.4224)
					(thickness 0.1524)
				)
				(justify left mirror)
			)
		)
		(pad "1" smd rect
			(at 1.0922 0 270)
			(size 0.8128 0.8636)
			(layers "B.Cu" "B.Mask" "B.Paste")
			(net "P52V_HS2_4287_GATE2_R")
		)
		(pad "2" smd rect
			(at -1.0922 0 90)
			(size 0.8128 0.8636)
			(layers "B.Cu" "B.Mask" "B.Paste")
			(net "P52V_HS2_GATE2_R1")
		)
	)
	(footprint ""
		(layer "B.Cu")
		(at 285.9024 -74.168 180)
		(property "Reference" "R5856"
			(at 0 0 0)
			(layer "B.SilkS")
			(hide yes)
			(effects
				(font
					(size 1.27 1.27)
				)
				(justify mirror)
			)
		)
		(property "Value" ""
			(at 0 0 0)
			(layer "B.Fab")
			(effects
				(font
					(size 1.27 1.27)
				)
				(justify mirror)
			)
		)
		(duplicate_pad_numbers_are_jumpers no)
		(fp_line
			(start 0.7874 0.4064)
			(end 0.7874 -0.4064)
			(stroke
				(width 0.1524)
				(type default)
			)
			(layer "B.SilkS")
		)
		(fp_line
			(start 0.7874 -0.4064)
			(end -0.7874 -0.4064)
			(stroke
				(width 0.1524)
				(type default)
			)
			(layer "B.SilkS")
		)
		(fp_line
			(start -0.7874 0.4064)
			(end 0.7874 0.4064)
			(stroke
				(width 0.1524)
				(type default)
			)
			(layer "B.SilkS")
		)
		(fp_line
			(start -0.7874 -0.4064)
			(end -0.7874 0.4064)
			(stroke
				(width 0.1524)
				(type default)
			)
			(layer "B.SilkS")
		)
		(fp_line
			(start 0.67945 0.3048)
			(end 0.67945 -0.305054)
			(stroke
				(width 0.1)
				(type default)
			)
			(layer "B.Fab")
		)
		(fp_line
			(start 0.67945 -0.305054)
			(end 0.12065 -0.305054)
			(stroke
				(width 0.1)
				(type default)
			)
			(layer "B.Fab")
		)
		(fp_line
			(start 0.12065 0.3048)
			(end 0.67945 0.3048)
			(stroke
				(width 0.1)
				(type default)
			)
			(layer "B.Fab")
		)
		(fp_line
			(start 0.12065 0.2794)
			(end 0.12065 0.3048)
			(stroke
				(width 0.1)
				(type default)
			)
			(layer "B.Fab")
		)
		(fp_line
			(start 0.12065 -0.2794)
			(end -0.12065 -0.2794)
			(stroke
				(width 0.1)
				(type default)
			)
			(layer "B.Fab")
		)
		(fp_line
			(start 0.12065 -0.305054)
			(end 0.12065 -0.2794)
			(stroke
				(width 0.1)
				(type default)
			)
			(layer "B.Fab")
		)
		(fp_line
			(start -0.120396 0.3048)
			(end -0.120396 0.2794)
			(stroke
				(width 0.1)
				(type default)
			)
			(layer "B.Fab")
		)
		(fp_line
			(start -0.120396 0.2794)
			(end 0.12065 0.2794)
			(stroke
				(width 0.1)
				(type default)
			)
			(layer "B.Fab")
		)
		(fp_line
			(start -0.12065 -0.2794)
			(end -0.12065 -0.3048)
			(stroke
				(width 0.1)
				(type default)
			)
			(layer "B.Fab")
		)
		(fp_line
			(start -0.12065 -0.3048)
			(end -0.67945 -0.3048)
			(stroke
				(width 0.1)
				(type default)
			)
			(layer "B.Fab")
		)
		(fp_line
			(start -0.67945 0.3048)
			(end -0.120396 0.3048)
			(stroke
				(width 0.1)
				(type default)
			)
			(layer "B.Fab")
		)
		(fp_line
			(start -0.67945 -0.3048)
			(end -0.67945 0.3048)
			(stroke
				(width 0.1)
				(type default)
			)
			(layer "B.Fab")
		)
		(pad "1" smd circle
			(at 0.40005 0)
			(size 0 0)
			(layers "B.Cu" "B.Mask" "B.Paste")
			(net "SMB_P52V_PDB_SDA")
		)
		(pad "2" smd circle
			(at -0.40005 0)
			(size 0 0)
			(layers "B.Cu" "B.Mask" "B.Paste")
			(net "SMB_P52V_HS1_SDAO")
		)
	)
	(footprint ""
		(layer "B.Cu")
		(at 155.621736 -79.375 -90)
		(property "Reference" "R5875"
			(at 0 0 90)
			(layer "B.SilkS")
			(hide yes)
			(effects
				(font
					(size 1.27 1.27)
				)
				(justify mirror)
			)
		)
		(property "Value" ""
			(at 0 0 90)
			(layer "B.Fab")
			(effects
				(font
					(size 1.27 1.27)
				)
				(justify mirror)
			)
		)
		(duplicate_pad_numbers_are_jumpers no)
		(fp_line
			(start -0.7874 0.4064)
			(end 0.7874 0.4064)
			(stroke
				(width 0.1524)
				(type default)
			)
			(layer "B.SilkS")
		)
		(fp_line
			(start 0.7874 0.4064)
			(end 0.7874 -0.4064)
			(stroke
				(width 0.1524)
				(type default)
			)
			(layer "B.SilkS")
		)
		(fp_line
			(start -0.7874 -0.4064)
			(end -0.7874 0.4064)
			(stroke
				(width 0.1524)
				(type default)
			)
			(layer "B.SilkS")
		)
		(fp_line
			(start 0.7874 -0.4064)
			(end -0.7874 -0.4064)
			(stroke
				(width 0.1524)
				(type default)
			)
			(layer "B.SilkS")
		)
		(fp_line
			(start -0.67945 0.3048)
			(end -0.120396 0.3048)
			(stroke
				(width 0.1)
				(type default)
			)
			(layer "B.Fab")
		)
		(fp_line
			(start -0.120396 0.3048)
			(end -0.120396 0.2794)
			(stroke
				(width 0.1)
				(type default)
			)
			(layer "B.Fab")
		)
		(fp_line
			(start 0.12065 0.3048)
			(end 0.67945 0.3048)
			(stroke
				(width 0.1)
				(type default)
			)
			(layer "B.Fab")
		)
		(fp_line
			(start 0.67945 0.3048)
			(end 0.67945 -0.305054)
			(stroke
				(width 0.1)
				(type default)
			)
			(layer "B.Fab")
		)
		(fp_line
			(start -0.120396 0.2794)
			(end 0.12065 0.2794)
			(stroke
				(width 0.1)
				(type default)
			)
			(layer "B.Fab")
		)
		(fp_line
			(start 0.12065 0.2794)
			(end 0.12065 0.3048)
			(stroke
				(width 0.1)
				(type default)
			)
			(layer "B.Fab")
		)
		(fp_line
			(start -0.12065 -0.2794)
			(end -0.12065 -0.3048)
			(stroke
				(width 0.1)
				(type default)
			)
			(layer "B.Fab")
		)
		(fp_line
			(start 0.12065 -0.2794)
			(end -0.12065 -0.2794)
			(stroke
				(width 0.1)
				(type default)
			)
			(layer "B.Fab")
		)
		(fp_line
			(start -0.67945 -0.3048)
			(end -0.67945 0.3048)
			(stroke
				(width 0.1)
				(type default)
			)
			(layer "B.Fab")
		)
		(fp_line
			(start -0.12065 -0.3048)
			(end -0.67945 -0.3048)
			(stroke
				(width 0.1)
				(type default)
			)
			(layer "B.Fab")
		)
		(fp_line
			(start 0.12065 -0.305054)
			(end 0.12065 -0.2794)
			(stroke
				(width 0.1)
				(type default)
			)
			(layer "B.Fab")
		)
		(fp_line
			(start 0.67945 -0.305054)
			(end 0.12065 -0.305054)
			(stroke
				(width 0.1)
				(type default)
			)
			(layer "B.Fab")
		)
		(pad "1" smd circle
			(at 0.40005 0 90)
			(size 0 0)
			(layers "B.Cu" "B.Mask" "B.Paste")
			(net "P52V_HS2_ADR0")
		)
		(pad "2" smd circle
			(at -0.40005 0 90)
			(size 0 0)
			(layers "B.Cu" "B.Mask" "B.Paste")
			(net "GND1_FIELD_SIGNAL")
		)
	)
	(footprint ""
		(layer "B.Cu")
		(at 278.7904 -75.565 180)
		(property "Reference" "PR21"
			(at 0 0 0)
			(layer "B.SilkS")
			(hide yes)
			(effects
				(font
					(size 1.27 1.27)
				)
				(justify mirror)
			)
		)
		(property "Value" ""
			(at 0 0 0)
			(layer "B.Fab")
			(effects
				(font
					(size 1.27 1.27)
				)
				(justify mirror)
			)
		)
		(duplicate_pad_numbers_are_jumpers no)
		(fp_line
			(start 0.7874 0.4064)
			(end 0.7874 -0.4064)
			(stroke
				(width 0.1524)
				(type default)
			)
			(layer "B.SilkS")
		)
		(fp_line
			(start 0.7874 -0.4064)
			(end -0.7874 -0.4064)
			(stroke
				(width 0.1524)
				(type default)
			)
			(layer "B.SilkS")
		)
		(fp_line
			(start -0.7874 0.4064)
			(end 0.7874 0.4064)
			(stroke
				(width 0.1524)
				(type default)
			)
			(layer "B.SilkS")
		)
		(fp_line
			(start -0.7874 -0.4064)
			(end -0.7874 0.4064)
			(stroke
				(width 0.1524)
				(type default)
			)
			(layer "B.SilkS")
		)
		(fp_line
			(start 0.67945 0.3048)
			(end 0.67945 -0.305054)
			(stroke
				(width 0.1)
				(type default)
			)
			(layer "B.Fab")
		)
		(fp_line
			(start 0.67945 -0.305054)
			(end 0.12065 -0.305054)
			(stroke
				(width 0.1)
				(type default)
			)
			(layer "B.Fab")
		)
		(fp_line
			(start 0.12065 0.3048)
			(end 0.67945 0.3048)
			(stroke
				(width 0.1)
				(type default)
			)
			(layer "B.Fab")
		)
		(fp_line
			(start 0.12065 0.2794)
			(end 0.12065 0.3048)
			(stroke
				(width 0.1)
				(type default)
			)
			(layer "B.Fab")
		)
		(fp_line
			(start 0.12065 -0.2794)
			(end -0.12065 -0.2794)
			(stroke
				(width 0.1)
				(type default)
			)
			(layer "B.Fab")
		)
		(fp_line
			(start 0.12065 -0.305054)
			(end 0.12065 -0.2794)
			(stroke
				(width 0.1)
				(type default)
			)
			(layer "B.Fab")
		)
		(fp_line
			(start -0.120396 0.3048)
			(end -0.120396 0.2794)
			(stroke
				(width 0.1)
				(type default)
			)
			(layer "B.Fab")
		)
		(fp_line
			(start -0.120396 0.2794)
			(end 0.12065 0.2794)
			(stroke
				(width 0.1)
				(type default)
			)
			(layer "B.Fab")
		)
		(fp_line
			(start -0.12065 -0.2794)
			(end -0.12065 -0.3048)
			(stroke
				(width 0.1)
				(type default)
			)
			(layer "B.Fab")
		)
		(fp_line
			(start -0.12065 -0.3048)
			(end -0.67945 -0.3048)
			(stroke
				(width 0.1)
				(type default)
			)
			(layer "B.Fab")
		)
		(fp_line
			(start -0.67945 0.3048)
			(end -0.120396 0.3048)
			(stroke
				(width 0.1)
				(type default)
			)
			(layer "B.Fab")
		)
		(fp_line
			(start -0.67945 -0.3048)
			(end -0.67945 0.3048)
			(stroke
				(width 0.1)
				(type default)
			)
			(layer "B.Fab")
		)
		(pad "1" smd circle
			(at 0.40005 0)
			(size 0 0)
			(layers "B.Cu" "B.Mask" "B.Paste")
			(net "P52V_HS1_ISET")
		)
		(pad "2" smd circle
			(at -0.40005 0)
			(size 0 0)
			(layers "B.Cu" "B.Mask" "B.Paste")
			(net "GND_FIELD_SIGNAL")
		)
	)
	(footprint ""
		(layer "B.Cu")
		(at 159.812736 -58.674)
		(property "Reference" "PC605"
			(at 0 0 0)
			(layer "B.SilkS")
			(hide yes)
			(effects
				(font
					(size 1.27 1.27)
				)
				(justify mirror)
			)
		)
		(property "Value" ""
			(at 0 0 0)
			(layer "B.Fab")
			(effects
				(font
					(size 1.27 1.27)
				)
				(justify mirror)
			)
		)
		(duplicate_pad_numbers_are_jumpers no)
		(fp_line
			(start -2.2098 -0.9398)
			(end -2.2098 0.9398)
			(stroke
				(width 0.1524)
				(type default)
			)
			(layer "B.SilkS")
		)
		(fp_line
			(start -2.2098 0.9398)
			(end 2.2098 0.9398)
			(stroke
				(width 0.1524)
				(type default)
			)
			(layer "B.SilkS")
		)
		(fp_line
			(start 2.2098 -0.9398)
			(end -2.2098 -0.9398)
			(stroke
				(width 0.1524)
				(type default)
			)
			(layer "B.SilkS")
		)
		(fp_line
			(start 2.2098 0.9398)
			(end 2.2098 -0.9398)
			(stroke
				(width 0.1524)
				(type default)
			)
			(layer "B.SilkS")
		)
		(fp_line
			(start -1.700022 -0.899922)
			(end -1.700022 0.899922)
			(stroke
				(width 0.1)
				(type default)
			)
			(layer "B.Fab")
		)
		(fp_line
			(start -1.700022 0.899922)
			(end 1.700022 0.899922)
			(stroke
				(width 0.1)
				(type default)
			)
			(layer "B.Fab")
		)
		(fp_line
			(start 1.700022 -0.899922)
			(end -1.700022 -0.899922)
			(stroke
				(width 0.1)
				(type default)
			)
			(layer "B.Fab")
		)
		(fp_line
			(start 1.700022 0.899922)
			(end 1.700022 -0.899922)
			(stroke
				(width 0.1)
				(type default)
			)
			(layer "B.Fab")
		)
		(pad "1" smd rect
			(at 1.4732 0)
			(size 1.1684 1.5748)
			(layers "B.Cu" "B.Mask" "B.Paste")
			(net "P52V_HS2_DVCC")
		)
		(pad "2" smd rect
			(at -1.4732 0)
			(size 1.1684 1.5748)
			(layers "B.Cu" "B.Mask" "B.Paste")
			(net "GND")
		)
	)
	(footprint ""
		(layer "B.Cu")
		(at 293.116 -86.487 180)
		(property "Reference" "U42"
			(at 0.3175 -2.07137 0)
			(unlocked yes)
			(layer "B.SilkS")
			(effects
				(font
					(size 0.7874 0.5842)
					(thickness 0.1524)
				)
				(justify left mirror)
			)
		)
		(property "Value" ""
			(at 0 0 0)
			(layer "B.Fab")
			(effects
				(font
					(size 1.27 1.27)
				)
				(justify mirror)
			)
		)
		(duplicate_pad_numbers_are_jumpers no)
		(fp_line
			(start 1.400048 1.100074)
			(end 1.400048 -1.100074)
			(stroke
				(width 0.1524)
				(type default)
			)
			(layer "B.SilkS")
		)
		(fp_line
			(start -1.400048 1.100074)
			(end 1.400048 1.100074)
			(stroke
				(width 0.1524)
				(type default)
			)
			(layer "B.SilkS")
		)
		(fp_line
			(start -1.400048 -1.100074)
			(end 1.400048 -1.100074)
			(stroke
				(width 0.1524)
				(type default)
			)
			(layer "B.SilkS")
		)
		(fp_line
			(start -1.400048 -1.100074)
			(end -1.400048 1.100074)
			(stroke
				(width 0.1524)
				(type default)
			)
			(layer "B.SilkS")
		)
		(fp_poly
			(pts
				(xy 1.590548 -0.649986) (xy 2.606548 -1.157986) (xy 2.606548 -0.141986)
			)
			(stroke
				(width 0)
				(type default)
			)
			(fill yes)
			(layer "B.SilkS")
		)
		(fp_line
			(start 0.674878 1.100074)
			(end 0.674878 -1.100074)
			(stroke
				(width 0.1)
				(type default)
			)
			(layer "B.Fab")
		)
		(fp_line
			(start 0.674878 -1.100074)
			(end -0.674878 -1.100074)
			(stroke
				(width 0.1)
				(type default)
			)
			(layer "B.Fab")
		)
		(fp_line
			(start -0.674878 1.100074)
			(end 0.674878 1.100074)
			(stroke
				(width 0.1)
				(type default)
			)
			(layer "B.Fab")
		)
		(fp_line
			(start -0.674878 -1.100074)
			(end -0.674878 1.100074)
			(stroke
				(width 0.1)
				(type default)
			)
			(layer "B.Fab")
		)
		(fp_poly
			(pts
				(xy 1.590548 -0.649986) (xy 2.606548 -1.157986) (xy 2.606548 -0.141986)
			)
			(stroke
				(width 0)
				(type default)
			)
			(fill yes)
			(layer "B.Fab")
		)
		(pad "1" smd rect
			(at 0.94996 -0.649986 90)
			(size 0.4318 0.6096)
			(layers "B.Cu" "B.Mask" "B.Paste")
			(net "Net_418")
		)
		(pad "2" smd rect
			(at 0.94996 0 90)
			(size 0.4318 0.6096)
			(layers "B.Cu" "B.Mask" "B.Paste")
			(net "FM_HS1_EN_BUSBAR")
		)
		(pad "3" smd rect
			(at 0.94996 0.649986 90)
			(size 0.4318 0.6096)
			(layers "B.Cu" "B.Mask" "B.Paste")
			(net "GND")
		)
		(pad "4" smd rect
			(at -0.94996 0.649986 90)
			(size 0.4318 0.6096)
			(layers "B.Cu" "B.Mask" "B.Paste")
			(net "FM_HS1_EN_BUSBAR_BUF")
		)
		(pad "5" smd rect
			(at -0.94996 -0.649986 90)
			(size 0.4318 0.6096)
			(layers "B.Cu" "B.Mask" "B.Paste")
			(net "P3V3_AUX")
		)
	)
	(footprint ""
		(layer "B.Cu")
		(at 107.188 -43.561 90)
		(property "Reference" "PR7001"
			(at 0 0 90)
			(layer "B.SilkS")
			(hide yes)
			(effects
				(font
					(size 1.27 1.27)
				)
				(justify mirror)
			)
		)
		(property "Value" ""
			(at 0 0 90)
			(layer "B.Fab")
			(effects
				(font
					(size 1.27 1.27)
				)
				(justify mirror)
			)
		)
		(duplicate_pad_numbers_are_jumpers no)
		(fp_line
			(start 0.7874 -0.4064)
			(end -0.7874 -0.4064)
			(stroke
				(width 0.1524)
				(type default)
			)
			(layer "B.SilkS")
		)
		(fp_line
			(start -0.7874 -0.4064)
			(end -0.7874 0.4064)
			(stroke
				(width 0.1524)
				(type default)
			)
			(layer "B.SilkS")
		)
		(fp_line
			(start 0.7874 0.4064)
			(end 0.7874 -0.4064)
			(stroke
				(width 0.1524)
				(type default)
			)
			(layer "B.SilkS")
		)
		(fp_line
			(start -0.7874 0.4064)
			(end 0.7874 0.4064)
			(stroke
				(width 0.1524)
				(type default)
			)
			(layer "B.SilkS")
		)
		(fp_line
			(start 0.67945 -0.305054)
			(end 0.12065 -0.305054)
			(stroke
				(width 0.1)
				(type default)
			)
			(layer "B.Fab")
		)
		(fp_line
			(start 0.12065 -0.305054)
			(end 0.12065 -0.2794)
			(stroke
				(width 0.1)
				(type default)
			)
			(layer "B.Fab")
		)
		(fp_line
			(start -0.12065 -0.3048)
			(end -0.67945 -0.3048)
			(stroke
				(width 0.1)
				(type default)
			)
			(layer "B.Fab")
		)
		(fp_line
			(start -0.67945 -0.3048)
			(end -0.67945 0.3048)
			(stroke
				(width 0.1)
				(type default)
			)
			(layer "B.Fab")
		)
		(fp_line
			(start 0.12065 -0.2794)
			(end -0.12065 -0.2794)
			(stroke
				(width 0.1)
				(type default)
			)
			(layer "B.Fab")
		)
		(fp_line
			(start -0.12065 -0.2794)
			(end -0.12065 -0.3048)
			(stroke
				(width 0.1)
				(type default)
			)
			(layer "B.Fab")
		)
		(fp_line
			(start 0.12065 0.2794)
			(end 0.12065 0.3048)
			(stroke
				(width 0.1)
				(type default)
			)
			(layer "B.Fab")
		)
		(fp_line
			(start -0.120396 0.2794)
			(end 0.12065 0.2794)
			(stroke
				(width 0.1)
				(type default)
			)
			(layer "B.Fab")
		)
		(fp_line
			(start 0.67945 0.3048)
			(end 0.67945 -0.305054)
			(stroke
				(width 0.1)
				(type default)
			)
			(layer "B.Fab")
		)
		(fp_line
			(start 0.12065 0.3048)
			(end 0.67945 0.3048)
			(stroke
				(width 0.1)
				(type default)
			)
			(layer "B.Fab")
		)
		(fp_line
			(start -0.120396 0.3048)
			(end -0.120396 0.2794)
			(stroke
				(width 0.1)
				(type default)
			)
			(layer "B.Fab")
		)
		(fp_line
			(start -0.67945 0.3048)
			(end -0.120396 0.3048)
			(stroke
				(width 0.1)
				(type default)
			)
			(layer "B.Fab")
		)
		(pad "1" smd rect
			(at 0.40005 0 90)
			(size 0.4572 0.508)
			(layers "B.Cu" "B.Mask" "B.Paste")
			(net "P52V_HS2_GATE2_R1")
		)
		(pad "2" smd rect
			(at -0.40005 0 90)
			(size 0.4572 0.508)
			(layers "B.Cu" "B.Mask" "B.Paste")
			(net "P52V_HS2_4287_GATE2_R")
		)
	)
	(footprint ""
		(layer "B.Cu")
		(at 179.6034 -51.562)
		(property "Reference" "C88"
			(at 0 0 0)
			(layer "B.SilkS")
			(hide yes)
			(effects
				(font
					(size 1.27 1.27)
				)
				(justify mirror)
			)
		)
		(property "Value" ""
			(at 0 0 0)
			(layer "B.Fab")
			(effects
				(font
					(size 1.27 1.27)
				)
				(justify mirror)
			)
		)
		(duplicate_pad_numbers_are_jumpers no)
		(fp_line
			(start -1.2954 -0.5842)
			(end -1.2954 0.5842)
			(stroke
				(width 0.1524)
				(type default)
			)
			(layer "B.SilkS")
		)
		(fp_line
			(start -1.2954 0.5842)
			(end 1.2954 0.5842)
			(stroke
				(width 0.1524)
				(type default)
			)
			(layer "B.SilkS")
		)
		(fp_line
			(start 1.2954 -0.5842)
			(end -1.2954 -0.5842)
			(stroke
				(width 0.1524)
				(type default)
			)
			(layer "B.SilkS")
		)
		(fp_line
			(start 1.2954 0.5842)
			(end 1.2954 -0.5842)
			(stroke
				(width 0.1524)
				(type default)
			)
			(layer "B.SilkS")
		)
		(fp_line
			(start -1.1938 -0.4064)
			(end -1.1938 0.4064)
			(stroke
				(width 0.1)
				(type default)
			)
			(layer "B.Fab")
		)
		(fp_line
			(start -1.1938 0.4064)
			(end -0.8636 0.4064)
			(stroke
				(width 0.1)
				(type default)
			)
			(layer "B.Fab")
		)
		(fp_line
			(start -0.8636 -0.4572)
			(end -0.8636 -0.4064)
			(stroke
				(width 0.1)
				(type default)
			)
			(layer "B.Fab")
		)
		(fp_line
			(start -0.8636 -0.4064)
			(end -1.1938 -0.4064)
			(stroke
				(width 0.1)
				(type default)
			)
			(layer "B.Fab")
		)
		(fp_line
			(start -0.8636 0.4064)
			(end -0.8636 0.4572)
			(stroke
				(width 0.1)
				(type default)
			)
			(layer "B.Fab")
		)
		(fp_line
			(start -0.8636 0.4572)
			(end 0.8636 0.4572)
			(stroke
				(width 0.1)
				(type default)
			)
			(layer "B.Fab")
		)
		(fp_line
			(start 0.8636 -0.4572)
			(end -0.8636 -0.4572)
			(stroke
				(width 0.1)
				(type default)
			)
			(layer "B.Fab")
		)
		(fp_line
			(start 0.8636 -0.4064)
			(end 0.8636 -0.4572)
			(stroke
				(width 0.1)
				(type default)
			)
			(layer "B.Fab")
		)
		(fp_line
			(start 0.8636 0.4064)
			(end 1.1938 0.4064)
			(stroke
				(width 0.1)
				(type default)
			)
			(layer "B.Fab")
		)
		(fp_line
			(start 0.8636 0.4572)
			(end 0.8636 0.4064)
			(stroke
				(width 0.1)
				(type default)
			)
			(layer "B.Fab")
		)
		(fp_line
			(start 1.1938 -0.4064)
			(end 0.8636 -0.4064)
			(stroke
				(width 0.1)
				(type default)
			)
			(layer "B.Fab")
		)
		(fp_line
			(start 1.1938 0.4064)
			(end 1.1938 -0.4064)
			(stroke
				(width 0.1)
				(type default)
			)
			(layer "B.Fab")
		)
		(pad "1" smd rect
			(at 0.7366 0 270)
			(size 0.7112 0.8128)
			(layers "B.Cu" "B.Mask" "B.Paste")
			(net "FM_HS2_EN_FUSE")
		)
		(pad "2" smd rect
			(at -0.7366 0 270)
			(size 0.7112 0.8128)
			(layers "B.Cu" "B.Mask" "B.Paste")
			(net "GND")
		)
	)
	(footprint ""
		(layer "B.Cu")
		(at 285.9024 -67.945)
		(property "Reference" "PR213"
			(at 0 0 0)
			(layer "B.SilkS")
			(hide yes)
			(effects
				(font
					(size 1.27 1.27)
				)
				(justify mirror)
			)
		)
		(property "Value" ""
			(at 0 0 0)
			(layer "B.Fab")
			(effects
				(font
					(size 1.27 1.27)
				)
				(justify mirror)
			)
		)
		(duplicate_pad_numbers_are_jumpers no)
		(fp_line
			(start -0.7874 -0.4064)
			(end -0.7874 0.4064)
			(stroke
				(width 0.1524)
				(type default)
			)
			(layer "B.SilkS")
		)
		(fp_line
			(start -0.7874 0.4064)
			(end 0.7874 0.4064)
			(stroke
				(width 0.1524)
				(type default)
			)
			(layer "B.SilkS")
		)
		(fp_line
			(start 0.7874 -0.4064)
			(end -0.7874 -0.4064)
			(stroke
				(width 0.1524)
				(type default)
			)
			(layer "B.SilkS")
		)
		(fp_line
			(start 0.7874 0.4064)
			(end 0.7874 -0.4064)
			(stroke
				(width 0.1524)
				(type default)
			)
			(layer "B.SilkS")
		)
		(fp_line
			(start -0.67945 -0.3048)
			(end -0.67945 0.3048)
			(stroke
				(width 0.1)
				(type default)
			)
			(layer "B.Fab")
		)
		(fp_line
			(start -0.67945 0.3048)
			(end -0.120396 0.3048)
			(stroke
				(width 0.1)
				(type default)
			)
			(layer "B.Fab")
		)
		(fp_line
			(start -0.12065 -0.3048)
			(end -0.67945 -0.3048)
			(stroke
				(width 0.1)
				(type default)
			)
			(layer "B.Fab")
		)
		(fp_line
			(start -0.12065 -0.2794)
			(end -0.12065 -0.3048)
			(stroke
				(width 0.1)
				(type default)
			)
			(layer "B.Fab")
		)
		(fp_line
			(start -0.120396 0.2794)
			(end 0.12065 0.2794)
			(stroke
				(width 0.1)
				(type default)
			)
			(layer "B.Fab")
		)
		(fp_line
			(start -0.120396 0.3048)
			(end -0.120396 0.2794)
			(stroke
				(width 0.1)
				(type default)
			)
			(layer "B.Fab")
		)
		(fp_line
			(start 0.12065 -0.305054)
			(end 0.12065 -0.2794)
			(stroke
				(width 0.1)
				(type default)
			)
			(layer "B.Fab")
		)
		(fp_line
			(start 0.12065 -0.2794)
			(end -0.12065 -0.2794)
			(stroke
				(width 0.1)
				(type default)
			)
			(layer "B.Fab")
		)
		(fp_line
			(start 0.12065 0.2794)
			(end 0.12065 0.3048)
			(stroke
				(width 0.1)
				(type default)
			)
			(layer "B.Fab")
		)
		(fp_line
			(start 0.12065 0.3048)
			(end 0.67945 0.3048)
			(stroke
				(width 0.1)
				(type default)
			)
			(layer "B.Fab")
		)
		(fp_line
			(start 0.67945 -0.305054)
			(end 0.12065 -0.305054)
			(stroke
				(width 0.1)
				(type default)
			)
			(layer "B.Fab")
		)
		(fp_line
			(start 0.67945 0.3048)
			(end 0.67945 -0.305054)
			(stroke
				(width 0.1)
				(type default)
			)
			(layer "B.Fab")
		)
		(pad "1" smd circle
			(at 0.40005 0 180)
			(size 0 0)
			(layers "B.Cu" "B.Mask" "B.Paste")
			(net "P52V_HS1_SIO")
		)
		(pad "2" smd circle
			(at -0.40005 0 180)
			(size 0 0)
			(layers "B.Cu" "B.Mask" "B.Paste")
			(net "GND_FIELD_SIGNAL")
		)
	)
	(footprint ""
		(layer "B.Cu")
		(at 191.1604 -52.832 90)
		(property "Reference" "PD11"
			(at 7.84733 2.5146 0)
			(unlocked yes)
			(layer "B.SilkS")
			(effects
				(font
					(size 0.7874 0.5842)
					(thickness 0.1524)
				)
				(justify left mirror)
			)
		)
		(property "Value" ""
			(at 0 0 90)
			(layer "B.Fab")
			(effects
				(font
					(size 1.27 1.27)
				)
				(justify mirror)
			)
		)
		(duplicate_pad_numbers_are_jumpers no)
		(fp_line
			(start 4.664456 -3.109976)
			(end -4.743704 -3.109976)
			(stroke
				(width 0.1524)
				(type default)
			)
			(layer "B.SilkS")
		)
		(fp_line
			(start -4.183126 -3.109976)
			(end -4.794504 -3.109976)
			(stroke
				(width 0.1524)
				(type default)
			)
			(layer "B.SilkS")
		)
		(fp_line
			(start -4.511802 -3.109976)
			(end -4.207002 -3.109976)
			(stroke
				(width 0.1524)
				(type default)
			)
			(layer "B.SilkS")
		)
		(fp_line
			(start -4.6101 -3.109976)
			(end -4.283202 -3.109976)
			(stroke
				(width 0.1524)
				(type default)
			)
			(layer "B.SilkS")
		)
		(fp_line
			(start -4.695444 -3.109976)
			(end -4.695444 3.109976)
			(stroke
				(width 0.1524)
				(type default)
			)
			(layer "B.SilkS")
		)
		(fp_line
			(start -4.70535 -3.109976)
			(end -4.70535 3.109976)
			(stroke
				(width 0.1524)
				(type default)
			)
			(layer "B.SilkS")
		)
		(fp_line
			(start -4.70535 -3.109976)
			(end -4.70535 3.109976)
			(stroke
				(width 0.1524)
				(type default)
			)
			(layer "B.SilkS")
		)
		(fp_line
			(start -4.70535 -3.109976)
			(end -4.70535 3.109976)
			(stroke
				(width 0.1524)
				(type default)
			)
			(layer "B.SilkS")
		)
		(fp_line
			(start -4.805426 -3.109976)
			(end -4.805426 3.109976)
			(stroke
				(width 0.1524)
				(type default)
			)
			(layer "B.SilkS")
		)
		(fp_line
			(start -4.932426 -3.109976)
			(end -4.932426 3.109976)
			(stroke
				(width 0.1524)
				(type default)
			)
			(layer "B.SilkS")
		)
		(fp_line
			(start -5.008626 -3.109976)
			(end -5.008626 3.109976)
			(stroke
				(width 0.1524)
				(type default)
			)
			(layer "B.SilkS")
		)
		(fp_line
			(start -5.110226 -3.109976)
			(end -5.110226 3.109976)
			(stroke
				(width 0.1524)
				(type default)
			)
			(layer "B.SilkS")
		)
		(fp_line
			(start -5.211826 -3.109976)
			(end -5.211826 3.109976)
			(stroke
				(width 0.1524)
				(type default)
			)
			(layer "B.SilkS")
		)
		(fp_line
			(start -5.262626 -3.109976)
			(end -5.262626 3.109976)
			(stroke
				(width 0.1524)
				(type default)
			)
			(layer "B.SilkS")
		)
		(fp_line
			(start -5.313426 -3.109976)
			(end -5.313426 1.0668)
			(stroke
				(width 0.1524)
				(type default)
			)
			(layer "B.SilkS")
		)
		(fp_line
			(start -5.4102 -3.109976)
			(end -4.783074 -3.109976)
			(stroke
				(width 0.1524)
				(type default)
			)
			(layer "B.SilkS")
		)
		(fp_line
			(start 0.508 -1.016)
			(end -0.762 0)
			(stroke
				(width 0.1524)
				(type default)
			)
			(layer "B.SilkS")
		)
		(fp_line
			(start 1.0668 0)
			(end 0.6096 0)
			(stroke
				(width 0.1524)
				(type default)
			)
			(layer "B.SilkS")
		)
		(fp_line
			(start -0.762 0)
			(end -1.2192 0)
			(stroke
				(width 0.1524)
				(type default)
			)
			(layer "B.SilkS")
		)
		(fp_line
			(start -0.762 0)
			(end 0.508 1.016)
			(stroke
				(width 0.1524)
				(type default)
			)
			(layer "B.SilkS")
		)
		(fp_line
			(start 0.508 1.016)
			(end 0.508 -1.016)
			(stroke
				(width 0.1524)
				(type default)
			)
			(layer "B.SilkS")
		)
		(fp_line
			(start -5.4102 1.0668)
			(end -5.4102 -3.109976)
			(stroke
				(width 0.1524)
				(type default)
			)
			(layer "B.SilkS")
		)
		(fp_line
			(start -0.762 1.27)
			(end -0.762 -1.27)
			(stroke
				(width 0.1524)
				(type default)
			)
			(layer "B.SilkS")
		)
		(fp_line
			(start -5.313426 2.0066)
			(end -5.313426 3.109976)
			(stroke
				(width 0.1524)
				(type default)
			)
			(layer "B.SilkS")
		)
		(fp_line
			(start -4.715002 3.035554)
			(end -4.7117 2.984754)
			(stroke
				(width 0.1524)
				(type default)
			)
			(layer "B.SilkS")
		)
		(fp_line
			(start 4.664456 3.109976)
			(end 4.664456 -3.109976)
			(stroke
				(width 0.1524)
				(type default)
			)
			(layer "B.SilkS")
		)
		(fp_line
			(start -4.156202 3.109976)
			(end -4.183126 3.109976)
			(stroke
				(width 0.1524)
				(type default)
			)
			(layer "B.SilkS")
		)
		(fp_line
			(start -4.743704 3.109976)
			(end -4.6101 3.109976)
			(stroke
				(width 0.1524)
				(type default)
			)
			(layer "B.SilkS")
		)
		(fp_line
			(start -4.743704 3.109976)
			(end -5.4102 3.109976)
			(stroke
				(width 0.1524)
				(type default)
			)
			(layer "B.SilkS")
		)
		(fp_line
			(start -4.769104 3.109976)
			(end 4.664456 3.109976)
			(stroke
				(width 0.1524)
				(type default)
			)
			(layer "B.SilkS")
		)
		(fp_line
			(start -4.794504 3.109976)
			(end -3.554984 3.109976)
			(stroke
				(width 0.1524)
				(type default)
			)
			(layer "B.SilkS")
		)
		(fp_line
			(start -5.4102 3.109976)
			(end -5.4102 2.0066)
			(stroke
				(width 0.1524)
				(type default)
			)
			(layer "B.SilkS")
		)
		(fp_line
			(start 4.065016 -3.109976)
			(end -4.065016 -3.109976)
			(stroke
				(width 0.1)
				(type default)
			)
			(layer "B.Fab")
		)
		(fp_line
			(start -4.065016 -3.109976)
			(end -4.065016 3.109976)
			(stroke
				(width 0.1)
				(type default)
			)
			(layer "B.Fab")
		)
		(fp_line
			(start 4.065016 3.109976)
			(end 4.065016 -3.109976)
			(stroke
				(width 0.1)
				(type default)
			)
			(layer "B.Fab")
		)
		(fp_line
			(start -4.065016 3.109976)
			(end 4.065016 3.109976)
			(stroke
				(width 0.1)
				(type default)
			)
			(layer "B.Fab")
		)
		(fp_text user "-"
			(at -7.493 0.32385 270)
			(unlocked yes)
			(layer "B.SilkS")
			(effects
				(font
					(size 1.905 1.4224)
					(thickness 0.1524)
				)
				(justify left mirror)
			)
		)
		(fp_text user "+"
			(at 5.9944 0.37465 270)
			(unlocked yes)
			(layer "B.SilkS")
			(effects
				(font
					(size 1.905 1.4224)
					(thickness 0.1524)
				)
				(justify left mirror)
			)
		)
		(fp_text user "+"
			(at 4.5974 0.24765 270)
			(unlocked yes)
			(layer "B.Fab")
			(effects
				(font
					(size 1.905 1.4224)
					(thickness 0.1524)
				)
				(justify left mirror)
			)
		)
		(fp_text user "-"
			(at -6.643624 0.40005 270)
			(unlocked yes)
			(layer "B.Fab")
			(effects
				(font
					(size 1.905 1.4224)
					(thickness 0.1524)
				)
				(justify left mirror)
			)
		)
		(pad "A" smd rect
			(at 3.299968 0 90)
			(size 2.413 3.302)
			(layers "B.Cu" "B.Mask" "B.Paste")
			(net "GND")
		)
		(pad "C" smd rect
			(at -3.299968 0 90)
			(size 2.413 3.302)
			(layers "B.Cu" "B.Mask" "B.Paste")
			(net "P52V_2_FUSE_1")
		)
	)
	(footprint ""
		(layer "B.Cu")
		(at 249.047 -52.832 90)
		(property "Reference" "PD9"
			(at 5.334 -2.69367 270)
			(unlocked yes)
			(layer "B.SilkS")
			(effects
				(font
					(size 0.7874 0.5842)
					(thickness 0.1524)
				)
				(justify left mirror)
			)
		)
		(property "Value" ""
			(at 0 0 90)
			(layer "B.Fab")
			(effects
				(font
					(size 1.27 1.27)
				)
				(justify mirror)
			)
		)
		(duplicate_pad_numbers_are_jumpers no)
		(fp_line
			(start 4.664456 -3.109976)
			(end -4.743704 -3.109976)
			(stroke
				(width 0.1524)
				(type default)
			)
			(layer "B.SilkS")
		)
		(fp_line
			(start -4.183126 -3.109976)
			(end -4.794504 -3.109976)
			(stroke
				(width 0.1524)
				(type default)
			)
			(layer "B.SilkS")
		)
		(fp_line
			(start -4.511802 -3.109976)
			(end -4.207002 -3.109976)
			(stroke
				(width 0.1524)
				(type default)
			)
			(layer "B.SilkS")
		)
		(fp_line
			(start -4.6101 -3.109976)
			(end -4.283202 -3.109976)
			(stroke
				(width 0.1524)
				(type default)
			)
			(layer "B.SilkS")
		)
		(fp_line
			(start -4.695444 -3.109976)
			(end -4.695444 3.109976)
			(stroke
				(width 0.1524)
				(type default)
			)
			(layer "B.SilkS")
		)
		(fp_line
			(start -4.70535 -3.109976)
			(end -4.70535 3.109976)
			(stroke
				(width 0.1524)
				(type default)
			)
			(layer "B.SilkS")
		)
		(fp_line
			(start -4.70535 -3.109976)
			(end -4.70535 3.109976)
			(stroke
				(width 0.1524)
				(type default)
			)
			(layer "B.SilkS")
		)
		(fp_line
			(start -4.70535 -3.109976)
			(end -4.70535 3.109976)
			(stroke
				(width 0.1524)
				(type default)
			)
			(layer "B.SilkS")
		)
		(fp_line
			(start -4.805426 -3.109976)
			(end -4.805426 3.109976)
			(stroke
				(width 0.1524)
				(type default)
			)
			(layer "B.SilkS")
		)
		(fp_line
			(start -4.932426 -3.109976)
			(end -4.932426 3.109976)
			(stroke
				(width 0.1524)
				(type default)
			)
			(layer "B.SilkS")
		)
		(fp_line
			(start -5.008626 -3.109976)
			(end -5.008626 3.109976)
			(stroke
				(width 0.1524)
				(type default)
			)
			(layer "B.SilkS")
		)
		(fp_line
			(start -5.110226 -3.109976)
			(end -5.110226 3.109976)
			(stroke
				(width 0.1524)
				(type default)
			)
			(layer "B.SilkS")
		)
		(fp_line
			(start -5.211826 -3.109976)
			(end -5.211826 3.109976)
			(stroke
				(width 0.1524)
				(type default)
			)
			(layer "B.SilkS")
		)
		(fp_line
			(start -5.262626 -3.109976)
			(end -5.262626 3.109976)
			(stroke
				(width 0.1524)
				(type default)
			)
			(layer "B.SilkS")
		)
		(fp_line
			(start -5.313426 -3.109976)
			(end -5.313426 -2.1082)
			(stroke
				(width 0.1524)
				(type default)
			)
			(layer "B.SilkS")
		)
		(fp_line
			(start -5.4102 -3.109976)
			(end -4.783074 -3.109976)
			(stroke
				(width 0.1524)
				(type default)
			)
			(layer "B.SilkS")
		)
		(fp_line
			(start -5.4102 -2.3368)
			(end -5.4102 -3.109976)
			(stroke
				(width 0.1524)
				(type default)
			)
			(layer "B.SilkS")
		)
		(fp_line
			(start 0.508 -1.016)
			(end -0.762 0)
			(stroke
				(width 0.1524)
				(type default)
			)
			(layer "B.SilkS")
		)
		(fp_line
			(start -5.313426 -0.9398)
			(end -5.313426 3.109976)
			(stroke
				(width 0.1524)
				(type default)
			)
			(layer "B.SilkS")
		)
		(fp_line
			(start 1.0668 0)
			(end 0.6096 0)
			(stroke
				(width 0.1524)
				(type default)
			)
			(layer "B.SilkS")
		)
		(fp_line
			(start -0.762 0)
			(end -1.2192 0)
			(stroke
				(width 0.1524)
				(type default)
			)
			(layer "B.SilkS")
		)
		(fp_line
			(start -0.762 0)
			(end 0.508 1.016)
			(stroke
				(width 0.1524)
				(type default)
			)
			(layer "B.SilkS")
		)
		(fp_line
			(start 0.508 1.016)
			(end 0.508 -1.016)
			(stroke
				(width 0.1524)
				(type default)
			)
			(layer "B.SilkS")
		)
		(fp_line
			(start -0.762 1.27)
			(end -0.762 -1.27)
			(stroke
				(width 0.1524)
				(type default)
			)
			(layer "B.SilkS")
		)
		(fp_line
			(start -4.715002 3.035554)
			(end -4.7117 2.984754)
			(stroke
				(width 0.1524)
				(type default)
			)
			(layer "B.SilkS")
		)
		(fp_line
			(start 4.664456 3.109976)
			(end 4.664456 -3.109976)
			(stroke
				(width 0.1524)
				(type default)
			)
			(layer "B.SilkS")
		)
		(fp_line
			(start -4.156202 3.109976)
			(end -4.183126 3.109976)
			(stroke
				(width 0.1524)
				(type default)
			)
			(layer "B.SilkS")
		)
		(fp_line
			(start -4.743704 3.109976)
			(end -4.6101 3.109976)
			(stroke
				(width 0.1524)
				(type default)
			)
			(layer "B.SilkS")
		)
		(fp_line
			(start -4.743704 3.109976)
			(end -5.4102 3.109976)
			(stroke
				(width 0.1524)
				(type default)
			)
			(layer "B.SilkS")
		)
		(fp_line
			(start -4.769104 3.109976)
			(end 4.664456 3.109976)
			(stroke
				(width 0.1524)
				(type default)
			)
			(layer "B.SilkS")
		)
		(fp_line
			(start -4.794504 3.109976)
			(end -3.554984 3.109976)
			(stroke
				(width 0.1524)
				(type default)
			)
			(layer "B.SilkS")
		)
		(fp_line
			(start -5.4102 3.109976)
			(end -5.4102 -0.7366)
			(stroke
				(width 0.1524)
				(type default)
			)
			(layer "B.SilkS")
		)
		(fp_line
			(start 4.065016 -3.109976)
			(end -4.065016 -3.109976)
			(stroke
				(width 0.1)
				(type default)
			)
			(layer "B.Fab")
		)
		(fp_line
			(start -4.065016 -3.109976)
			(end -4.065016 3.109976)
			(stroke
				(width 0.1)
				(type default)
			)
			(layer "B.Fab")
		)
		(fp_line
			(start 4.065016 3.109976)
			(end 4.065016 -3.109976)
			(stroke
				(width 0.1)
				(type default)
			)
			(layer "B.Fab")
		)
		(fp_line
			(start -4.065016 3.109976)
			(end 4.065016 3.109976)
			(stroke
				(width 0.1)
				(type default)
			)
			(layer "B.Fab")
		)
		(fp_text user "+"
			(at 6.1976 0.37465 270)
			(unlocked yes)
			(layer "B.SilkS")
			(effects
				(font
					(size 1.905 1.4224)
					(thickness 0.1524)
				)
				(justify left mirror)
			)
		)
		(fp_text user "-"
			(at -7.405624 0.65405 270)
			(unlocked yes)
			(layer "B.SilkS")
			(effects
				(font
					(size 1.905 1.4224)
					(thickness 0.1524)
				)
				(justify left mirror)
			)
		)
		(fp_text user "+"
			(at 4.5974 0.24765 270)
			(unlocked yes)
			(layer "B.Fab")
			(effects
				(font
					(size 1.905 1.4224)
					(thickness 0.1524)
				)
				(justify left mirror)
			)
		)
		(fp_text user "-"
			(at -6.643624 0.40005 270)
			(unlocked yes)
			(layer "B.Fab")
			(effects
				(font
					(size 1.905 1.4224)
					(thickness 0.1524)
				)
				(justify left mirror)
			)
		)
		(pad "A" smd rect
			(at 3.299968 0 90)
			(size 2.413 3.302)
			(layers "B.Cu" "B.Mask" "B.Paste")
			(net "GND")
		)
		(pad "C" smd rect
			(at -3.299968 0 90)
			(size 2.413 3.302)
			(layers "B.Cu" "B.Mask" "B.Paste")
			(net "P52V_1_FUSE_1")
		)
	)
	(footprint ""
		(layer "B.Cu")
		(at 341.5792 -38.7858 -90)
		(property "Reference" "PR6999"
			(at 0 0 90)
			(layer "B.SilkS")
			(hide yes)
			(effects
				(font
					(size 1.27 1.27)
				)
				(justify mirror)
			)
		)
		(property "Value" ""
			(at 0 0 90)
			(layer "B.Fab")
			(effects
				(font
					(size 1.27 1.27)
				)
				(justify mirror)
			)
		)
		(duplicate_pad_numbers_are_jumpers no)
		(fp_line
			(start -1.2954 0.5842)
			(end 1.2954 0.5842)
			(stroke
				(width 0.1524)
				(type default)
			)
			(layer "B.SilkS")
		)
		(fp_line
			(start 1.2954 0.5842)
			(end 1.2954 -0.5842)
			(stroke
				(width 0.1524)
				(type default)
			)
			(layer "B.SilkS")
		)
		(fp_line
			(start -1.2954 -0.5842)
			(end -1.2954 0.5842)
			(stroke
				(width 0.1524)
				(type default)
			)
			(layer "B.SilkS")
		)
		(fp_line
			(start 1.2954 -0.5842)
			(end -1.2954 -0.5842)
			(stroke
				(width 0.1524)
				(type default)
			)
			(layer "B.SilkS")
		)
		(fp_line
			(start -0.8636 0.4572)
			(end 0.8636 0.4572)
			(stroke
				(width 0.1)
				(type default)
			)
			(layer "B.Fab")
		)
		(fp_line
			(start 0.8636 0.4572)
			(end 0.8636 0.4318)
			(stroke
				(width 0.1)
				(type default)
			)
			(layer "B.Fab")
		)
		(fp_line
			(start 0.8636 0.4318)
			(end 0.8636 0.4064)
			(stroke
				(width 0.1)
				(type default)
			)
			(layer "B.Fab")
		)
		(fp_line
			(start -1.1938 0.4064)
			(end -0.8636 0.4064)
			(stroke
				(width 0.1)
				(type default)
			)
			(layer "B.Fab")
		)
		(fp_line
			(start -0.8636 0.4064)
			(end -0.8636 0.4572)
			(stroke
				(width 0.1)
				(type default)
			)
			(layer "B.Fab")
		)
		(fp_line
			(start 0.8636 0.4064)
			(end 1.1938 0.4064)
			(stroke
				(width 0.1)
				(type default)
			)
			(layer "B.Fab")
		)
		(fp_line
			(start 1.1938 0.4064)
			(end 1.1938 -0.406654)
			(stroke
				(width 0.1)
				(type default)
			)
			(layer "B.Fab")
		)
		(fp_line
			(start -1.1938 -0.406654)
			(end -1.1938 0.4064)
			(stroke
				(width 0.1)
				(type default)
			)
			(layer "B.Fab")
		)
		(fp_line
			(start -0.8636 -0.406654)
			(end -1.1938 -0.406654)
			(stroke
				(width 0.1)
				(type default)
			)
			(layer "B.Fab")
		)
		(fp_line
			(start 0.8636 -0.406654)
			(end 0.8636 -0.4572)
			(stroke
				(width 0.1)
				(type default)
			)
			(layer "B.Fab")
		)
		(fp_line
			(start 1.1938 -0.406654)
			(end 0.8636 -0.406654)
			(stroke
				(width 0.1)
				(type default)
			)
			(layer "B.Fab")
		)
		(fp_line
			(start -0.8636 -0.4572)
			(end -0.8636 -0.406654)
			(stroke
				(width 0.1)
				(type default)
			)
			(layer "B.Fab")
		)
		(fp_line
			(start 0.8636 -0.4572)
			(end -0.8636 -0.4572)
			(stroke
				(width 0.1)
				(type default)
			)
			(layer "B.Fab")
		)
		(pad "1" smd rect
			(at 0.7366 0 180)
			(size 0.7112 0.8128)
			(layers "B.Cu" "B.Mask" "B.Paste")
			(net "P52V_HS1_4287_GATE2_R")
		)
		(pad "2" smd rect
			(at -0.7366 0 180)
			(size 0.7112 0.8128)
			(layers "B.Cu" "B.Mask" "B.Paste")
			(net "P52V_HS1_4287_GATE2_RC")
		)
	)
	(footprint ""
		(layer "B.Cu")
		(at 278.4094 -65.913)
		(property "Reference" "R144"
			(at 0 0 0)
			(layer "B.SilkS")
			(hide yes)
			(effects
				(font
					(size 1.27 1.27)
				)
				(justify mirror)
			)
		)
		(property "Value" ""
			(at 0 0 0)
			(layer "B.Fab")
			(effects
				(font
					(size 1.27 1.27)
				)
				(justify mirror)
			)
		)
		(duplicate_pad_numbers_are_jumpers no)
		(fp_line
			(start -0.7874 -0.4064)
			(end -0.7874 0.4064)
			(stroke
				(width 0.1524)
				(type default)
			)
			(layer "B.SilkS")
		)
		(fp_line
			(start -0.7874 0.4064)
			(end 0.7874 0.4064)
			(stroke
				(width 0.1524)
				(type default)
			)
			(layer "B.SilkS")
		)
		(fp_line
			(start 0.7874 -0.4064)
			(end -0.7874 -0.4064)
			(stroke
				(width 0.1524)
				(type default)
			)
			(layer "B.SilkS")
		)
		(fp_line
			(start 0.7874 0.4064)
			(end 0.7874 -0.4064)
			(stroke
				(width 0.1524)
				(type default)
			)
			(layer "B.SilkS")
		)
		(fp_line
			(start -0.67945 -0.3048)
			(end -0.67945 0.3048)
			(stroke
				(width 0.1)
				(type default)
			)
			(layer "B.Fab")
		)
		(fp_line
			(start -0.67945 0.3048)
			(end -0.120396 0.3048)
			(stroke
				(width 0.1)
				(type default)
			)
			(layer "B.Fab")
		)
		(fp_line
			(start -0.12065 -0.3048)
			(end -0.67945 -0.3048)
			(stroke
				(width 0.1)
				(type default)
			)
			(layer "B.Fab")
		)
		(fp_line
			(start -0.12065 -0.2794)
			(end -0.12065 -0.3048)
			(stroke
				(width 0.1)
				(type default)
			)
			(layer "B.Fab")
		)
		(fp_line
			(start -0.120396 0.2794)
			(end 0.12065 0.2794)
			(stroke
				(width 0.1)
				(type default)
			)
			(layer "B.Fab")
		)
		(fp_line
			(start -0.120396 0.3048)
			(end -0.120396 0.2794)
			(stroke
				(width 0.1)
				(type default)
			)
			(layer "B.Fab")
		)
		(fp_line
			(start 0.12065 -0.305054)
			(end 0.12065 -0.2794)
			(stroke
				(width 0.1)
				(type default)
			)
			(layer "B.Fab")
		)
		(fp_line
			(start 0.12065 -0.2794)
			(end -0.12065 -0.2794)
			(stroke
				(width 0.1)
				(type default)
			)
			(layer "B.Fab")
		)
		(fp_line
			(start 0.12065 0.2794)
			(end 0.12065 0.3048)
			(stroke
				(width 0.1)
				(type default)
			)
			(layer "B.Fab")
		)
		(fp_line
			(start 0.12065 0.3048)
			(end 0.67945 0.3048)
			(stroke
				(width 0.1)
				(type default)
			)
			(layer "B.Fab")
		)
		(fp_line
			(start 0.67945 -0.305054)
			(end 0.12065 -0.305054)
			(stroke
				(width 0.1)
				(type default)
			)
			(layer "B.Fab")
		)
		(fp_line
			(start 0.67945 0.3048)
			(end 0.67945 -0.305054)
			(stroke
				(width 0.1)
				(type default)
			)
			(layer "B.Fab")
		)
		(pad "1" smd circle
			(at 0.40005 0 180)
			(size 0 0)
			(layers "B.Cu" "B.Mask" "B.Paste")
			(net "SMB_P52V_PDB_SDA")
		)
		(pad "2" smd circle
			(at -0.40005 0 180)
			(size 0 0)
			(layers "B.Cu" "B.Mask" "B.Paste")
			(net "SMB_CM_HS1_3V3SB_DATI")
		)
	)
	(footprint ""
		(layer "B.Cu")
		(at 287.6804 -68.58)
		(property "Reference" "PR212"
			(at 0 0 0)
			(layer "B.SilkS")
			(hide yes)
			(effects
				(font
					(size 1.27 1.27)
				)
				(justify mirror)
			)
		)
		(property "Value" ""
			(at 0 0 0)
			(layer "B.Fab")
			(effects
				(font
					(size 1.27 1.27)
				)
				(justify mirror)
			)
		)
		(duplicate_pad_numbers_are_jumpers no)
		(fp_line
			(start -0.7874 -0.4064)
			(end -0.7874 0.4064)
			(stroke
				(width 0.1524)
				(type default)
			)
			(layer "B.SilkS")
		)
		(fp_line
			(start -0.7874 0.4064)
			(end 0.7874 0.4064)
			(stroke
				(width 0.1524)
				(type default)
			)
			(layer "B.SilkS")
		)
		(fp_line
			(start 0.7874 -0.4064)
			(end -0.7874 -0.4064)
			(stroke
				(width 0.1524)
				(type default)
			)
			(layer "B.SilkS")
		)
		(fp_line
			(start 0.7874 0.4064)
			(end 0.7874 -0.4064)
			(stroke
				(width 0.1524)
				(type default)
			)
			(layer "B.SilkS")
		)
		(fp_line
			(start -0.67945 -0.3048)
			(end -0.67945 0.3048)
			(stroke
				(width 0.1)
				(type default)
			)
			(layer "B.Fab")
		)
		(fp_line
			(start -0.67945 0.3048)
			(end -0.120396 0.3048)
			(stroke
				(width 0.1)
				(type default)
			)
			(layer "B.Fab")
		)
		(fp_line
			(start -0.12065 -0.3048)
			(end -0.67945 -0.3048)
			(stroke
				(width 0.1)
				(type default)
			)
			(layer "B.Fab")
		)
		(fp_line
			(start -0.12065 -0.2794)
			(end -0.12065 -0.3048)
			(stroke
				(width 0.1)
				(type default)
			)
			(layer "B.Fab")
		)
		(fp_line
			(start -0.120396 0.2794)
			(end 0.12065 0.2794)
			(stroke
				(width 0.1)
				(type default)
			)
			(layer "B.Fab")
		)
		(fp_line
			(start -0.120396 0.3048)
			(end -0.120396 0.2794)
			(stroke
				(width 0.1)
				(type default)
			)
			(layer "B.Fab")
		)
		(fp_line
			(start 0.12065 -0.305054)
			(end 0.12065 -0.2794)
			(stroke
				(width 0.1)
				(type default)
			)
			(layer "B.Fab")
		)
		(fp_line
			(start 0.12065 -0.2794)
			(end -0.12065 -0.2794)
			(stroke
				(width 0.1)
				(type default)
			)
			(layer "B.Fab")
		)
		(fp_line
			(start 0.12065 0.2794)
			(end 0.12065 0.3048)
			(stroke
				(width 0.1)
				(type default)
			)
			(layer "B.Fab")
		)
		(fp_line
			(start 0.12065 0.3048)
			(end 0.67945 0.3048)
			(stroke
				(width 0.1)
				(type default)
			)
			(layer "B.Fab")
		)
		(fp_line
			(start 0.67945 -0.305054)
			(end 0.12065 -0.305054)
			(stroke
				(width 0.1)
				(type default)
			)
			(layer "B.Fab")
		)
		(fp_line
			(start 0.67945 0.3048)
			(end 0.67945 -0.305054)
			(stroke
				(width 0.1)
				(type default)
			)
			(layer "B.Fab")
		)
		(pad "1" smd circle
			(at 0.40005 0 180)
			(size 0 0)
			(layers "B.Cu" "B.Mask" "B.Paste")
			(net "P52V_HS1_SIO")
		)
		(pad "2" smd circle
			(at -0.40005 0 180)
			(size 0 0)
			(layers "B.Cu" "B.Mask" "B.Paste")
			(net "P52V_HS1_INTVCC")
		)
	)
	(footprint ""
		(layer "B.Cu")
		(at 293.2684 -80.01 -90)
		(property "Reference" "PJ1"
			(at -0.254 -1.34493 270)
			(unlocked yes)
			(layer "B.SilkS")
			(effects
				(font
					(size 0.7874 0.5842)
					(thickness 0.1524)
				)
				(justify left mirror)
			)
		)
		(property "Value" ""
			(at 0 0 90)
			(layer "B.Fab")
			(effects
				(font
					(size 1.27 1.27)
				)
				(justify mirror)
			)
		)
		(duplicate_pad_numbers_are_jumpers no)
		(pad "1" smd circle
			(at 0.7493 0)
			(size 0 0)
			(layers "B.Cu" "B.Mask" "B.Paste")
			(net "GND_FIELD_SIGNAL")
		)
		(pad "2" smd rect
			(at -0.7493 0 180)
			(size 0.7112 0.8128)
			(layers "B.Cu" "B.Mask" "B.Paste")
			(net "GND")
		)
		(zone
			(layer "B.Cu")
			(hatch none 0.5)
			(connect_pads
				(clearance 0)
			)
			(min_thickness 0.25)
			(keepout
				(tracks allowed)
				(vias not_allowed)
				(pads allowed)
				(copperpour not_allowed)
				(footprints allowed)
			)
			(placement
				(enabled no)
				(sheetname "")
			)
			(fill
				(thermal_gap 0.5)
				(thermal_bridge_width 0.5)
				(island_removal_mode 0)
			)
			(polygon
				(pts
					(xy 293.6748 -81.2165) (xy 292.857174 -81.2165) (xy 292.857174 -78.8289) (xy 293.6748 -78.8289)
				)
			)
		)
	)
	(footprint ""
		(layer "B.Cu")
		(at 106.1974 -57.023 180)
		(property "Reference" "PC592"
			(at 0 0 0)
			(layer "B.SilkS")
			(hide yes)
			(effects
				(font
					(size 1.27 1.27)
				)
				(justify mirror)
			)
		)
		(property "Value" ""
			(at 0 0 0)
			(layer "B.Fab")
			(effects
				(font
					(size 1.27 1.27)
				)
				(justify mirror)
			)
		)
		(duplicate_pad_numbers_are_jumpers no)
		(fp_line
			(start 1.2954 0.5842)
			(end 1.2954 -0.5842)
			(stroke
				(width 0.1524)
				(type default)
			)
			(layer "B.SilkS")
		)
		(fp_line
			(start 1.2954 -0.5842)
			(end -1.2954 -0.5842)
			(stroke
				(width 0.1524)
				(type default)
			)
			(layer "B.SilkS")
		)
		(fp_line
			(start -1.2954 0.5842)
			(end 1.2954 0.5842)
			(stroke
				(width 0.1524)
				(type default)
			)
			(layer "B.SilkS")
		)
		(fp_line
			(start -1.2954 -0.5842)
			(end -1.2954 0.5842)
			(stroke
				(width 0.1524)
				(type default)
			)
			(layer "B.SilkS")
		)
		(fp_line
			(start 1.1938 0.4064)
			(end 1.1938 -0.4064)
			(stroke
				(width 0.1)
				(type default)
			)
			(layer "B.Fab")
		)
		(fp_line
			(start 1.1938 -0.4064)
			(end 0.8636 -0.4064)
			(stroke
				(width 0.1)
				(type default)
			)
			(layer "B.Fab")
		)
		(fp_line
			(start 0.8636 0.4572)
			(end 0.8636 0.4064)
			(stroke
				(width 0.1)
				(type default)
			)
			(layer "B.Fab")
		)
		(fp_line
			(start 0.8636 0.4064)
			(end 1.1938 0.4064)
			(stroke
				(width 0.1)
				(type default)
			)
			(layer "B.Fab")
		)
		(fp_line
			(start 0.8636 -0.4064)
			(end 0.8636 -0.4572)
			(stroke
				(width 0.1)
				(type default)
			)
			(layer "B.Fab")
		)
		(fp_line
			(start 0.8636 -0.4572)
			(end -0.8636 -0.4572)
			(stroke
				(width 0.1)
				(type default)
			)
			(layer "B.Fab")
		)
		(fp_line
			(start -0.8636 0.4572)
			(end 0.8636 0.4572)
			(stroke
				(width 0.1)
				(type default)
			)
			(layer "B.Fab")
		)
		(fp_line
			(start -0.8636 0.4064)
			(end -0.8636 0.4572)
			(stroke
				(width 0.1)
				(type default)
			)
			(layer "B.Fab")
		)
		(fp_line
			(start -0.8636 -0.4064)
			(end -1.1938 -0.4064)
			(stroke
				(width 0.1)
				(type default)
			)
			(layer "B.Fab")
		)
		(fp_line
			(start -0.8636 -0.4572)
			(end -0.8636 -0.4064)
			(stroke
				(width 0.1)
				(type default)
			)
			(layer "B.Fab")
		)
		(fp_line
			(start -1.1938 0.4064)
			(end -0.8636 0.4064)
			(stroke
				(width 0.1)
				(type default)
			)
			(layer "B.Fab")
		)
		(fp_line
			(start -1.1938 -0.4064)
			(end -1.1938 0.4064)
			(stroke
				(width 0.1)
				(type default)
			)
			(layer "B.Fab")
		)
		(pad "1" smd rect
			(at 0.7366 0 90)
			(size 0.7112 0.8128)
			(layers "B.Cu" "B.Mask" "B.Paste")
			(net "GND")
		)
		(pad "2" smd rect
			(at -0.7366 0 90)
			(size 0.7112 0.8128)
			(layers "B.Cu" "B.Mask" "B.Paste")
			(net "P52V_HS2_GATE_R1")
		)
	)
	(footprint ""
		(layer "B.Cu")
		(at 111.2774 -55.626 90)
		(property "Reference" "R5866"
			(at 0 0 90)
			(layer "B.SilkS")
			(hide yes)
			(effects
				(font
					(size 1.27 1.27)
				)
				(justify mirror)
			)
		)
		(property "Value" ""
			(at 0 0 90)
			(layer "B.Fab")
			(effects
				(font
					(size 1.27 1.27)
				)
				(justify mirror)
			)
		)
		(duplicate_pad_numbers_are_jumpers no)
		(fp_line
			(start 0.7874 -0.4064)
			(end -0.7874 -0.4064)
			(stroke
				(width 0.1524)
				(type default)
			)
			(layer "B.SilkS")
		)
		(fp_line
			(start -0.7874 -0.4064)
			(end -0.7874 0.4064)
			(stroke
				(width 0.1524)
				(type default)
			)
			(layer "B.SilkS")
		)
		(fp_line
			(start 0.7874 0.4064)
			(end 0.7874 -0.4064)
			(stroke
				(width 0.1524)
				(type default)
			)
			(layer "B.SilkS")
		)
		(fp_line
			(start -0.7874 0.4064)
			(end 0.7874 0.4064)
			(stroke
				(width 0.1524)
				(type default)
			)
			(layer "B.SilkS")
		)
		(fp_line
			(start 0.67945 -0.305054)
			(end 0.12065 -0.305054)
			(stroke
				(width 0.1)
				(type default)
			)
			(layer "B.Fab")
		)
		(fp_line
			(start 0.12065 -0.305054)
			(end 0.12065 -0.2794)
			(stroke
				(width 0.1)
				(type default)
			)
			(layer "B.Fab")
		)
		(fp_line
			(start -0.12065 -0.3048)
			(end -0.67945 -0.3048)
			(stroke
				(width 0.1)
				(type default)
			)
			(layer "B.Fab")
		)
		(fp_line
			(start -0.67945 -0.3048)
			(end -0.67945 0.3048)
			(stroke
				(width 0.1)
				(type default)
			)
			(layer "B.Fab")
		)
		(fp_line
			(start 0.12065 -0.2794)
			(end -0.12065 -0.2794)
			(stroke
				(width 0.1)
				(type default)
			)
			(layer "B.Fab")
		)
		(fp_line
			(start -0.12065 -0.2794)
			(end -0.12065 -0.3048)
			(stroke
				(width 0.1)
				(type default)
			)
			(layer "B.Fab")
		)
		(fp_line
			(start 0.12065 0.2794)
			(end 0.12065 0.3048)
			(stroke
				(width 0.1)
				(type default)
			)
			(layer "B.Fab")
		)
		(fp_line
			(start -0.120396 0.2794)
			(end 0.12065 0.2794)
			(stroke
				(width 0.1)
				(type default)
			)
			(layer "B.Fab")
		)
		(fp_line
			(start 0.67945 0.3048)
			(end 0.67945 -0.305054)
			(stroke
				(width 0.1)
				(type default)
			)
			(layer "B.Fab")
		)
		(fp_line
			(start 0.12065 0.3048)
			(end 0.67945 0.3048)
			(stroke
				(width 0.1)
				(type default)
			)
			(layer "B.Fab")
		)
		(fp_line
			(start -0.120396 0.3048)
			(end -0.120396 0.2794)
			(stroke
				(width 0.1)
				(type default)
			)
			(layer "B.Fab")
		)
		(fp_line
			(start -0.67945 0.3048)
			(end -0.120396 0.3048)
			(stroke
				(width 0.1)
				(type default)
			)
			(layer "B.Fab")
		)
		(pad "1" smd circle
			(at 0.40005 0 270)
			(size 0 0)
			(layers "B.Cu" "B.Mask" "B.Paste")
			(net "P52V_HS2_GATE1_R")
		)
		(pad "2" smd circle
			(at -0.40005 0 270)
			(size 0 0)
			(layers "B.Cu" "B.Mask" "B.Paste")
			(net "P52V_HS2_1272_GATE")
		)
	)
	(footprint ""
		(layer "B.Cu")
		(at 151.7904 -59.69 180)
		(property "Reference" "PR7005"
			(at 0 0 0)
			(layer "B.SilkS")
			(hide yes)
			(effects
				(font
					(size 1.27 1.27)
				)
				(justify mirror)
			)
		)
		(property "Value" ""
			(at 0 0 0)
			(layer "B.Fab")
			(effects
				(font
					(size 1.27 1.27)
				)
				(justify mirror)
			)
		)
		(duplicate_pad_numbers_are_jumpers no)
		(fp_line
			(start 1.651 0.8382)
			(end 1.651 -0.8382)
			(stroke
				(width 0.1524)
				(type default)
			)
			(layer "B.SilkS")
		)
		(fp_line
			(start 1.651 -0.8382)
			(end -1.651 -0.8382)
			(stroke
				(width 0.1524)
				(type default)
			)
			(layer "B.SilkS")
		)
		(fp_line
			(start -1.651 0.8382)
			(end 1.651 0.8382)
			(stroke
				(width 0.1524)
				(type default)
			)
			(layer "B.SilkS")
		)
		(fp_line
			(start -1.651 -0.8382)
			(end -1.651 0.8382)
			(stroke
				(width 0.1524)
				(type default)
			)
			(layer "B.SilkS")
		)
		(fp_line
			(start 1.559814 0.7366)
			(end 1.524 0.7366)
			(stroke
				(width 0.1)
				(type default)
			)
			(layer "B.Fab")
		)
		(fp_line
			(start 1.559814 -0.7366)
			(end 1.559814 0.7366)
			(stroke
				(width 0.1)
				(type default)
			)
			(layer "B.Fab")
		)
		(fp_line
			(start 1.524 0.7366)
			(end -1.524 0.7366)
			(stroke
				(width 0.1)
				(type default)
			)
			(layer "B.Fab")
		)
		(fp_line
			(start 1.524 -0.7366)
			(end 1.559814 -0.7366)
			(stroke
				(width 0.1)
				(type default)
			)
			(layer "B.Fab")
		)
		(fp_line
			(start -1.524 0.7366)
			(end -1.560576 0.7366)
			(stroke
				(width 0.1)
				(type default)
			)
			(layer "B.Fab")
		)
		(fp_line
			(start -1.524 -0.7366)
			(end 1.524 -0.7366)
			(stroke
				(width 0.1)
				(type default)
			)
			(layer "B.Fab")
		)
		(fp_line
			(start -1.560576 0.7366)
			(end -1.560576 -0.7366)
			(stroke
				(width 0.1)
				(type default)
			)
			(layer "B.Fab")
		)
		(fp_line
			(start -1.560576 -0.7366)
			(end -1.524 -0.7366)
			(stroke
				(width 0.1)
				(type default)
			)
			(layer "B.Fab")
		)
		(pad "1" smd rect
			(at 0.94996 0 180)
			(size 1.1176 1.3716)
			(layers "B.Cu" "B.Mask" "B.Paste")
			(net "P52V_HS2")
		)
		(pad "2" smd rect
			(at -0.94996 0 180)
			(size 1.1176 1.3716)
			(layers "B.Cu" "B.Mask" "B.Paste")
			(net "P52V_HS2_FB")
		)
	)
	(footprint ""
		(layer "B.Cu")
		(at 177.465736 -70.612 180)
		(property "Reference" "PU9"
			(at -3.699764 -5.24637 0)
			(unlocked yes)
			(layer "B.SilkS")
			(effects
				(font
					(size 0.7874 0.5842)
					(thickness 0.1524)
				)
				(justify left mirror)
			)
		)
		(property "Value" ""
			(at 0 0 0)
			(layer "B.Fab")
			(effects
				(font
					(size 1.27 1.27)
				)
				(justify mirror)
			)
		)
		(duplicate_pad_numbers_are_jumpers no)
		(fp_line
			(start 4.05003 3.549904)
			(end 3.5052 3.549904)
			(stroke
				(width 0.1524)
				(type default)
			)
			(layer "B.SilkS")
		)
		(fp_line
			(start 4.05003 3.0226)
			(end 4.05003 3.549904)
			(stroke
				(width 0.1524)
				(type default)
			)
			(layer "B.SilkS")
		)
		(fp_line
			(start 4.05003 -3.549904)
			(end 4.05003 -3.0226)
			(stroke
				(width 0.1524)
				(type default)
			)
			(layer "B.SilkS")
		)
		(fp_line
			(start 3.5052 -3.549904)
			(end 4.05003 -3.549904)
			(stroke
				(width 0.1524)
				(type default)
			)
			(layer "B.SilkS")
		)
		(fp_line
			(start -0.0254 3.549904)
			(end -0.9906 3.549904)
			(stroke
				(width 0.1524)
				(type default)
			)
			(layer "B.SilkS")
		)
		(fp_line
			(start -0.9906 -3.549904)
			(end -0.0254 -3.549904)
			(stroke
				(width 0.1524)
				(type default)
			)
			(layer "B.SilkS")
		)
		(fp_line
			(start -3.5052 3.549904)
			(end -4.05003 3.549904)
			(stroke
				(width 0.1524)
				(type default)
			)
			(layer "B.SilkS")
		)
		(fp_line
			(start -4.05003 3.549904)
			(end -4.05003 3.0226)
			(stroke
				(width 0.1524)
				(type default)
			)
			(layer "B.SilkS")
		)
		(fp_line
			(start -4.05003 -3.0226)
			(end -4.05003 -3.549904)
			(stroke
				(width 0.1524)
				(type default)
			)
			(layer "B.SilkS")
		)
		(fp_line
			(start -4.05003 -3.549904)
			(end -3.5052 -3.549904)
			(stroke
				(width 0.1524)
				(type default)
			)
			(layer "B.SilkS")
		)
		(fp_poly
			(pts
				(xy 4.706112 -4.300728) (xy 5.424424 -3.582162) (xy 4.346702 -3.223006)
			)
			(stroke
				(width 0)
				(type default)
			)
			(fill yes)
			(layer "B.SilkS")
		)
		(fp_line
			(start 4.05003 3.549904)
			(end -4.05003 3.549904)
			(stroke
				(width 0.1)
				(type default)
			)
			(layer "B.Fab")
		)
		(fp_line
			(start 4.05003 -3.549904)
			(end 4.05003 3.549904)
			(stroke
				(width 0.1)
				(type default)
			)
			(layer "B.Fab")
		)
		(fp_line
			(start -4.05003 3.549904)
			(end -4.05003 -3.549904)
			(stroke
				(width 0.1)
				(type default)
			)
			(layer "B.Fab")
		)
		(fp_line
			(start -4.05003 -3.549904)
			(end 4.05003 -3.549904)
			(stroke
				(width 0.1)
				(type default)
			)
			(layer "B.Fab")
		)
		(fp_poly
			(pts
				(xy 5.588 -3.25882) (xy 5.588 -2.24282) (xy 4.572 -2.75082)
			)
			(stroke
				(width 0)
				(type default)
			)
			(fill yes)
			(layer "B.Fab")
		)
		(pad "1" smd oval
			(at 3.9497 -2.75082 90)
			(size 0.3048 0.8382)
			(layers "B.Cu" "B.Mask" "B.Paste")
			(net "P52V_HS2_ISET")
		)
		(pad "2" smd oval
			(at 3.9497 -2.25044 90)
			(size 0.3048 0.8382)
			(layers "B.Cu" "B.Mask" "B.Paste")
			(net "P52V_HS2_ISTART")
		)
		(pad "3" smd oval
			(at 3.9497 -1.75006 90)
			(size 0.3048 0.8382)
			(layers "B.Cu" "B.Mask" "B.Paste")
			(net "P52V_HS2_VCAP")
		)
		(pad "4" smd oval
			(at 3.9497 -1.24968 90)
			(size 0.3048 0.8382)
			(layers "B.Cu" "B.Mask" "B.Paste")
			(net "P52V_HS2_ESTART_R")
		)
		(pad "5" smd oval
			(at 3.9497 -0.7493 90)
			(size 0.3048 0.8382)
			(layers "B.Cu" "B.Mask" "B.Paste")
			(net "P52V_HS2_EFAULT_R")
		)
		(pad "6" smd oval
			(at 3.9497 -0.24892 90)
			(size 0.3048 0.8382)
			(layers "B.Cu" "B.Mask" "B.Paste")
			(net "P52V_HS2_EN")
		)
		(pad "7" smd oval
			(at 3.9497 0.24892 90)
			(size 0.3048 0.8382)
			(layers "B.Cu" "B.Mask" "B.Paste")
			(net "P52V_HS2_ADR0")
		)
		(pad "8" smd oval
			(at 3.9497 0.7493 90)
			(size 0.3048 0.8382)
			(layers "B.Cu" "B.Mask" "B.Paste")
			(net "P52V_HS2_ADR1")
		)
		(pad "9" smd oval
			(at 3.9497 1.24968 90)
			(size 0.3048 0.8382)
			(layers "B.Cu" "B.Mask" "B.Paste")
			(net "SMB_P52V_PDB_SCL_R2")
		)
		(pad "10" smd oval
			(at 3.9497 1.75006 90)
			(size 0.3048 0.8382)
			(layers "B.Cu" "B.Mask" "B.Paste")
			(net "SMB_CM_HS2_3V3SB_DATI")
		)
		(pad "11" smd oval
			(at 3.9497 2.25044 90)
			(size 0.3048 0.8382)
			(layers "B.Cu" "B.Mask" "B.Paste")
			(net "SMB_CM_HS2_3V3SB_DATO")
		)
		(pad "12" smd oval
			(at 3.9497 2.75082 90)
			(size 0.3048 0.8382)
			(layers "B.Cu" "B.Mask" "B.Paste")
			(net "P52V_HS2_MCB")
		)
		(pad "13" smd oval
			(at 3.2512 3.44932)
			(size 0.3048 0.8382)
			(layers "B.Cu" "B.Mask" "B.Paste")
			(net "P52V_HS2_GPO2")
		)
		(pad "14" smd oval
			(at 2.75082 3.44932)
			(size 0.3048 0.8382)
			(layers "B.Cu" "B.Mask" "B.Paste")
			(net "P52V_HS2_GPO1")
		)
		(pad "15" smd oval
			(at 2.25044 3.44932)
			(size 0.3048 0.8382)
			(layers "B.Cu" "B.Mask" "B.Paste")
			(net "Net_407")
		)
		(pad "16" smd oval
			(at 1.75006 3.44932)
			(size 0.3048 0.8382)
			(layers "B.Cu" "B.Mask" "B.Paste")
			(net "Net_406")
		)
		(pad "17" smd oval
			(at 1.24968 3.44932)
			(size 0.3048 0.8382)
			(layers "B.Cu" "B.Mask" "B.Paste")
			(net "PWRGD_P52V_HS2_PG")
		)
		(pad "18" smd oval
			(at 0.7493 3.44932)
			(size 0.3048 0.8382)
			(layers "B.Cu" "B.Mask" "B.Paste")
			(net "P52V_HS2_PWRGIN")
		)
		(pad "19" smd oval
			(at 0.24892 3.44932)
			(size 0.3048 0.8382)
			(layers "B.Cu" "B.Mask" "B.Paste")
			(net "GND1_FIELD_SIGNAL")
		)
		(pad "20" smd oval
			(at -1.24968 3.44932)
			(size 0.3048 0.8382)
			(layers "B.Cu" "B.Mask" "B.Paste")
			(net "P52V_HS2_VCC")
		)
		(pad "21" smd oval
			(at -1.75006 3.44932)
			(size 0.3048 0.8382)
			(layers "B.Cu" "B.Mask" "B.Paste")
			(net "P52V_HS2_VCC")
		)
		(pad "22" smd oval
			(at -2.25044 3.44932)
			(size 0.3048 0.8382)
			(layers "B.Cu" "B.Mask" "B.Paste")
			(net "P52V_HS2_VCC")
		)
		(pad "23" smd oval
			(at -2.75082 3.44932)
			(size 0.3048 0.8382)
			(layers "B.Cu" "B.Mask" "B.Paste")
			(net "P52V_HS2_VCC")
		)
		(pad "24" smd oval
			(at -3.2512 3.44932)
			(size 0.3048 0.8382)
			(layers "B.Cu" "B.Mask" "B.Paste")
			(net "P52V_HS2_VCC")
		)
		(pad "25" smd oval
			(at -3.9497 2.75082 90)
			(size 0.3048 0.8382)
			(layers "B.Cu" "B.Mask" "B.Paste")
			(net "Net_23")
		)
		(pad "26" smd oval
			(at -3.9497 2.25044 90)
			(size 0.3048 0.8382)
			(layers "B.Cu" "B.Mask" "B.Paste")
			(net "Net_14")
		)
		(pad "27" smd oval
			(at -3.9497 1.75006 90)
			(size 0.3048 0.8382)
			(layers "B.Cu" "B.Mask" "B.Paste")
			(net "Net_6")
		)
		(pad "28" smd oval
			(at -3.9497 1.24968 90)
			(size 0.3048 0.8382)
			(layers "B.Cu" "B.Mask" "B.Paste")
			(net "Net_19")
		)
		(pad "29" smd oval
			(at -3.9497 0.7493 90)
			(size 0.3048 0.8382)
			(layers "B.Cu" "B.Mask" "B.Paste")
			(net "P52V_HS2_VCP")
		)
		(pad "30" smd oval
			(at -3.9497 0.24892 90)
			(size 0.3048 0.8382)
			(layers "B.Cu" "B.Mask" "B.Paste")
			(net "P52V_HS2_DV_DT_R")
		)
		(pad "31" smd oval
			(at -3.9497 -0.24892 90)
			(size 0.3048 0.8382)
			(layers "B.Cu" "B.Mask" "B.Paste")
			(net "P52V_HS2")
		)
		(pad "32" smd oval
			(at -3.9497 -0.7493 90)
			(size 0.3048 0.8382)
			(layers "B.Cu" "B.Mask" "B.Paste")
			(net "P52V_HS2_1272_GATE")
		)
		(pad "33" smd oval
			(at -3.9497 -1.24968 90)
			(size 0.3048 0.8382)
			(layers "B.Cu" "B.Mask" "B.Paste")
			(net "Net_5")
		)
		(pad "34" smd oval
			(at -3.9497 -1.75006 90)
			(size 0.3048 0.8382)
			(layers "B.Cu" "B.Mask" "B.Paste")
			(net "Net_11")
		)
		(pad "35" smd oval
			(at -3.9497 -2.25044 90)
			(size 0.3048 0.8382)
			(layers "B.Cu" "B.Mask" "B.Paste")
			(net "Net_7")
		)
		(pad "36" smd oval
			(at -3.9497 -2.75082 90)
			(size 0.3048 0.8382)
			(layers "B.Cu" "B.Mask" "B.Paste")
			(net "Net_10")
		)
		(pad "37" smd oval
			(at -3.2512 -3.44932)
			(size 0.3048 0.8382)
			(layers "B.Cu" "B.Mask" "B.Paste")
			(net "Net_22")
		)
		(pad "38" smd oval
			(at -2.75082 -3.44932)
			(size 0.3048 0.8382)
			(layers "B.Cu" "B.Mask" "B.Paste")
			(net "P52V_HS2_1272_S_N")
		)
		(pad "39" smd oval
			(at -2.25044 -3.44932)
			(size 0.3048 0.8382)
			(layers "B.Cu" "B.Mask" "B.Paste")
			(net "P52V_HS2_1272_S_P")
		)
		(pad "40" smd oval
			(at -1.75006 -3.44932)
			(size 0.3048 0.8382)
			(layers "B.Cu" "B.Mask" "B.Paste")
			(net "Net_9")
		)
		(pad "41" smd oval
			(at -1.24968 -3.44932)
			(size 0.3048 0.8382)
			(layers "B.Cu" "B.Mask" "B.Paste")
			(net "P52V_HS2_VCC")
		)
		(pad "42" smd oval
			(at 0.24892 -3.44932)
			(size 0.3048 0.8382)
			(layers "B.Cu" "B.Mask" "B.Paste")
			(net "P52V_HS2_VREG")
		)
		(pad "43" smd oval
			(at 0.7493 -3.44932)
			(size 0.3048 0.8382)
			(layers "B.Cu" "B.Mask" "B.Paste")
			(net "P52V_HS2_TEMPN")
		)
		(pad "44" smd oval
			(at 1.24968 -3.44932)
			(size 0.3048 0.8382)
			(layers "B.Cu" "B.Mask" "B.Paste")
			(net "P52V_HS2_TEMPP")
		)
		(pad "45" smd oval
			(at 1.75006 -3.44932)
			(size 0.3048 0.8382)
			(layers "B.Cu" "B.Mask" "B.Paste")
			(net "P52V_HS2_UVH")
		)
		(pad "46" smd oval
			(at 2.25044 -3.44932)
			(size 0.3048 0.8382)
			(layers "B.Cu" "B.Mask" "B.Paste")
			(net "P52V_HS2_UVLO_EN")
		)
		(pad "47" smd oval
			(at 2.75082 -3.44932)
			(size 0.3048 0.8382)
			(layers "B.Cu" "B.Mask" "B.Paste")
			(net "P52V_HS2_OV")
		)
		(pad "48" smd oval
			(at 3.2512 -3.44932)
			(size 0.3048 0.8382)
			(layers "B.Cu" "B.Mask" "B.Paste")
			(net "P52V_HS2_RND")
		)
		(pad "PAD1" smd rect
			(at 1.89738 0)
			(size 2.794 5.588)
			(layers "B.Cu" "B.Mask" "B.Paste")
			(net "GND1_FIELD_SIGNAL")
		)
		(pad "PAD2" smd rect
			(at -1.55194 0)
			(size 1.4986 3.4036)
			(layers "B.Cu" "B.Mask" "B.Paste")
			(net "P52V_HS2_VCC")
		)
		(zone
			(layer "B.Cu")
			(hatch none 0.5)
			(connect_pads
				(clearance 0)
			)
			(min_thickness 0.25)
			(keepout
				(tracks not_allowed)
				(vias allowed)
				(pads allowed)
				(copperpour not_allowed)
				(footprints allowed)
			)
			(placement
				(enabled no)
				(sheetname "")
			)
			(fill
				(thermal_gap 0.5)
				(thermal_bridge_width 0.5)
				(island_removal_mode 0)
			)
			(polygon
				(pts
					(xy 180.945536 -67.6402) (xy 180.945536 -73.5838) (xy 178.227736 -73.5838) (xy 178.227736 -72.3646)
					(xy 179.827936 -72.3646) (xy 179.827936 -68.8594) (xy 178.227736 -68.8594) (xy 178.227736 -67.6402)
				)
			)
		)
		(zone
			(layer "B.Cu")
			(hatch none 0.5)
			(connect_pads
				(clearance 0)
			)
			(min_thickness 0.25)
			(keepout
				(tracks not_allowed)
				(vias allowed)
				(pads allowed)
				(copperpour not_allowed)
				(footprints allowed)
			)
			(placement
				(enabled no)
				(sheetname "")
			)
			(fill
				(thermal_gap 0.5)
				(thermal_bridge_width 0.5)
				(island_removal_mode 0)
			)
			(polygon
				(pts
					(xy 173.985936 -69.2912) (xy 173.985936 -73.5838) (xy 178.202336 -73.5838) (xy 178.202336 -67.6402)
					(xy 173.985936 -67.6402) (xy 173.985936 -69.2658) (xy 174.112936 -69.2658) (xy 174.112936 -67.7672)
					(xy 177.033936 -67.7672) (xy 177.033936 -73.4568) (xy 174.112936 -73.4568) (xy 174.112936 -69.2912)
				)
			)
		)
	)
	(footprint ""
		(layer "B.Cu")
		(at 289.306 -92.075 -90)
		(property "Reference" "C91"
			(at 0 0 90)
			(layer "B.SilkS")
			(hide yes)
			(effects
				(font
					(size 1.27 1.27)
				)
				(justify mirror)
			)
		)
		(property "Value" ""
			(at 0 0 90)
			(layer "B.Fab")
			(effects
				(font
					(size 1.27 1.27)
				)
				(justify mirror)
			)
		)
		(duplicate_pad_numbers_are_jumpers no)
		(fp_line
			(start -0.7874 0.4064)
			(end 0.7874 0.4064)
			(stroke
				(width 0.1524)
				(type default)
			)
			(layer "B.SilkS")
		)
		(fp_line
			(start 0.7874 0.4064)
			(end 0.7874 -0.4064)
			(stroke
				(width 0.1524)
				(type default)
			)
			(layer "B.SilkS")
		)
		(fp_line
			(start -0.7874 -0.4064)
			(end -0.7874 0.4064)
			(stroke
				(width 0.1524)
				(type default)
			)
			(layer "B.SilkS")
		)
		(fp_line
			(start 0.7874 -0.4064)
			(end -0.7874 -0.4064)
			(stroke
				(width 0.1524)
				(type default)
			)
			(layer "B.SilkS")
		)
		(fp_line
			(start -0.67945 0.3048)
			(end -0.120396 0.3048)
			(stroke
				(width 0.1)
				(type default)
			)
			(layer "B.Fab")
		)
		(fp_line
			(start -0.120396 0.3048)
			(end -0.120396 0.2794)
			(stroke
				(width 0.1)
				(type default)
			)
			(layer "B.Fab")
		)
		(fp_line
			(start 0.12065 0.3048)
			(end 0.67945 0.3048)
			(stroke
				(width 0.1)
				(type default)
			)
			(layer "B.Fab")
		)
		(fp_line
			(start 0.67945 0.3048)
			(end 0.67945 -0.305054)
			(stroke
				(width 0.1)
				(type default)
			)
			(layer "B.Fab")
		)
		(fp_line
			(start -0.120396 0.2794)
			(end 0.12065 0.2794)
			(stroke
				(width 0.1)
				(type default)
			)
			(layer "B.Fab")
		)
		(fp_line
			(start 0.12065 0.2794)
			(end 0.12065 0.3048)
			(stroke
				(width 0.1)
				(type default)
			)
			(layer "B.Fab")
		)
		(fp_line
			(start -0.12065 -0.2794)
			(end -0.12065 -0.3048)
			(stroke
				(width 0.1)
				(type default)
			)
			(layer "B.Fab")
		)
		(fp_line
			(start 0.12065 -0.2794)
			(end -0.12065 -0.2794)
			(stroke
				(width 0.1)
				(type default)
			)
			(layer "B.Fab")
		)
		(fp_line
			(start -0.67945 -0.3048)
			(end -0.67945 0.3048)
			(stroke
				(width 0.1)
				(type default)
			)
			(layer "B.Fab")
		)
		(fp_line
			(start -0.12065 -0.3048)
			(end -0.67945 -0.3048)
			(stroke
				(width 0.1)
				(type default)
			)
			(layer "B.Fab")
		)
		(fp_line
			(start 0.12065 -0.305054)
			(end 0.12065 -0.2794)
			(stroke
				(width 0.1)
				(type default)
			)
			(layer "B.Fab")
		)
		(fp_line
			(start 0.67945 -0.305054)
			(end 0.12065 -0.305054)
			(stroke
				(width 0.1)
				(type default)
			)
			(layer "B.Fab")
		)
		(pad "1" smd circle
			(at 0.40005 0 90)
			(size 0 0)
			(layers "B.Cu" "B.Mask" "B.Paste")
			(net "P3V3_AND")
		)
		(pad "2" smd circle
			(at -0.40005 0 90)
			(size 0 0)
			(layers "B.Cu" "B.Mask" "B.Paste")
			(net "GND")
		)
	)
	(footprint ""
		(layer "B.Cu")
		(at 420.37 -40.468042 180)
		(property "Reference" "U39"
			(at 2.4765 -5.074412 0)
			(unlocked yes)
			(layer "B.SilkS")
			(effects
				(font
					(size 0.7874 0.5842)
					(thickness 0.1524)
				)
				(justify left mirror)
			)
		)
		(property "Value" ""
			(at 0 0 0)
			(layer "B.Fab")
			(effects
				(font
					(size 1.27 1.27)
				)
				(justify mirror)
			)
		)
		(duplicate_pad_numbers_are_jumpers no)
		(fp_line
			(start 2.0066 3.9624)
			(end 2.0066 -3.9624)
			(stroke
				(width 0.1524)
				(type default)
			)
			(layer "B.SilkS")
		)
		(fp_line
			(start 2.0066 -3.9624)
			(end 0.5842 -3.9624)
			(stroke
				(width 0.1524)
				(type default)
			)
			(layer "B.SilkS")
		)
		(fp_line
			(start 0.5842 -3.9624)
			(end 0 -3.3782)
			(stroke
				(width 0.1524)
				(type default)
			)
			(layer "B.SilkS")
		)
		(fp_line
			(start 0 -3.3782)
			(end -0.5842 -3.9624)
			(stroke
				(width 0.1524)
				(type default)
			)
			(layer "B.SilkS")
		)
		(fp_line
			(start -0.5842 -3.9624)
			(end -2.0066 -3.9624)
			(stroke
				(width 0.1524)
				(type default)
			)
			(layer "B.SilkS")
		)
		(fp_line
			(start -2.0066 3.9624)
			(end 2.0066 3.9624)
			(stroke
				(width 0.1524)
				(type default)
			)
			(layer "B.SilkS")
		)
		(fp_line
			(start -2.0066 -3.9624)
			(end -2.0066 3.9624)
			(stroke
				(width 0.1524)
				(type default)
			)
			(layer "B.SilkS")
		)
		(fp_poly
			(pts
				(xy 3.8862 -3.570986) (xy 4.6482 -3.189986) (xy 4.6482 -3.951986)
			)
			(stroke
				(width 0)
				(type default)
			)
			(fill yes)
			(layer "B.SilkS")
		)
		(fp_line
			(start 3.724402 3.80365)
			(end 2.2479 3.80365)
			(stroke
				(width 0.1)
				(type default)
			)
			(layer "B.Fab")
		)
		(fp_line
			(start 3.724402 -3.80365)
			(end 3.724402 3.80365)
			(stroke
				(width 0.1)
				(type default)
			)
			(layer "B.Fab")
		)
		(fp_line
			(start 3.7211 -3.34645)
			(end 3.7211 -3.80365)
			(stroke
				(width 0.1)
				(type default)
			)
			(layer "B.Fab")
		)
		(fp_line
			(start 2.2479 3.9624)
			(end -2.2479 3.9624)
			(stroke
				(width 0.1)
				(type default)
			)
			(layer "B.Fab")
		)
		(fp_line
			(start 2.2479 3.80365)
			(end 2.2479 3.9624)
			(stroke
				(width 0.1)
				(type default)
			)
			(layer "B.Fab")
		)
		(fp_line
			(start 2.2479 -3.80365)
			(end 3.724402 -3.80365)
			(stroke
				(width 0.1)
				(type default)
			)
			(layer "B.Fab")
		)
		(fp_line
			(start 2.2479 -3.974846)
			(end 2.2479 -3.80365)
			(stroke
				(width 0.1)
				(type default)
			)
			(layer "B.Fab")
		)
		(fp_line
			(start -2.2479 3.9624)
			(end -2.2479 3.80365)
			(stroke
				(width 0.1)
				(type default)
			)
			(layer "B.Fab")
		)
		(fp_line
			(start -2.2479 3.80365)
			(end -3.7211 3.80365)
			(stroke
				(width 0.1)
				(type default)
			)
			(layer "B.Fab")
		)
		(fp_line
			(start -2.2479 -3.80365)
			(end -2.2479 -3.974846)
			(stroke
				(width 0.1)
				(type default)
			)
			(layer "B.Fab")
		)
		(fp_line
			(start -2.2479 -3.974846)
			(end 2.2479 -3.974846)
			(stroke
				(width 0.1)
				(type default)
			)
			(layer "B.Fab")
		)
		(fp_line
			(start -3.7211 3.80365)
			(end -3.7211 -3.80365)
			(stroke
				(width 0.1)
				(type default)
			)
			(layer "B.Fab")
		)
		(fp_line
			(start -3.7211 -3.80365)
			(end -2.2479 -3.80365)
			(stroke
				(width 0.1)
				(type default)
			)
			(layer "B.Fab")
		)
		(fp_poly
			(pts
				(xy 3.8862 -3.570986) (xy 4.6482 -3.189986) (xy 4.6482 -3.951986)
			)
			(stroke
				(width 0)
				(type default)
			)
			(fill yes)
			(layer "B.Fab")
		)
		(pad "1" smd rect
			(at 2.921 -3.57505 90)
			(size 0.3556 1.4986)
			(layers "B.Cu" "B.Mask" "B.Paste")
			(net "PU_U39_PIN1")
		)
		(pad "2" smd rect
			(at 2.921 -2.925064 90)
			(size 0.3556 1.4986)
			(layers "B.Cu" "B.Mask" "B.Paste")
			(net "PCA9555_2_A1")
		)
		(pad "3" smd rect
			(at 2.921 -2.275078 90)
			(size 0.3556 1.4986)
			(layers "B.Cu" "B.Mask" "B.Paste")
			(net "PCA9555_2_A2")
		)
		(pad "4" smd rect
			(at 2.921 -1.625092 90)
			(size 0.3556 1.4986)
			(layers "B.Cu" "B.Mask" "B.Paste")
			(net "PWRGD_P12V_FAN_LED")
		)
		(pad "5" smd rect
			(at 2.921 -0.975106 90)
			(size 0.3556 1.4986)
			(layers "B.Cu" "B.Mask" "B.Paste")
			(net "FM_HS1_EN_BUSBAR_BUF")
		)
		(pad "6" smd rect
			(at 2.921 -0.32512 90)
			(size 0.3556 1.4986)
			(layers "B.Cu" "B.Mask" "B.Paste")
			(net "FM_HS1_EN_FUSE_BUF")
		)
		(pad "7" smd rect
			(at 2.921 0.32512 90)
			(size 0.3556 1.4986)
			(layers "B.Cu" "B.Mask" "B.Paste")
			(net "FM_HS2_EN_BUSBAR_BUF")
		)
		(pad "8" smd rect
			(at 2.921 0.975106 90)
			(size 0.3556 1.4986)
			(layers "B.Cu" "B.Mask" "B.Paste")
			(net "FM_HS2_EN_FUSE_BUF")
		)
		(pad "9" smd rect
			(at 2.921 1.625092 90)
			(size 0.3556 1.4986)
			(layers "B.Cu" "B.Mask" "B.Paste")
			(net "TP_U39_P05")
		)
		(pad "10" smd rect
			(at 2.921 2.275078 90)
			(size 0.3556 1.4986)
			(layers "B.Cu" "B.Mask" "B.Paste")
			(net "TP_U39_P06")
		)
		(pad "11" smd rect
			(at 2.921 2.925064 90)
			(size 0.3556 1.4986)
			(layers "B.Cu" "B.Mask" "B.Paste")
			(net "TP_U39_P07")
		)
		(pad "12" smd rect
			(at 2.921 3.57505 90)
			(size 0.3556 1.4986)
			(layers "B.Cu" "B.Mask" "B.Paste")
			(net "GND")
		)
		(pad "13" smd rect
			(at -2.921 3.57505 90)
			(size 0.3556 1.4986)
			(layers "B.Cu" "B.Mask" "B.Paste")
			(net "TP_U39_P10")
		)
		(pad "14" smd rect
			(at -2.921 2.925064 90)
			(size 0.3556 1.4986)
			(layers "B.Cu" "B.Mask" "B.Paste")
			(net "TP_U39_P11")
		)
		(pad "15" smd rect
			(at -2.921 2.275078 90)
			(size 0.3556 1.4986)
			(layers "B.Cu" "B.Mask" "B.Paste")
			(net "TP_U39_P12")
		)
		(pad "16" smd rect
			(at -2.921 1.625092 90)
			(size 0.3556 1.4986)
			(layers "B.Cu" "B.Mask" "B.Paste")
			(net "TP_U39_P13")
		)
		(pad "17" smd rect
			(at -2.921 0.975106 90)
			(size 0.3556 1.4986)
			(layers "B.Cu" "B.Mask" "B.Paste")
			(net "TP_U39_P14")
		)
		(pad "18" smd rect
			(at -2.921 0.32512 90)
			(size 0.3556 1.4986)
			(layers "B.Cu" "B.Mask" "B.Paste")
			(net "TP_U39_P15")
		)
		(pad "19" smd rect
			(at -2.921 -0.32512 90)
			(size 0.3556 1.4986)
			(layers "B.Cu" "B.Mask" "B.Paste")
			(net "TP_U39_P16")
		)
		(pad "20" smd rect
			(at -2.921 -0.975106 90)
			(size 0.3556 1.4986)
			(layers "B.Cu" "B.Mask" "B.Paste")
			(net "TP_U39_P17")
		)
		(pad "21" smd rect
			(at -2.921 -1.625092 90)
			(size 0.3556 1.4986)
			(layers "B.Cu" "B.Mask" "B.Paste")
			(net "PCA9555_2_A0")
		)
		(pad "22" smd rect
			(at -2.921 -2.275078 90)
			(size 0.3556 1.4986)
			(layers "B.Cu" "B.Mask" "B.Paste")
			(net "SMB_IOEXP_2_SCL")
		)
		(pad "23" smd rect
			(at -2.921 -2.925064 90)
			(size 0.3556 1.4986)
			(layers "B.Cu" "B.Mask" "B.Paste")
			(net "SMB_IOEXP_2_SDA")
		)
		(pad "24" smd rect
			(at -2.921 -3.57505 90)
			(size 0.3556 1.4986)
			(layers "B.Cu" "B.Mask" "B.Paste")
			(net "P3V3_AUX")
		)
	)
	(footprint ""
		(layer "B.Cu")
		(at 161.336736 -74.93 -90)
		(property "Reference" "PR7008"
			(at 0 0 90)
			(layer "B.SilkS")
			(hide yes)
			(effects
				(font
					(size 1.27 1.27)
				)
				(justify mirror)
			)
		)
		(property "Value" ""
			(at 0 0 90)
			(layer "B.Fab")
			(effects
				(font
					(size 1.27 1.27)
				)
				(justify mirror)
			)
		)
		(duplicate_pad_numbers_are_jumpers no)
		(fp_line
			(start -0.7874 0.4064)
			(end 0.7874 0.4064)
			(stroke
				(width 0.1524)
				(type default)
			)
			(layer "B.SilkS")
		)
		(fp_line
			(start 0.7874 0.4064)
			(end 0.7874 -0.4064)
			(stroke
				(width 0.1524)
				(type default)
			)
			(layer "B.SilkS")
		)
		(fp_line
			(start -0.7874 -0.4064)
			(end -0.7874 0.4064)
			(stroke
				(width 0.1524)
				(type default)
			)
			(layer "B.SilkS")
		)
		(fp_line
			(start 0.7874 -0.4064)
			(end -0.7874 -0.4064)
			(stroke
				(width 0.1524)
				(type default)
			)
			(layer "B.SilkS")
		)
		(fp_line
			(start -0.67945 0.3048)
			(end -0.120396 0.3048)
			(stroke
				(width 0.1)
				(type default)
			)
			(layer "B.Fab")
		)
		(fp_line
			(start -0.120396 0.3048)
			(end -0.120396 0.2794)
			(stroke
				(width 0.1)
				(type default)
			)
			(layer "B.Fab")
		)
		(fp_line
			(start 0.12065 0.3048)
			(end 0.67945 0.3048)
			(stroke
				(width 0.1)
				(type default)
			)
			(layer "B.Fab")
		)
		(fp_line
			(start 0.67945 0.3048)
			(end 0.67945 -0.305054)
			(stroke
				(width 0.1)
				(type default)
			)
			(layer "B.Fab")
		)
		(fp_line
			(start -0.120396 0.2794)
			(end 0.12065 0.2794)
			(stroke
				(width 0.1)
				(type default)
			)
			(layer "B.Fab")
		)
		(fp_line
			(start 0.12065 0.2794)
			(end 0.12065 0.3048)
			(stroke
				(width 0.1)
				(type default)
			)
			(layer "B.Fab")
		)
		(fp_line
			(start -0.12065 -0.2794)
			(end -0.12065 -0.3048)
			(stroke
				(width 0.1)
				(type default)
			)
			(layer "B.Fab")
		)
		(fp_line
			(start 0.12065 -0.2794)
			(end -0.12065 -0.2794)
			(stroke
				(width 0.1)
				(type default)
			)
			(layer "B.Fab")
		)
		(fp_line
			(start -0.67945 -0.3048)
			(end -0.67945 0.3048)
			(stroke
				(width 0.1)
				(type default)
			)
			(layer "B.Fab")
		)
		(fp_line
			(start -0.12065 -0.3048)
			(end -0.67945 -0.3048)
			(stroke
				(width 0.1)
				(type default)
			)
			(layer "B.Fab")
		)
		(fp_line
			(start 0.12065 -0.305054)
			(end 0.12065 -0.2794)
			(stroke
				(width 0.1)
				(type default)
			)
			(layer "B.Fab")
		)
		(fp_line
			(start 0.67945 -0.305054)
			(end 0.12065 -0.305054)
			(stroke
				(width 0.1)
				(type default)
			)
			(layer "B.Fab")
		)
		(pad "1" smd circle
			(at 0.40005 0 90)
			(size 0 0)
			(layers "B.Cu" "B.Mask" "B.Paste")
			(net "P52V_HS2_TMR")
		)
		(pad "2" smd circle
			(at -0.40005 0 90)
			(size 0 0)
			(layers "B.Cu" "B.Mask" "B.Paste")
			(net "HS2_TMR1")
		)
	)
	(footprint ""
		(layer "B.Cu")
		(at 343.535 -37.973 180)
		(property "Reference" "PC585"
			(at 0 0 0)
			(layer "B.SilkS")
			(hide yes)
			(effects
				(font
					(size 1.27 1.27)
				)
				(justify mirror)
			)
		)
		(property "Value" ""
			(at 0 0 0)
			(layer "B.Fab")
			(effects
				(font
					(size 1.27 1.27)
				)
				(justify mirror)
			)
		)
		(duplicate_pad_numbers_are_jumpers no)
		(fp_line
			(start 1.2954 0.5842)
			(end 1.2954 -0.5842)
			(stroke
				(width 0.1524)
				(type default)
			)
			(layer "B.SilkS")
		)
		(fp_line
			(start 1.2954 -0.5842)
			(end -1.2954 -0.5842)
			(stroke
				(width 0.1524)
				(type default)
			)
			(layer "B.SilkS")
		)
		(fp_line
			(start -1.2954 0.5842)
			(end 1.2954 0.5842)
			(stroke
				(width 0.1524)
				(type default)
			)
			(layer "B.SilkS")
		)
		(fp_line
			(start -1.2954 -0.5842)
			(end -1.2954 0.5842)
			(stroke
				(width 0.1524)
				(type default)
			)
			(layer "B.SilkS")
		)
		(fp_line
			(start 1.1938 0.4064)
			(end 1.1938 -0.4064)
			(stroke
				(width 0.1)
				(type default)
			)
			(layer "B.Fab")
		)
		(fp_line
			(start 1.1938 -0.4064)
			(end 0.8636 -0.4064)
			(stroke
				(width 0.1)
				(type default)
			)
			(layer "B.Fab")
		)
		(fp_line
			(start 0.8636 0.4572)
			(end 0.8636 0.4064)
			(stroke
				(width 0.1)
				(type default)
			)
			(layer "B.Fab")
		)
		(fp_line
			(start 0.8636 0.4064)
			(end 1.1938 0.4064)
			(stroke
				(width 0.1)
				(type default)
			)
			(layer "B.Fab")
		)
		(fp_line
			(start 0.8636 -0.4064)
			(end 0.8636 -0.4572)
			(stroke
				(width 0.1)
				(type default)
			)
			(layer "B.Fab")
		)
		(fp_line
			(start 0.8636 -0.4572)
			(end -0.8636 -0.4572)
			(stroke
				(width 0.1)
				(type default)
			)
			(layer "B.Fab")
		)
		(fp_line
			(start -0.8636 0.4572)
			(end 0.8636 0.4572)
			(stroke
				(width 0.1)
				(type default)
			)
			(layer "B.Fab")
		)
		(fp_line
			(start -0.8636 0.4064)
			(end -0.8636 0.4572)
			(stroke
				(width 0.1)
				(type default)
			)
			(layer "B.Fab")
		)
		(fp_line
			(start -0.8636 -0.4064)
			(end -1.1938 -0.4064)
			(stroke
				(width 0.1)
				(type default)
			)
			(layer "B.Fab")
		)
		(fp_line
			(start -0.8636 -0.4572)
			(end -0.8636 -0.4064)
			(stroke
				(width 0.1)
				(type default)
			)
			(layer "B.Fab")
		)
		(fp_line
			(start -1.1938 0.4064)
			(end -0.8636 0.4064)
			(stroke
				(width 0.1)
				(type default)
			)
			(layer "B.Fab")
		)
		(fp_line
			(start -1.1938 -0.4064)
			(end -1.1938 0.4064)
			(stroke
				(width 0.1)
				(type default)
			)
			(layer "B.Fab")
		)
		(pad "1" smd rect
			(at 0.7366 0 90)
			(size 0.7112 0.8128)
			(layers "B.Cu" "B.Mask" "B.Paste")
			(net "P52V_HS1_4287_GATE2_RC")
		)
		(pad "2" smd rect
			(at -0.7366 0 90)
			(size 0.7112 0.8128)
			(layers "B.Cu" "B.Mask" "B.Paste")
			(net "P52V_HS1")
		)
	)
	(footprint ""
		(layer "B.Cu")
		(at 270.4084 -84.201 90)
		(property "Reference" "PR481"
			(at 0 0 90)
			(layer "B.SilkS")
			(hide yes)
			(effects
				(font
					(size 1.27 1.27)
				)
				(justify mirror)
			)
		)
		(property "Value" ""
			(at 0 0 90)
			(layer "B.Fab")
			(effects
				(font
					(size 1.27 1.27)
				)
				(justify mirror)
			)
		)
		(duplicate_pad_numbers_are_jumpers no)
		(fp_line
			(start 1.651 -0.8382)
			(end -1.651 -0.8382)
			(stroke
				(width 0.1524)
				(type default)
			)
			(layer "B.SilkS")
		)
		(fp_line
			(start -1.651 -0.8382)
			(end -1.651 0.8382)
			(stroke
				(width 0.1524)
				(type default)
			)
			(layer "B.SilkS")
		)
		(fp_line
			(start 1.651 0.8382)
			(end 1.651 -0.8382)
			(stroke
				(width 0.1524)
				(type default)
			)
			(layer "B.SilkS")
		)
		(fp_line
			(start -1.651 0.8382)
			(end 1.651 0.8382)
			(stroke
				(width 0.1524)
				(type default)
			)
			(layer "B.SilkS")
		)
		(fp_line
			(start 1.559814 -0.7366)
			(end 1.559814 0.7366)
			(stroke
				(width 0.1)
				(type default)
			)
			(layer "B.Fab")
		)
		(fp_line
			(start 1.524 -0.7366)
			(end 1.559814 -0.7366)
			(stroke
				(width 0.1)
				(type default)
			)
			(layer "B.Fab")
		)
		(fp_line
			(start -1.524 -0.7366)
			(end 1.524 -0.7366)
			(stroke
				(width 0.1)
				(type default)
			)
			(layer "B.Fab")
		)
		(fp_line
			(start -1.560576 -0.7366)
			(end -1.524 -0.7366)
			(stroke
				(width 0.1)
				(type default)
			)
			(layer "B.Fab")
		)
		(fp_line
			(start 1.559814 0.7366)
			(end 1.524 0.7366)
			(stroke
				(width 0.1)
				(type default)
			)
			(layer "B.Fab")
		)
		(fp_line
			(start 1.524 0.7366)
			(end -1.524 0.7366)
			(stroke
				(width 0.1)
				(type default)
			)
			(layer "B.Fab")
		)
		(fp_line
			(start -1.524 0.7366)
			(end -1.560576 0.7366)
			(stroke
				(width 0.1)
				(type default)
			)
			(layer "B.Fab")
		)
		(fp_line
			(start -1.560576 0.7366)
			(end -1.560576 -0.7366)
			(stroke
				(width 0.1)
				(type default)
			)
			(layer "B.Fab")
		)
		(pad "1" smd rect
			(at 0.94996 0 90)
			(size 1.1176 1.3716)
			(layers "B.Cu" "B.Mask" "B.Paste")
			(net "P52V_1")
		)
		(pad "2" smd rect
			(at -0.94996 0 90)
			(size 1.1176 1.3716)
			(layers "B.Cu" "B.Mask" "B.Paste")
			(net "P52V_HS1_UVLO_EN")
		)
	)
	(footprint ""
		(layer "B.Cu")
		(at 262.4074 -69.088 90)
		(property "Reference" "PC588"
			(at 0 0 90)
			(layer "B.SilkS")
			(hide yes)
			(effects
				(font
					(size 1.27 1.27)
				)
				(justify mirror)
			)
		)
		(property "Value" ""
			(at 0 0 90)
			(layer "B.Fab")
			(effects
				(font
					(size 1.27 1.27)
				)
				(justify mirror)
			)
		)
		(duplicate_pad_numbers_are_jumpers no)
		(fp_line
			(start 2.2098 -0.9398)
			(end -2.2098 -0.9398)
			(stroke
				(width 0.1524)
				(type default)
			)
			(layer "B.SilkS")
		)
		(fp_line
			(start -2.2098 -0.9398)
			(end -2.2098 0.9398)
			(stroke
				(width 0.1524)
				(type default)
			)
			(layer "B.SilkS")
		)
		(fp_line
			(start 2.2098 0.9398)
			(end 2.2098 -0.9398)
			(stroke
				(width 0.1524)
				(type default)
			)
			(layer "B.SilkS")
		)
		(fp_line
			(start -2.2098 0.9398)
			(end 2.2098 0.9398)
			(stroke
				(width 0.1524)
				(type default)
			)
			(layer "B.SilkS")
		)
		(fp_line
			(start 1.6764 -0.9398)
			(end -1.6764 -0.9398)
			(stroke
				(width 0.1)
				(type default)
			)
			(layer "B.Fab")
		)
		(fp_line
			(start -1.6764 -0.9398)
			(end -1.6764 -0.889)
			(stroke
				(width 0.1)
				(type default)
			)
			(layer "B.Fab")
		)
		(fp_line
			(start 1.6764 -0.889)
			(end 1.6764 -0.9398)
			(stroke
				(width 0.1)
				(type default)
			)
			(layer "B.Fab")
		)
		(fp_line
			(start -1.6764 -0.889)
			(end -1.6764 -0.8382)
			(stroke
				(width 0.1)
				(type default)
			)
			(layer "B.Fab")
		)
		(fp_line
			(start 2.1082 -0.8382)
			(end 1.6764 -0.8382)
			(stroke
				(width 0.1)
				(type default)
			)
			(layer "B.Fab")
		)
		(fp_line
			(start 1.6764 -0.8382)
			(end 1.6764 -0.889)
			(stroke
				(width 0.1)
				(type default)
			)
			(layer "B.Fab")
		)
		(fp_line
			(start -1.6764 -0.8382)
			(end -2.1082 -0.8382)
			(stroke
				(width 0.1)
				(type default)
			)
			(layer "B.Fab")
		)
		(fp_line
			(start -2.1082 -0.8382)
			(end -2.1082 0.8382)
			(stroke
				(width 0.1)
				(type default)
			)
			(layer "B.Fab")
		)
		(fp_line
			(start 2.1082 0.8382)
			(end 2.1082 -0.8382)
			(stroke
				(width 0.1)
				(type default)
			)
			(layer "B.Fab")
		)
		(fp_line
			(start 1.6764 0.8382)
			(end 2.1082 0.8382)
			(stroke
				(width 0.1)
				(type default)
			)
			(layer "B.Fab")
		)
		(fp_line
			(start -1.6764 0.8382)
			(end -1.6764 0.889)
			(stroke
				(width 0.1)
				(type default)
			)
			(layer "B.Fab")
		)
		(fp_line
			(start -2.1082 0.8382)
			(end -1.6764 0.8382)
			(stroke
				(width 0.1)
				(type default)
			)
			(layer "B.Fab")
		)
		(fp_line
			(start 1.6764 0.889)
			(end 1.6764 0.8382)
			(stroke
				(width 0.1)
				(type default)
			)
			(layer "B.Fab")
		)
		(fp_line
			(start -1.6764 0.889)
			(end -1.6764 0.9398)
			(stroke
				(width 0.1)
				(type default)
			)
			(layer "B.Fab")
		)
		(fp_line
			(start 1.6764 0.9398)
			(end 1.6764 0.889)
			(stroke
				(width 0.1)
				(type default)
			)
			(layer "B.Fab")
		)
		(fp_line
			(start -1.6764 0.9398)
			(end 1.6764 0.9398)
			(stroke
				(width 0.1)
				(type default)
			)
			(layer "B.Fab")
		)
		(pad "1" smd rect
			(at 1.4732 0 90)
			(size 1.1684 1.5748)
			(layers "B.Cu" "B.Mask" "B.Paste")
			(net "P52V_HS1")
		)
		(pad "2" smd rect
			(at -1.4732 0 90)
			(size 1.1684 1.5748)
			(layers "B.Cu" "B.Mask" "B.Paste")
			(net "P52V_HS1_VCP")
		)
	)
	(footprint ""
		(layer "B.Cu")
		(at 340.3854 -38.5318 90)
		(property "Reference" "PR6998"
			(at 0 0 90)
			(layer "B.SilkS")
			(hide yes)
			(effects
				(font
					(size 1.27 1.27)
				)
				(justify mirror)
			)
		)
		(property "Value" ""
			(at 0 0 90)
			(layer "B.Fab")
			(effects
				(font
					(size 1.27 1.27)
				)
				(justify mirror)
			)
		)
		(duplicate_pad_numbers_are_jumpers no)
		(fp_line
			(start 0.7874 -0.4064)
			(end -0.7874 -0.4064)
			(stroke
				(width 0.1524)
				(type default)
			)
			(layer "B.SilkS")
		)
		(fp_line
			(start -0.7874 -0.4064)
			(end -0.7874 0.4064)
			(stroke
				(width 0.1524)
				(type default)
			)
			(layer "B.SilkS")
		)
		(fp_line
			(start 0.7874 0.4064)
			(end 0.7874 -0.4064)
			(stroke
				(width 0.1524)
				(type default)
			)
			(layer "B.SilkS")
		)
		(fp_line
			(start -0.7874 0.4064)
			(end 0.7874 0.4064)
			(stroke
				(width 0.1524)
				(type default)
			)
			(layer "B.SilkS")
		)
		(fp_line
			(start 0.67945 -0.305054)
			(end 0.12065 -0.305054)
			(stroke
				(width 0.1)
				(type default)
			)
			(layer "B.Fab")
		)
		(fp_line
			(start 0.12065 -0.305054)
			(end 0.12065 -0.2794)
			(stroke
				(width 0.1)
				(type default)
			)
			(layer "B.Fab")
		)
		(fp_line
			(start -0.12065 -0.3048)
			(end -0.67945 -0.3048)
			(stroke
				(width 0.1)
				(type default)
			)
			(layer "B.Fab")
		)
		(fp_line
			(start -0.67945 -0.3048)
			(end -0.67945 0.3048)
			(stroke
				(width 0.1)
				(type default)
			)
			(layer "B.Fab")
		)
		(fp_line
			(start 0.12065 -0.2794)
			(end -0.12065 -0.2794)
			(stroke
				(width 0.1)
				(type default)
			)
			(layer "B.Fab")
		)
		(fp_line
			(start -0.12065 -0.2794)
			(end -0.12065 -0.3048)
			(stroke
				(width 0.1)
				(type default)
			)
			(layer "B.Fab")
		)
		(fp_line
			(start 0.12065 0.2794)
			(end 0.12065 0.3048)
			(stroke
				(width 0.1)
				(type default)
			)
			(layer "B.Fab")
		)
		(fp_line
			(start -0.120396 0.2794)
			(end 0.12065 0.2794)
			(stroke
				(width 0.1)
				(type default)
			)
			(layer "B.Fab")
		)
		(fp_line
			(start 0.67945 0.3048)
			(end 0.67945 -0.305054)
			(stroke
				(width 0.1)
				(type default)
			)
			(layer "B.Fab")
		)
		(fp_line
			(start 0.12065 0.3048)
			(end 0.67945 0.3048)
			(stroke
				(width 0.1)
				(type default)
			)
			(layer "B.Fab")
		)
		(fp_line
			(start -0.120396 0.3048)
			(end -0.120396 0.2794)
			(stroke
				(width 0.1)
				(type default)
			)
			(layer "B.Fab")
		)
		(fp_line
			(start -0.67945 0.3048)
			(end -0.120396 0.3048)
			(stroke
				(width 0.1)
				(type default)
			)
			(layer "B.Fab")
		)
		(pad "1" smd rect
			(at 0.40005 0 90)
			(size 0.4572 0.508)
			(layers "B.Cu" "B.Mask" "B.Paste")
			(net "P52V_HS1_GATE2_R1")
		)
		(pad "2" smd rect
			(at -0.40005 0 90)
			(size 0.4572 0.508)
			(layers "B.Cu" "B.Mask" "B.Paste")
			(net "P52V_HS1_4287_GATE2_R")
		)
	)
	(footprint ""
		(layer "B.Cu")
		(at 284.2514 -61.849)
		(property "Reference" "PR211"
			(at 0 0 0)
			(layer "B.SilkS")
			(hide yes)
			(effects
				(font
					(size 1.27 1.27)
				)
				(justify mirror)
			)
		)
		(property "Value" ""
			(at 0 0 0)
			(layer "B.Fab")
			(effects
				(font
					(size 1.27 1.27)
				)
				(justify mirror)
			)
		)
		(duplicate_pad_numbers_are_jumpers no)
		(fp_line
			(start -0.7874 -0.4064)
			(end -0.7874 0.4064)
			(stroke
				(width 0.1524)
				(type default)
			)
			(layer "B.SilkS")
		)
		(fp_line
			(start -0.7874 0.4064)
			(end 0.7874 0.4064)
			(stroke
				(width 0.1524)
				(type default)
			)
			(layer "B.SilkS")
		)
		(fp_line
			(start 0.7874 -0.4064)
			(end -0.7874 -0.4064)
			(stroke
				(width 0.1524)
				(type default)
			)
			(layer "B.SilkS")
		)
		(fp_line
			(start 0.7874 0.4064)
			(end 0.7874 -0.4064)
			(stroke
				(width 0.1524)
				(type default)
			)
			(layer "B.SilkS")
		)
		(fp_line
			(start -0.67945 -0.3048)
			(end -0.67945 0.3048)
			(stroke
				(width 0.1)
				(type default)
			)
			(layer "B.Fab")
		)
		(fp_line
			(start -0.67945 0.3048)
			(end -0.120396 0.3048)
			(stroke
				(width 0.1)
				(type default)
			)
			(layer "B.Fab")
		)
		(fp_line
			(start -0.12065 -0.3048)
			(end -0.67945 -0.3048)
			(stroke
				(width 0.1)
				(type default)
			)
			(layer "B.Fab")
		)
		(fp_line
			(start -0.12065 -0.2794)
			(end -0.12065 -0.3048)
			(stroke
				(width 0.1)
				(type default)
			)
			(layer "B.Fab")
		)
		(fp_line
			(start -0.120396 0.2794)
			(end 0.12065 0.2794)
			(stroke
				(width 0.1)
				(type default)
			)
			(layer "B.Fab")
		)
		(fp_line
			(start -0.120396 0.3048)
			(end -0.120396 0.2794)
			(stroke
				(width 0.1)
				(type default)
			)
			(layer "B.Fab")
		)
		(fp_line
			(start 0.12065 -0.305054)
			(end 0.12065 -0.2794)
			(stroke
				(width 0.1)
				(type default)
			)
			(layer "B.Fab")
		)
		(fp_line
			(start 0.12065 -0.2794)
			(end -0.12065 -0.2794)
			(stroke
				(width 0.1)
				(type default)
			)
			(layer "B.Fab")
		)
		(fp_line
			(start 0.12065 0.2794)
			(end 0.12065 0.3048)
			(stroke
				(width 0.1)
				(type default)
			)
			(layer "B.Fab")
		)
		(fp_line
			(start 0.12065 0.3048)
			(end 0.67945 0.3048)
			(stroke
				(width 0.1)
				(type default)
			)
			(layer "B.Fab")
		)
		(fp_line
			(start 0.67945 -0.305054)
			(end 0.12065 -0.305054)
			(stroke
				(width 0.1)
				(type default)
			)
			(layer "B.Fab")
		)
		(fp_line
			(start 0.67945 0.3048)
			(end 0.67945 -0.305054)
			(stroke
				(width 0.1)
				(type default)
			)
			(layer "B.Fab")
		)
		(pad "1" smd circle
			(at 0.40005 0 180)
			(size 0 0)
			(layers "B.Cu" "B.Mask" "B.Paste")
			(net "HS1_TMR2")
		)
		(pad "2" smd circle
			(at -0.40005 0 180)
			(size 0 0)
			(layers "B.Cu" "B.Mask" "B.Paste")
			(net "GND_FIELD_SIGNAL")
		)
	)
	(footprint ""
		(layer "B.Cu")
		(at 278.4094 -64.897)
		(property "Reference" "R145"
			(at 0 0 0)
			(layer "B.SilkS")
			(hide yes)
			(effects
				(font
					(size 1.27 1.27)
				)
				(justify mirror)
			)
		)
		(property "Value" ""
			(at 0 0 0)
			(layer "B.Fab")
			(effects
				(font
					(size 1.27 1.27)
				)
				(justify mirror)
			)
		)
		(duplicate_pad_numbers_are_jumpers no)
		(fp_line
			(start -0.7874 -0.4064)
			(end -0.7874 0.4064)
			(stroke
				(width 0.1524)
				(type default)
			)
			(layer "B.SilkS")
		)
		(fp_line
			(start -0.7874 0.4064)
			(end 0.7874 0.4064)
			(stroke
				(width 0.1524)
				(type default)
			)
			(layer "B.SilkS")
		)
		(fp_line
			(start 0.7874 -0.4064)
			(end -0.7874 -0.4064)
			(stroke
				(width 0.1524)
				(type default)
			)
			(layer "B.SilkS")
		)
		(fp_line
			(start 0.7874 0.4064)
			(end 0.7874 -0.4064)
			(stroke
				(width 0.1524)
				(type default)
			)
			(layer "B.SilkS")
		)
		(fp_line
			(start -0.67945 -0.3048)
			(end -0.67945 0.3048)
			(stroke
				(width 0.1)
				(type default)
			)
			(layer "B.Fab")
		)
		(fp_line
			(start -0.67945 0.3048)
			(end -0.120396 0.3048)
			(stroke
				(width 0.1)
				(type default)
			)
			(layer "B.Fab")
		)
		(fp_line
			(start -0.12065 -0.3048)
			(end -0.67945 -0.3048)
			(stroke
				(width 0.1)
				(type default)
			)
			(layer "B.Fab")
		)
		(fp_line
			(start -0.12065 -0.2794)
			(end -0.12065 -0.3048)
			(stroke
				(width 0.1)
				(type default)
			)
			(layer "B.Fab")
		)
		(fp_line
			(start -0.120396 0.2794)
			(end 0.12065 0.2794)
			(stroke
				(width 0.1)
				(type default)
			)
			(layer "B.Fab")
		)
		(fp_line
			(start -0.120396 0.3048)
			(end -0.120396 0.2794)
			(stroke
				(width 0.1)
				(type default)
			)
			(layer "B.Fab")
		)
		(fp_line
			(start 0.12065 -0.305054)
			(end 0.12065 -0.2794)
			(stroke
				(width 0.1)
				(type default)
			)
			(layer "B.Fab")
		)
		(fp_line
			(start 0.12065 -0.2794)
			(end -0.12065 -0.2794)
			(stroke
				(width 0.1)
				(type default)
			)
			(layer "B.Fab")
		)
		(fp_line
			(start 0.12065 0.2794)
			(end 0.12065 0.3048)
			(stroke
				(width 0.1)
				(type default)
			)
			(layer "B.Fab")
		)
		(fp_line
			(start 0.12065 0.3048)
			(end 0.67945 0.3048)
			(stroke
				(width 0.1)
				(type default)
			)
			(layer "B.Fab")
		)
		(fp_line
			(start 0.67945 -0.305054)
			(end 0.12065 -0.305054)
			(stroke
				(width 0.1)
				(type default)
			)
			(layer "B.Fab")
		)
		(fp_line
			(start 0.67945 0.3048)
			(end 0.67945 -0.305054)
			(stroke
				(width 0.1)
				(type default)
			)
			(layer "B.Fab")
		)
		(pad "1" smd circle
			(at 0.40005 0 180)
			(size 0 0)
			(layers "B.Cu" "B.Mask" "B.Paste")
			(net "SMB_P52V_PDB_SDA")
		)
		(pad "2" smd circle
			(at -0.40005 0 180)
			(size 0 0)
			(layers "B.Cu" "B.Mask" "B.Paste")
			(net "SMB_CM_HS1_3V3SB_DATO")
		)
	)
	(footprint ""
		(layer "B.Cu")
		(at 273.8374 -76.454 -90)
		(property "Reference" "PC586"
			(at 0 0 90)
			(layer "B.SilkS")
			(hide yes)
			(effects
				(font
					(size 1.27 1.27)
				)
				(justify mirror)
			)
		)
		(property "Value" ""
			(at 0 0 90)
			(layer "B.Fab")
			(effects
				(font
					(size 1.27 1.27)
				)
				(justify mirror)
			)
		)
		(duplicate_pad_numbers_are_jumpers no)
		(fp_line
			(start -0.7874 0.4064)
			(end 0.7874 0.4064)
			(stroke
				(width 0.1524)
				(type default)
			)
			(layer "B.SilkS")
		)
		(fp_line
			(start 0.7874 0.4064)
			(end 0.7874 -0.4064)
			(stroke
				(width 0.1524)
				(type default)
			)
			(layer "B.SilkS")
		)
		(fp_line
			(start -0.7874 -0.4064)
			(end -0.7874 0.4064)
			(stroke
				(width 0.1524)
				(type default)
			)
			(layer "B.SilkS")
		)
		(fp_line
			(start 0.7874 -0.4064)
			(end -0.7874 -0.4064)
			(stroke
				(width 0.1524)
				(type default)
			)
			(layer "B.SilkS")
		)
		(fp_line
			(start -0.67945 0.3048)
			(end -0.120396 0.3048)
			(stroke
				(width 0.1)
				(type default)
			)
			(layer "B.Fab")
		)
		(fp_line
			(start -0.120396 0.3048)
			(end -0.120396 0.2794)
			(stroke
				(width 0.1)
				(type default)
			)
			(layer "B.Fab")
		)
		(fp_line
			(start 0.12065 0.3048)
			(end 0.67945 0.3048)
			(stroke
				(width 0.1)
				(type default)
			)
			(layer "B.Fab")
		)
		(fp_line
			(start 0.67945 0.3048)
			(end 0.67945 -0.305054)
			(stroke
				(width 0.1)
				(type default)
			)
			(layer "B.Fab")
		)
		(fp_line
			(start -0.120396 0.2794)
			(end 0.12065 0.2794)
			(stroke
				(width 0.1)
				(type default)
			)
			(layer "B.Fab")
		)
		(fp_line
			(start 0.12065 0.2794)
			(end 0.12065 0.3048)
			(stroke
				(width 0.1)
				(type default)
			)
			(layer "B.Fab")
		)
		(fp_line
			(start -0.12065 -0.2794)
			(end -0.12065 -0.3048)
			(stroke
				(width 0.1)
				(type default)
			)
			(layer "B.Fab")
		)
		(fp_line
			(start 0.12065 -0.2794)
			(end -0.12065 -0.2794)
			(stroke
				(width 0.1)
				(type default)
			)
			(layer "B.Fab")
		)
		(fp_line
			(start -0.67945 -0.3048)
			(end -0.67945 0.3048)
			(stroke
				(width 0.1)
				(type default)
			)
			(layer "B.Fab")
		)
		(fp_line
			(start -0.12065 -0.3048)
			(end -0.67945 -0.3048)
			(stroke
				(width 0.1)
				(type default)
			)
			(layer "B.Fab")
		)
		(fp_line
			(start 0.12065 -0.305054)
			(end 0.12065 -0.2794)
			(stroke
				(width 0.1)
				(type default)
			)
			(layer "B.Fab")
		)
		(fp_line
			(start 0.67945 -0.305054)
			(end 0.12065 -0.305054)
			(stroke
				(width 0.1)
				(type default)
			)
			(layer "B.Fab")
		)
		(pad "1" smd circle
			(at 0.40005 0 90)
			(size 0 0)
			(layers "B.Cu" "B.Mask" "B.Paste")
			(net "P52V_HS1_UVH")
		)
		(pad "2" smd circle
			(at -0.40005 0 90)
			(size 0 0)
			(layers "B.Cu" "B.Mask" "B.Paste")
			(net "GND_FIELD_SIGNAL")
		)
	)
	(footprint ""
		(layer "B.Cu")
		(at 270.1544 -69.596)
		(property "Reference" "PU7"
			(at -1.8034 4.85267 0)
			(unlocked yes)
			(layer "B.SilkS")
			(effects
				(font
					(size 0.7874 0.5842)
					(thickness 0.1524)
				)
				(justify left mirror)
			)
		)
		(property "Value" ""
			(at 0 0 0)
			(layer "B.Fab")
			(effects
				(font
					(size 1.27 1.27)
				)
				(justify mirror)
			)
		)
		(duplicate_pad_numbers_are_jumpers no)
		(fp_line
			(start -4.05003 -3.549904)
			(end -3.5052 -3.549904)
			(stroke
				(width 0.1524)
				(type default)
			)
			(layer "B.SilkS")
		)
		(fp_line
			(start -4.05003 -3.0226)
			(end -4.05003 -3.549904)
			(stroke
				(width 0.1524)
				(type default)
			)
			(layer "B.SilkS")
		)
		(fp_line
			(start -4.05003 3.549904)
			(end -4.05003 3.0226)
			(stroke
				(width 0.1524)
				(type default)
			)
			(layer "B.SilkS")
		)
		(fp_line
			(start -3.5052 3.549904)
			(end -4.05003 3.549904)
			(stroke
				(width 0.1524)
				(type default)
			)
			(layer "B.SilkS")
		)
		(fp_line
			(start -0.9906 -3.549904)
			(end -0.0254 -3.549904)
			(stroke
				(width 0.1524)
				(type default)
			)
			(layer "B.SilkS")
		)
		(fp_line
			(start -0.0254 3.549904)
			(end -0.9906 3.549904)
			(stroke
				(width 0.1524)
				(type default)
			)
			(layer "B.SilkS")
		)
		(fp_line
			(start 3.5052 -3.549904)
			(end 4.05003 -3.549904)
			(stroke
				(width 0.1524)
				(type default)
			)
			(layer "B.SilkS")
		)
		(fp_line
			(start 4.05003 -3.549904)
			(end 4.05003 -3.0226)
			(stroke
				(width 0.1524)
				(type default)
			)
			(layer "B.SilkS")
		)
		(fp_line
			(start 4.05003 3.0226)
			(end 4.05003 3.549904)
			(stroke
				(width 0.1524)
				(type default)
			)
			(layer "B.SilkS")
		)
		(fp_line
			(start 4.05003 3.549904)
			(end 3.5052 3.549904)
			(stroke
				(width 0.1524)
				(type default)
			)
			(layer "B.SilkS")
		)
		(fp_poly
			(pts
				(xy 4.886198 -4.246372) (xy 5.604764 -3.52806) (xy 4.527042 -3.168904)
			)
			(stroke
				(width 0)
				(type default)
			)
			(fill yes)
			(layer "B.SilkS")
		)
		(fp_line
			(start -4.05003 -3.549904)
			(end 4.05003 -3.549904)
			(stroke
				(width 0.1)
				(type default)
			)
			(layer "B.Fab")
		)
		(fp_line
			(start -4.05003 3.549904)
			(end -4.05003 -3.549904)
			(stroke
				(width 0.1)
				(type default)
			)
			(layer "B.Fab")
		)
		(fp_line
			(start 4.05003 -3.549904)
			(end 4.05003 3.549904)
			(stroke
				(width 0.1)
				(type default)
			)
			(layer "B.Fab")
		)
		(fp_line
			(start 4.05003 3.549904)
			(end -4.05003 3.549904)
			(stroke
				(width 0.1)
				(type default)
			)
			(layer "B.Fab")
		)
		(fp_poly
			(pts
				(xy 5.588 -3.25882) (xy 5.588 -2.24282) (xy 4.572 -2.75082)
			)
			(stroke
				(width 0)
				(type default)
			)
			(fill yes)
			(layer "B.Fab")
		)
		(pad "1" smd oval
			(at 3.9497 -2.75082 270)
			(size 0.3048 0.8382)
			(layers "B.Cu" "B.Mask" "B.Paste")
			(net "P52V_HS1_ISET")
		)
		(pad "2" smd oval
			(at 3.9497 -2.25044 270)
			(size 0.3048 0.8382)
			(layers "B.Cu" "B.Mask" "B.Paste")
			(net "P52V_HS1_ISTART")
		)
		(pad "3" smd oval
			(at 3.9497 -1.75006 270)
			(size 0.3048 0.8382)
			(layers "B.Cu" "B.Mask" "B.Paste")
			(net "P52V_HS1_VCAP")
		)
		(pad "4" smd oval
			(at 3.9497 -1.24968 270)
			(size 0.3048 0.8382)
			(layers "B.Cu" "B.Mask" "B.Paste")
			(net "P52V_HS1_ESTART_R")
		)
		(pad "5" smd oval
			(at 3.9497 -0.7493 270)
			(size 0.3048 0.8382)
			(layers "B.Cu" "B.Mask" "B.Paste")
			(net "P52V_HS1_EFAULT_R")
		)
		(pad "6" smd oval
			(at 3.9497 -0.24892 270)
			(size 0.3048 0.8382)
			(layers "B.Cu" "B.Mask" "B.Paste")
			(net "P52V_HS1_EN")
		)
		(pad "7" smd oval
			(at 3.9497 0.24892 270)
			(size 0.3048 0.8382)
			(layers "B.Cu" "B.Mask" "B.Paste")
			(net "P52V_HS1_ADR0")
		)
		(pad "8" smd oval
			(at 3.9497 0.7493 270)
			(size 0.3048 0.8382)
			(layers "B.Cu" "B.Mask" "B.Paste")
			(net "P52V_HS1_ADR1")
		)
		(pad "9" smd oval
			(at 3.9497 1.24968 270)
			(size 0.3048 0.8382)
			(layers "B.Cu" "B.Mask" "B.Paste")
			(net "SMB_P52V_PDB_SCL_R1")
		)
		(pad "10" smd oval
			(at 3.9497 1.75006 270)
			(size 0.3048 0.8382)
			(layers "B.Cu" "B.Mask" "B.Paste")
			(net "SMB_CM_HS1_3V3SB_DATI")
		)
		(pad "11" smd oval
			(at 3.9497 2.25044 270)
			(size 0.3048 0.8382)
			(layers "B.Cu" "B.Mask" "B.Paste")
			(net "SMB_CM_HS1_3V3SB_DATO")
		)
		(pad "12" smd oval
			(at 3.9497 2.75082 270)
			(size 0.3048 0.8382)
			(layers "B.Cu" "B.Mask" "B.Paste")
			(net "P52V_HS1_MCB")
		)
		(pad "13" smd oval
			(at 3.2512 3.44932 180)
			(size 0.3048 0.8382)
			(layers "B.Cu" "B.Mask" "B.Paste")
			(net "P52V_HS1_GPO2")
		)
		(pad "14" smd oval
			(at 2.75082 3.44932 180)
			(size 0.3048 0.8382)
			(layers "B.Cu" "B.Mask" "B.Paste")
			(net "P52V_HS1_GPO1")
		)
		(pad "15" smd oval
			(at 2.25044 3.44932 180)
			(size 0.3048 0.8382)
			(layers "B.Cu" "B.Mask" "B.Paste")
			(net "Net_409")
		)
		(pad "16" smd oval
			(at 1.75006 3.44932 180)
			(size 0.3048 0.8382)
			(layers "B.Cu" "B.Mask" "B.Paste")
			(net "Net_408")
		)
		(pad "17" smd oval
			(at 1.24968 3.44932 180)
			(size 0.3048 0.8382)
			(layers "B.Cu" "B.Mask" "B.Paste")
			(net "PWRGD_P52V_HS1_PG")
		)
		(pad "18" smd oval
			(at 0.7493 3.44932 180)
			(size 0.3048 0.8382)
			(layers "B.Cu" "B.Mask" "B.Paste")
			(net "P52V_HS1_PWRGIN")
		)
		(pad "19" smd oval
			(at 0.24892 3.44932 180)
			(size 0.3048 0.8382)
			(layers "B.Cu" "B.Mask" "B.Paste")
			(net "GND_FIELD_SIGNAL")
		)
		(pad "20" smd oval
			(at -1.24968 3.44932 180)
			(size 0.3048 0.8382)
			(layers "B.Cu" "B.Mask" "B.Paste")
			(net "P52V_HS1_VCC")
		)
		(pad "21" smd oval
			(at -1.75006 3.44932 180)
			(size 0.3048 0.8382)
			(layers "B.Cu" "B.Mask" "B.Paste")
			(net "P52V_HS1_VCC")
		)
		(pad "22" smd oval
			(at -2.25044 3.44932 180)
			(size 0.3048 0.8382)
			(layers "B.Cu" "B.Mask" "B.Paste")
			(net "P52V_HS1_VCC")
		)
		(pad "23" smd oval
			(at -2.75082 3.44932 180)
			(size 0.3048 0.8382)
			(layers "B.Cu" "B.Mask" "B.Paste")
			(net "P52V_HS1_VCC")
		)
		(pad "24" smd oval
			(at -3.2512 3.44932 180)
			(size 0.3048 0.8382)
			(layers "B.Cu" "B.Mask" "B.Paste")
			(net "P52V_HS1_VCC")
		)
		(pad "25" smd oval
			(at -3.9497 2.75082 270)
			(size 0.3048 0.8382)
			(layers "B.Cu" "B.Mask" "B.Paste")
			(net "Net_16")
		)
		(pad "26" smd oval
			(at -3.9497 2.25044 270)
			(size 0.3048 0.8382)
			(layers "B.Cu" "B.Mask" "B.Paste")
			(net "Net_8")
		)
		(pad "27" smd oval
			(at -3.9497 1.75006 270)
			(size 0.3048 0.8382)
			(layers "B.Cu" "B.Mask" "B.Paste")
			(net "Net_15")
		)
		(pad "28" smd oval
			(at -3.9497 1.24968 270)
			(size 0.3048 0.8382)
			(layers "B.Cu" "B.Mask" "B.Paste")
			(net "Net_18")
		)
		(pad "29" smd oval
			(at -3.9497 0.7493 270)
			(size 0.3048 0.8382)
			(layers "B.Cu" "B.Mask" "B.Paste")
			(net "P52V_HS1_VCP")
		)
		(pad "30" smd oval
			(at -3.9497 0.24892 270)
			(size 0.3048 0.8382)
			(layers "B.Cu" "B.Mask" "B.Paste")
			(net "P52V_HS1_DV_DT_R")
		)
		(pad "31" smd oval
			(at -3.9497 -0.24892 270)
			(size 0.3048 0.8382)
			(layers "B.Cu" "B.Mask" "B.Paste")
			(net "P52V_HS1")
		)
		(pad "32" smd oval
			(at -3.9497 -0.7493 270)
			(size 0.3048 0.8382)
			(layers "B.Cu" "B.Mask" "B.Paste")
			(net "P52V_HS1_1272_GATE")
		)
		(pad "33" smd oval
			(at -3.9497 -1.24968 270)
			(size 0.3048 0.8382)
			(layers "B.Cu" "B.Mask" "B.Paste")
			(net "Net_21")
		)
		(pad "34" smd oval
			(at -3.9497 -1.75006 270)
			(size 0.3048 0.8382)
			(layers "B.Cu" "B.Mask" "B.Paste")
			(net "Net_20")
		)
		(pad "35" smd oval
			(at -3.9497 -2.25044 270)
			(size 0.3048 0.8382)
			(layers "B.Cu" "B.Mask" "B.Paste")
			(net "Net_4")
		)
		(pad "36" smd oval
			(at -3.9497 -2.75082 270)
			(size 0.3048 0.8382)
			(layers "B.Cu" "B.Mask" "B.Paste")
			(net "Net_17")
		)
		(pad "37" smd oval
			(at -3.2512 -3.44932 180)
			(size 0.3048 0.8382)
			(layers "B.Cu" "B.Mask" "B.Paste")
			(net "Net_13")
		)
		(pad "38" smd oval
			(at -2.75082 -3.44932 180)
			(size 0.3048 0.8382)
			(layers "B.Cu" "B.Mask" "B.Paste")
			(net "P52V_HS_1272_S_N")
		)
		(pad "39" smd oval
			(at -2.25044 -3.44932 180)
			(size 0.3048 0.8382)
			(layers "B.Cu" "B.Mask" "B.Paste")
			(net "P52V_HS_1272_S_P")
		)
		(pad "40" smd oval
			(at -1.75006 -3.44932 180)
			(size 0.3048 0.8382)
			(layers "B.Cu" "B.Mask" "B.Paste")
			(net "Net_12")
		)
		(pad "41" smd oval
			(at -1.24968 -3.44932 180)
			(size 0.3048 0.8382)
			(layers "B.Cu" "B.Mask" "B.Paste")
			(net "P52V_HS1_VCC")
		)
		(pad "42" smd oval
			(at 0.24892 -3.44932 180)
			(size 0.3048 0.8382)
			(layers "B.Cu" "B.Mask" "B.Paste")
			(net "P52V_HS1_VREG")
		)
		(pad "43" smd oval
			(at 0.7493 -3.44932 180)
			(size 0.3048 0.8382)
			(layers "B.Cu" "B.Mask" "B.Paste")
			(net "P52V_HS1_TEMPN")
		)
		(pad "44" smd oval
			(at 1.24968 -3.44932 180)
			(size 0.3048 0.8382)
			(layers "B.Cu" "B.Mask" "B.Paste")
			(net "P52V_HS1_TEMPP")
		)
		(pad "45" smd oval
			(at 1.75006 -3.44932 180)
			(size 0.3048 0.8382)
			(layers "B.Cu" "B.Mask" "B.Paste")
			(net "P52V_HS1_UVH")
		)
		(pad "46" smd oval
			(at 2.25044 -3.44932 180)
			(size 0.3048 0.8382)
			(layers "B.Cu" "B.Mask" "B.Paste")
			(net "P52V_HS1_UVLO_EN")
		)
		(pad "47" smd oval
			(at 2.75082 -3.44932 180)
			(size 0.3048 0.8382)
			(layers "B.Cu" "B.Mask" "B.Paste")
			(net "P52V_HS1_OV")
		)
		(pad "48" smd oval
			(at 3.2512 -3.44932 180)
			(size 0.3048 0.8382)
			(layers "B.Cu" "B.Mask" "B.Paste")
			(net "P52V_HS1_RND")
		)
		(pad "PAD1" smd rect
			(at 1.89738 0 180)
			(size 2.794 5.588)
			(layers "B.Cu" "B.Mask" "B.Paste")
			(net "GND_FIELD_SIGNAL")
		)
		(pad "PAD2" smd rect
			(at -1.55194 0 180)
			(size 1.4986 3.4036)
			(layers "B.Cu" "B.Mask" "B.Paste")
			(net "P52V_HS1_VCC")
		)
		(zone
			(layer "B.Cu")
			(hatch none 0.5)
			(connect_pads
				(clearance 0)
			)
			(min_thickness 0.25)
			(keepout
				(tracks not_allowed)
				(vias allowed)
				(pads allowed)
				(copperpour not_allowed)
				(footprints allowed)
			)
			(placement
				(enabled no)
				(sheetname "")
			)
			(fill
				(thermal_gap 0.5)
				(thermal_bridge_width 0.5)
				(island_removal_mode 0)
			)
			(polygon
				(pts
					(xy 266.6746 -72.5678) (xy 266.6746 -66.6242) (xy 269.3924 -66.6242) (xy 269.3924 -67.8434) (xy 267.7922 -67.8434)
					(xy 267.7922 -71.3486) (xy 269.3924 -71.3486) (xy 269.3924 -72.5678)
				)
			)
		)
		(zone
			(layer "B.Cu")
			(hatch none 0.5)
			(connect_pads
				(clearance 0)
			)
			(min_thickness 0.25)
			(keepout
				(tracks not_allowed)
				(vias allowed)
				(pads allowed)
				(copperpour not_allowed)
				(footprints allowed)
			)
			(placement
				(enabled no)
				(sheetname "")
			)
			(fill
				(thermal_gap 0.5)
				(thermal_bridge_width 0.5)
				(island_removal_mode 0)
			)
			(polygon
				(pts
					(xy 273.6342 -70.9168) (xy 273.6342 -66.6242) (xy 269.4178 -66.6242) (xy 269.4178 -72.5678) (xy 273.6342 -72.5678)
					(xy 273.6342 -70.9422) (xy 273.5072 -70.9422) (xy 273.5072 -72.4408) (xy 270.5862 -72.4408) (xy 270.5862 -66.7512)
					(xy 273.5072 -66.7512) (xy 273.5072 -70.9168)
				)
			)
		)
	)
	(footprint ""
		(layer "B.Cu")
		(at 289.5854 -62.992 90)
		(property "Reference" "PR214"
			(at 0 0 90)
			(layer "B.SilkS")
			(hide yes)
			(effects
				(font
					(size 1.27 1.27)
				)
				(justify mirror)
			)
		)
		(property "Value" ""
			(at 0 0 90)
			(layer "B.Fab")
			(effects
				(font
					(size 1.27 1.27)
				)
				(justify mirror)
			)
		)
		(duplicate_pad_numbers_are_jumpers no)
		(fp_line
			(start 0.7874 -0.4064)
			(end -0.7874 -0.4064)
			(stroke
				(width 0.1524)
				(type default)
			)
			(layer "B.SilkS")
		)
		(fp_line
			(start -0.7874 -0.4064)
			(end -0.7874 0.4064)
			(stroke
				(width 0.1524)
				(type default)
			)
			(layer "B.SilkS")
		)
		(fp_line
			(start 0.7874 0.4064)
			(end 0.7874 -0.4064)
			(stroke
				(width 0.1524)
				(type default)
			)
			(layer "B.SilkS")
		)
		(fp_line
			(start -0.7874 0.4064)
			(end 0.7874 0.4064)
			(stroke
				(width 0.1524)
				(type default)
			)
			(layer "B.SilkS")
		)
		(fp_line
			(start 0.67945 -0.305054)
			(end 0.12065 -0.305054)
			(stroke
				(width 0.1)
				(type default)
			)
			(layer "B.Fab")
		)
		(fp_line
			(start 0.12065 -0.305054)
			(end 0.12065 -0.2794)
			(stroke
				(width 0.1)
				(type default)
			)
			(layer "B.Fab")
		)
		(fp_line
			(start -0.12065 -0.3048)
			(end -0.67945 -0.3048)
			(stroke
				(width 0.1)
				(type default)
			)
			(layer "B.Fab")
		)
		(fp_line
			(start -0.67945 -0.3048)
			(end -0.67945 0.3048)
			(stroke
				(width 0.1)
				(type default)
			)
			(layer "B.Fab")
		)
		(fp_line
			(start 0.12065 -0.2794)
			(end -0.12065 -0.2794)
			(stroke
				(width 0.1)
				(type default)
			)
			(layer "B.Fab")
		)
		(fp_line
			(start -0.12065 -0.2794)
			(end -0.12065 -0.3048)
			(stroke
				(width 0.1)
				(type default)
			)
			(layer "B.Fab")
		)
		(fp_line
			(start 0.12065 0.2794)
			(end 0.12065 0.3048)
			(stroke
				(width 0.1)
				(type default)
			)
			(layer "B.Fab")
		)
		(fp_line
			(start -0.120396 0.2794)
			(end 0.12065 0.2794)
			(stroke
				(width 0.1)
				(type default)
			)
			(layer "B.Fab")
		)
		(fp_line
			(start 0.67945 0.3048)
			(end 0.67945 -0.305054)
			(stroke
				(width 0.1)
				(type default)
			)
			(layer "B.Fab")
		)
		(fp_line
			(start 0.12065 0.3048)
			(end 0.67945 0.3048)
			(stroke
				(width 0.1)
				(type default)
			)
			(layer "B.Fab")
		)
		(fp_line
			(start -0.120396 0.3048)
			(end -0.120396 0.2794)
			(stroke
				(width 0.1)
				(type default)
			)
			(layer "B.Fab")
		)
		(fp_line
			(start -0.67945 0.3048)
			(end -0.120396 0.3048)
			(stroke
				(width 0.1)
				(type default)
			)
			(layer "B.Fab")
		)
		(pad "1" smd circle
			(at 0.40005 0 270)
			(size 0 0)
			(layers "B.Cu" "B.Mask" "B.Paste")
			(net "P52V_HS1_MODE")
		)
		(pad "2" smd circle
			(at -0.40005 0 270)
			(size 0 0)
			(layers "B.Cu" "B.Mask" "B.Paste")
			(net "P52V_HS1_INTVCC")
		)
	)
	(footprint ""
		(layer "B.Cu")
		(at 256.798318 -144.790668 90)
		(property "Reference" "J14"
			(at 1.259332 -5.745988 270)
			(unlocked yes)
			(layer "B.SilkS")
			(effects
				(font
					(size 0.7874 0.5842)
					(thickness 0.1524)
				)
				(justify left mirror)
			)
		)
		(property "Value" ""
			(at 0 0 90)
			(layer "B.Fab")
			(effects
				(font
					(size 1.27 1.27)
				)
				(justify mirror)
			)
		)
		(duplicate_pad_numbers_are_jumpers no)
		(fp_line
			(start 3.330702 -4.771136)
			(end -3.330702 -4.771136)
			(stroke
				(width 0.1524)
				(type default)
			)
			(layer "B.SilkS")
		)
		(fp_line
			(start -3.330702 -4.771136)
			(end 0 4.011168)
			(stroke
				(width 0.1524)
				(type default)
			)
			(layer "B.SilkS")
		)
		(fp_line
			(start 0 4.011168)
			(end 3.330702 -4.771136)
			(stroke
				(width 0.1524)
				(type default)
			)
			(layer "B.SilkS")
		)
		(fp_line
			(start 3.330702 -4.771136)
			(end -3.330702 -4.771136)
			(stroke
				(width 0.1)
				(type default)
			)
			(layer "B.Fab")
		)
		(fp_line
			(start -3.330702 -4.771136)
			(end 0 4.011168)
			(stroke
				(width 0.1)
				(type default)
			)
			(layer "B.Fab")
		)
		(fp_line
			(start 0 4.011168)
			(end 3.330702 -4.771136)
			(stroke
				(width 0.1)
				(type default)
			)
			(layer "B.Fab")
		)
		(pad "1" thru_hole circle
			(at 0 0 270)
			(size 2.159 2.159)
			(drill 1.7018)
			(layers "*.Cu" "*.Mask")
			(remove_unused_layers no)
			(net "GND3")
			(clearance 0.0254)
			(thermal_gap 0.0254)
		)
		(pad "2" thru_hole circle
			(at 1.27 -3.348736 270)
			(size 2.159 2.159)
			(drill 1.7018)
			(layers "*.Cu" "*.Mask")
			(remove_unused_layers no)
			(net "TDR_SE_50_OHM_BOT")
			(clearance 0.0254)
			(thermal_gap 0.0254)
		)
		(pad "3" thru_hole circle
			(at -1.27 -3.348736 270)
			(size 2.159 2.159)
			(drill 1.7018)
			(layers "*.Cu" "*.Mask")
			(remove_unused_layers no)
			(net "TDR_SE_50_OHM_BOT")
			(clearance 0.0254)
			(thermal_gap 0.0254)
		)
	)
	(footprint ""
		(layer "B.Cu")
		(at 281.178 -91.059 -90)
		(property "Reference" "C90"
			(at 0 0 90)
			(layer "B.SilkS")
			(hide yes)
			(effects
				(font
					(size 1.27 1.27)
				)
				(justify mirror)
			)
		)
		(property "Value" ""
			(at 0 0 90)
			(layer "B.Fab")
			(effects
				(font
					(size 1.27 1.27)
				)
				(justify mirror)
			)
		)
		(duplicate_pad_numbers_are_jumpers no)
		(fp_line
			(start -1.2954 0.5842)
			(end 1.2954 0.5842)
			(stroke
				(width 0.1524)
				(type default)
			)
			(layer "B.SilkS")
		)
		(fp_line
			(start 1.2954 0.5842)
			(end 1.2954 -0.5842)
			(stroke
				(width 0.1524)
				(type default)
			)
			(layer "B.SilkS")
		)
		(fp_line
			(start -1.2954 -0.5842)
			(end -1.2954 0.5842)
			(stroke
				(width 0.1524)
				(type default)
			)
			(layer "B.SilkS")
		)
		(fp_line
			(start 1.2954 -0.5842)
			(end -1.2954 -0.5842)
			(stroke
				(width 0.1524)
				(type default)
			)
			(layer "B.SilkS")
		)
		(fp_line
			(start -0.8636 0.4572)
			(end 0.8636 0.4572)
			(stroke
				(width 0.1)
				(type default)
			)
			(layer "B.Fab")
		)
		(fp_line
			(start 0.8636 0.4572)
			(end 0.8636 0.4064)
			(stroke
				(width 0.1)
				(type default)
			)
			(layer "B.Fab")
		)
		(fp_line
			(start -1.1938 0.4064)
			(end -0.8636 0.4064)
			(stroke
				(width 0.1)
				(type default)
			)
			(layer "B.Fab")
		)
		(fp_line
			(start -0.8636 0.4064)
			(end -0.8636 0.4572)
			(stroke
				(width 0.1)
				(type default)
			)
			(layer "B.Fab")
		)
		(fp_line
			(start 0.8636 0.4064)
			(end 1.1938 0.4064)
			(stroke
				(width 0.1)
				(type default)
			)
			(layer "B.Fab")
		)
		(fp_line
			(start 1.1938 0.4064)
			(end 1.1938 -0.4064)
			(stroke
				(width 0.1)
				(type default)
			)
			(layer "B.Fab")
		)
		(fp_line
			(start -1.1938 -0.4064)
			(end -1.1938 0.4064)
			(stroke
				(width 0.1)
				(type default)
			)
			(layer "B.Fab")
		)
		(fp_line
			(start -0.8636 -0.4064)
			(end -1.1938 -0.4064)
			(stroke
				(width 0.1)
				(type default)
			)
			(layer "B.Fab")
		)
		(fp_line
			(start 0.8636 -0.4064)
			(end 0.8636 -0.4572)
			(stroke
				(width 0.1)
				(type default)
			)
			(layer "B.Fab")
		)
		(fp_line
			(start 1.1938 -0.4064)
			(end 0.8636 -0.4064)
			(stroke
				(width 0.1)
				(type default)
			)
			(layer "B.Fab")
		)
		(fp_line
			(start -0.8636 -0.4572)
			(end -0.8636 -0.4064)
			(stroke
				(width 0.1)
				(type default)
			)
			(layer "B.Fab")
		)
		(fp_line
			(start 0.8636 -0.4572)
			(end -0.8636 -0.4572)
			(stroke
				(width 0.1)
				(type default)
			)
			(layer "B.Fab")
		)
		(pad "1" smd rect
			(at 0.7366 0 180)
			(size 0.7112 0.8128)
			(layers "B.Cu" "B.Mask" "B.Paste")
			(net "FM_HS1_EN_BUSBAR")
		)
		(pad "2" smd rect
			(at -0.7366 0 180)
			(size 0.7112 0.8128)
			(layers "B.Cu" "B.Mask" "B.Paste")
			(net "GND")
		)
	)
	(footprint ""
		(layer "B.Cu")
		(at 274.8534 -76.454 -90)
		(property "Reference" "PR482"
			(at 0 0 90)
			(layer "B.SilkS")
			(hide yes)
			(effects
				(font
					(size 1.27 1.27)
				)
				(justify mirror)
			)
		)
		(property "Value" ""
			(at 0 0 90)
			(layer "B.Fab")
			(effects
				(font
					(size 1.27 1.27)
				)
				(justify mirror)
			)
		)
		(duplicate_pad_numbers_are_jumpers no)
		(fp_line
			(start -0.7874 0.4064)
			(end 0.7874 0.4064)
			(stroke
				(width 0.1524)
				(type default)
			)
			(layer "B.SilkS")
		)
		(fp_line
			(start 0.7874 0.4064)
			(end 0.7874 -0.4064)
			(stroke
				(width 0.1524)
				(type default)
			)
			(layer "B.SilkS")
		)
		(fp_line
			(start -0.7874 -0.4064)
			(end -0.7874 0.4064)
			(stroke
				(width 0.1524)
				(type default)
			)
			(layer "B.SilkS")
		)
		(fp_line
			(start 0.7874 -0.4064)
			(end -0.7874 -0.4064)
			(stroke
				(width 0.1524)
				(type default)
			)
			(layer "B.SilkS")
		)
		(fp_line
			(start -0.67945 0.3048)
			(end -0.120396 0.3048)
			(stroke
				(width 0.1)
				(type default)
			)
			(layer "B.Fab")
		)
		(fp_line
			(start -0.120396 0.3048)
			(end -0.120396 0.2794)
			(stroke
				(width 0.1)
				(type default)
			)
			(layer "B.Fab")
		)
		(fp_line
			(start 0.12065 0.3048)
			(end 0.67945 0.3048)
			(stroke
				(width 0.1)
				(type default)
			)
			(layer "B.Fab")
		)
		(fp_line
			(start 0.67945 0.3048)
			(end 0.67945 -0.305054)
			(stroke
				(width 0.1)
				(type default)
			)
			(layer "B.Fab")
		)
		(fp_line
			(start -0.120396 0.2794)
			(end 0.12065 0.2794)
			(stroke
				(width 0.1)
				(type default)
			)
			(layer "B.Fab")
		)
		(fp_line
			(start 0.12065 0.2794)
			(end 0.12065 0.3048)
			(stroke
				(width 0.1)
				(type default)
			)
			(layer "B.Fab")
		)
		(fp_line
			(start -0.12065 -0.2794)
			(end -0.12065 -0.3048)
			(stroke
				(width 0.1)
				(type default)
			)
			(layer "B.Fab")
		)
		(fp_line
			(start 0.12065 -0.2794)
			(end -0.12065 -0.2794)
			(stroke
				(width 0.1)
				(type default)
			)
			(layer "B.Fab")
		)
		(fp_line
			(start -0.67945 -0.3048)
			(end -0.67945 0.3048)
			(stroke
				(width 0.1)
				(type default)
			)
			(layer "B.Fab")
		)
		(fp_line
			(start -0.12065 -0.3048)
			(end -0.67945 -0.3048)
			(stroke
				(width 0.1)
				(type default)
			)
			(layer "B.Fab")
		)
		(fp_line
			(start 0.12065 -0.305054)
			(end 0.12065 -0.2794)
			(stroke
				(width 0.1)
				(type default)
			)
			(layer "B.Fab")
		)
		(fp_line
			(start 0.67945 -0.305054)
			(end 0.12065 -0.305054)
			(stroke
				(width 0.1)
				(type default)
			)
			(layer "B.Fab")
		)
		(pad "1" smd circle
			(at 0.40005 0 90)
			(size 0 0)
			(layers "B.Cu" "B.Mask" "B.Paste")
			(net "P52V_HS1_OV")
		)
		(pad "2" smd circle
			(at -0.40005 0 90)
			(size 0 0)
			(layers "B.Cu" "B.Mask" "B.Paste")
			(net "GND_FIELD_SIGNAL")
		)
	)
	(footprint ""
		(layer "B.Cu")
		(at 445.5414 -47.625 180)
		(property "Reference" "U40"
			(at -0.4445 -2.50317 0)
			(unlocked yes)
			(layer "B.SilkS")
			(effects
				(font
					(size 0.7874 0.5842)
					(thickness 0.1524)
				)
				(justify left mirror)
			)
		)
		(property "Value" ""
			(at 0 0 0)
			(layer "B.Fab")
			(effects
				(font
					(size 1.27 1.27)
				)
				(justify mirror)
			)
		)
		(duplicate_pad_numbers_are_jumpers no)
		(fp_line
			(start 1.733296 1.549908)
			(end -1.733296 1.549908)
			(stroke
				(width 0.1524)
				(type default)
			)
			(layer "B.SilkS")
		)
		(fp_line
			(start 1.733296 -1.549908)
			(end 1.733296 1.549908)
			(stroke
				(width 0.1524)
				(type default)
			)
			(layer "B.SilkS")
		)
		(fp_line
			(start 0.660908 -1.549908)
			(end 1.733296 -1.549908)
			(stroke
				(width 0.1524)
				(type default)
			)
			(layer "B.SilkS")
		)
		(fp_line
			(start 0 -0.889)
			(end 0.660908 -1.549908)
			(stroke
				(width 0.1524)
				(type default)
			)
			(layer "B.SilkS")
		)
		(fp_line
			(start -0.660908 -1.549908)
			(end 0 -0.889)
			(stroke
				(width 0.1524)
				(type default)
			)
			(layer "B.SilkS")
		)
		(fp_line
			(start -1.733296 1.549908)
			(end -1.733296 -1.549908)
			(stroke
				(width 0.1524)
				(type default)
			)
			(layer "B.SilkS")
		)
		(fp_line
			(start -1.733296 -1.549908)
			(end -0.660908 -1.549908)
			(stroke
				(width 0.1524)
				(type default)
			)
			(layer "B.SilkS")
		)
		(fp_poly
			(pts
				(xy 2.4384 -1.20396) (xy 2.4384 -0.69596) (xy 1.9304 -0.94996)
			)
			(stroke
				(width 0)
				(type default)
			)
			(fill yes)
			(layer "B.SilkS")
		)
		(fp_line
			(start 0.849884 1.549908)
			(end -0.849884 1.549908)
			(stroke
				(width 0.1)
				(type default)
			)
			(layer "B.Fab")
		)
		(fp_line
			(start 0.849884 -1.549908)
			(end 0.849884 1.549908)
			(stroke
				(width 0.1)
				(type default)
			)
			(layer "B.Fab")
		)
		(fp_line
			(start -0.849884 1.549908)
			(end -0.849884 -1.549908)
			(stroke
				(width 0.1)
				(type default)
			)
			(layer "B.Fab")
		)
		(fp_line
			(start -0.849884 -1.549908)
			(end 0.849884 -1.549908)
			(stroke
				(width 0.1)
				(type default)
			)
			(layer "B.Fab")
		)
		(fp_poly
			(pts
				(xy 2.4384 -1.20396) (xy 2.4384 -0.69596) (xy 1.9304 -0.94996)
			)
			(stroke
				(width 0)
				(type default)
			)
			(fill yes)
			(layer "B.Fab")
		)
		(pad "1" smd rect
			(at 1.199896 -0.94996 90)
			(size 0.5588 0.8128)
			(layers "B.Cu" "B.Mask" "B.Paste")
			(net "FAN_PWR_EN_BUF_R")
		)
		(pad "2" smd rect
			(at 1.199896 0 90)
			(size 0.5588 0.8128)
			(layers "B.Cu" "B.Mask" "B.Paste")
			(net "P3V3_HPDB_PG_R1")
		)
		(pad "3" smd rect
			(at 1.199896 0.94996 90)
			(size 0.5588 0.8128)
			(layers "B.Cu" "B.Mask" "B.Paste")
			(net "GND")
		)
		(pad "4" smd rect
			(at -1.199896 0.94996 90)
			(size 0.5588 0.8128)
			(layers "B.Cu" "B.Mask" "B.Paste")
			(net "P12V_LED_EN_BUF")
		)
		(pad "5" smd rect
			(at -1.199896 -0.94996 90)
			(size 0.5588 0.8128)
			(layers "B.Cu" "B.Mask" "B.Paste")
			(net "P3V3_AUX")
		)
	)
	(gr_poly
		(pts
			(xy 119.020336 -77.8256) (xy 119.020336 -76.5302) (xy 118.994936 -76.5048) (xy 112.670336 -76.5048)
			(xy 112.619536 -76.5556) (xy 112.619536 -77.8002) (xy 112.670336 -77.851) (xy 118.994936 -77.851)
		)
		(stroke
			(width 0)
			(type solid)
		)
		(fill yes)
		(layer "F.Cu")
		(net "P52V_HS2_GATE1")
	)
	(gr_poly
		(pts
			(xy 119.020336 -66.548) (xy 119.020336 -65.2526) (xy 118.994936 -65.2272) (xy 112.670336 -65.2272)
			(xy 112.619536 -65.278) (xy 112.619536 -66.5226) (xy 112.670336 -66.5734) (xy 118.994936 -66.5734)
		)
		(stroke
			(width 0)
			(type solid)
		)
		(fill yes)
		(layer "F.Cu")
		(net "P52V_HS2_GATE2")
	)
	(gr_poly
		(pts
			(xy 119.020336 -55.2704) (xy 119.020336 -53.975) (xy 118.994936 -53.9496) (xy 112.670336 -53.9496)
			(xy 112.619536 -54.0004) (xy 112.619536 -55.245) (xy 112.670336 -55.2958) (xy 118.994936 -55.2958)
		)
		(stroke
			(width 0)
			(type solid)
		)
		(fill yes)
		(layer "F.Cu")
		(net "P52V_HS2_GATE3")
	)
	(gr_poly
		(pts
			(xy 119.020336 -43.9928) (xy 119.020336 -42.6974) (xy 118.994936 -42.672) (xy 112.670336 -42.672)
			(xy 112.619536 -42.7228) (xy 112.619536 -43.9674) (xy 112.670336 -44.0182) (xy 118.994936 -44.0182)
		)
		(stroke
			(width 0)
			(type solid)
		)
		(fill yes)
		(layer "F.Cu")
		(net "P52V_HS2_GATE4")
	)
	(gr_poly
		(pts
			(xy 119.020336 -32.7152) (xy 119.020336 -31.4198) (xy 118.994936 -31.3944) (xy 112.670336 -31.3944)
			(xy 112.619536 -31.4452) (xy 112.619536 -32.6898) (xy 112.670336 -32.7406) (xy 118.994936 -32.7406)
		)
		(stroke
			(width 0)
			(type solid)
		)
		(fill yes)
		(layer "F.Cu")
		(net "P52V_HS2_GATE5")
	)
	(gr_poly
		(pts
			(xy 119.020336 -21.4376) (xy 119.020336 -20.1422) (xy 118.994936 -20.1168) (xy 112.670336 -20.1168)
			(xy 112.619536 -20.1676) (xy 112.619536 -21.4122) (xy 112.670336 -21.463) (xy 118.994936 -21.463)
		)
		(stroke
			(width 0)
			(type solid)
		)
		(fill yes)
		(layer "F.Cu")
		(net "P52V_HS2_GATE6")
	)
	(gr_poly
		(pts
			(xy 193.112136 -50.557684) (xy 193.112136 -46.692312) (xy 189.726824 -43.307) (xy 186.125866 -43.307)
			(xy 182.695088 -46.737778) (xy 182.695088 -50.684938) (xy 182.94223 -50.93208) (xy 192.73774 -50.93208)
		)
		(stroke
			(width 0)
			(type solid)
		)
		(fill yes)
		(layer "F.Cu")
		(net "P52V_2_FUSE_1")
	)
	(gr_poly
		(pts
			(xy 257.683 -50.557684) (xy 257.683 -46.692312) (xy 254.297688 -43.307) (xy 250.69673 -43.307) (xy 247.265952 -46.737778)
			(xy 247.265952 -50.684938) (xy 247.513094 -50.93208) (xy 257.308604 -50.93208)
		)
		(stroke
			(width 0)
			(type solid)
		)
		(fill yes)
		(layer "F.Cu")
		(net "P52V_1_FUSE_1")
	)
	(gr_poly
		(pts
			(xy 335.0006 -72.7456) (xy 335.0006 -71.501) (xy 334.9498 -71.4502) (xy 328.6252 -71.4502) (xy 328.5998 -71.4756)
			(xy 328.5998 -72.771) (xy 328.6252 -72.7964) (xy 334.9498 -72.7964)
		)
		(stroke
			(width 0)
			(type solid)
		)
		(fill yes)
		(layer "F.Cu")
		(net "P52V_HS1_GATE1")
	)
	(gr_poly
		(pts
			(xy 335.0006 -61.468) (xy 335.0006 -60.2234) (xy 334.9498 -60.1726) (xy 328.6252 -60.1726) (xy 328.5998 -60.198)
			(xy 328.5998 -61.4934) (xy 328.6252 -61.5188) (xy 334.9498 -61.5188)
		)
		(stroke
			(width 0)
			(type solid)
		)
		(fill yes)
		(layer "F.Cu")
		(net "P52V_HS1_GATE2")
	)
	(gr_poly
		(pts
			(xy 335.0006 -50.1904) (xy 335.0006 -48.9458) (xy 334.9498 -48.895) (xy 328.6252 -48.895) (xy 328.5998 -48.9204)
			(xy 328.5998 -50.2158) (xy 328.6252 -50.2412) (xy 334.9498 -50.2412)
		)
		(stroke
			(width 0)
			(type solid)
		)
		(fill yes)
		(layer "F.Cu")
		(net "P52V_HS1_GATE3")
	)
	(gr_poly
		(pts
			(xy 335.0006 -38.9128) (xy 335.0006 -37.6682) (xy 334.9498 -37.6174) (xy 328.6252 -37.6174) (xy 328.5998 -37.6428)
			(xy 328.5998 -38.9382) (xy 328.6252 -38.9636) (xy 334.9498 -38.9636)
		)
		(stroke
			(width 0)
			(type solid)
		)
		(fill yes)
		(layer "F.Cu")
		(net "P52V_HS1_GATE6")
	)
	(gr_poly
		(pts
			(xy 335.0006 -27.6352) (xy 335.0006 -26.3906) (xy 334.9498 -26.3398) (xy 328.6252 -26.3398) (xy 328.5998 -26.3652)
			(xy 328.5998 -27.6606) (xy 328.6252 -27.686) (xy 334.9498 -27.686)
		)
		(stroke
			(width 0)
			(type solid)
		)
		(fill yes)
		(layer "F.Cu")
		(net "P52V_HS1_GATE4")
	)
	(gr_poly
		(pts
			(xy 335.0006 -16.3576) (xy 335.0006 -15.113) (xy 334.9498 -15.0622) (xy 328.6252 -15.0622) (xy 328.5998 -15.0876)
			(xy 328.5998 -16.383) (xy 328.6252 -16.4084) (xy 334.9498 -16.4084)
		)
		(stroke
			(width 0)
			(type solid)
		)
		(fill yes)
		(layer "F.Cu")
		(net "P52V_HS1_GATE5")
	)
	(gr_poly
		(pts
			(xy 415.672778 -30.503876) (xy 415.672778 -29.812996) (xy 415.609278 -29.749496) (xy 413.335978 -29.749496)
			(xy 413.211518 -29.873956) (xy 413.211518 -30.557216) (xy 413.297878 -30.643576) (xy 415.533078 -30.643576)
		)
		(stroke
			(width 0)
			(type solid)
		)
		(fill yes)
		(layer "F.Cu")
		(net "P12V_LED_FLTB")
	)
	(gr_poly
		(pts
			(xy 445.3636 -83.6676) (xy 445.3636 -83.2612) (xy 445.2874 -83.185) (xy 443.2808 -83.185) (xy 443.23 -83.2358)
			(xy 443.23 -83.6676) (xy 443.2808 -83.7184) (xy 445.3128 -83.7184)
		)
		(stroke
			(width 0)
			(type solid)
		)
		(fill yes)
		(layer "F.Cu")
		(net "P3V3_HPDB_VCC")
	)
	(gr_poly
		(pts
			(xy 451.0532 -82.2198) (xy 451.0532 -81.661) (xy 450.9516 -81.5594) (xy 449.6308 -81.5594) (xy 449.5292 -81.661)
			(xy 449.5292 -82.2452) (xy 449.58 -82.296) (xy 450.977 -82.296)
		)
		(stroke
			(width 0)
			(type solid)
		)
		(fill yes)
		(layer "F.Cu")
		(net "SW_P3V3_HPDB_BT_R")
	)
	(gr_poly
		(pts
			(xy 426.085 -30.6324) (xy 426.085 -28.194) (xy 425.9834 -28.0924) (xy 415.8488 -28.0924) (xy 415.823654 -28.117546)
			(xy 415.823654 -29.3878) (xy 420.2176 -29.3878) (xy 421.7162 -30.8864) (xy 425.831 -30.8864)
		)
		(stroke
			(width 0)
			(type solid)
		)
		(fill yes)
		(layer "F.Cu")
		(net "P12V_HPDB")
	)
	(gr_poly
		(pts
			(xy 454.8124 -71.06539) (xy 454.8124 -62.484) (xy 454.6854 -62.357) (xy 453.5424 -62.357) (xy 453.2884 -62.611)
			(xy 440.29884 -62.611) (xy 439.6994 -63.21044) (xy 439.6994 -70.739) (xy 440.3344 -71.374) (xy 454.50379 -71.374)
		)
		(stroke
			(width 0)
			(type solid)
		)
		(fill yes)
		(layer "F.Cu")
		(net "P3V3_AUX")
	)
	(gr_poly
		(pts
			(xy 453.7964 -103.378) (xy 453.7964 -98.171) (xy 453.5551 -97.9297) (xy 451.6247 -97.9297) (xy 450.984874 -97.9297)
			(xy 450.749162 -98.165412) (xy 450.749162 -103.311452) (xy 450.94779 -103.51008) (xy 451.6374 -103.51008)
			(xy 453.33793 -103.51008) (xy 453.66432 -103.51008)
		)
		(stroke
			(width 0)
			(type solid)
		)
		(fill yes)
		(layer "F.Cu")
		(net "P12V_HPDB")
	)
	(gr_poly
		(pts
			(xy 448.14363 -83.70443) (xy 448.14363 -83.40217) (xy 449.2752 -82.2706) (xy 449.2752 -81.70926)
			(xy 449.21932 -81.65338) (xy 448.73672 -81.65338) (xy 448.660266 -81.729834) (xy 448.660266 -81.733898)
			(xy 448.660266 -81.845658) (xy 447.21018 -83.295744) (xy 447.21018 -83.648804) (xy 447.21018 -83.70824)
			(xy 447.22288 -83.72094) (xy 448.12712 -83.72094)
		)
		(stroke
			(width 0)
			(type solid)
		)
		(fill yes)
		(layer "F.Cu")
		(net "SW_P3V3_HPDB_BT")
	)
	(gr_poly
		(pts
			(xy 419.6842 -27.7368) (xy 419.6842 -19.304) (xy 419.4302 -19.05) (xy 415.671 -19.05) (xy 415.5186 -19.2024)
			(xy 415.5186 -21.703792) (xy 415.933128 -22.11832)
			(arc
				(start 415.933128 -27.697684)
				(mid 415.936961 -27.717041)
				(end 415.94786 -27.733498)
			)
			(arc
				(start 415.985452 -27.77109)
				(mid 416.001986 -27.782201)
				(end 416.02152 -27.786076)
			)
			(xy 419.634924 -27.786076)
		)
		(stroke
			(width 0)
			(type solid)
		)
		(fill yes)
		(layer "F.Cu")
		(net "P12V_FAN_LED")
	)
	(gr_poly
		(pts
			(xy 449.0974 -105.918) (xy 449.0974 -89.747852) (xy 446.788286 -87.438738) (xy 446.788286 -82.927698)
			(xy 447.121026 -82.594958) (xy 447.121026 -81.787238) (xy 447.088006 -81.754218) (xy 446.531746 -81.754218)
			(xy 446.478406 -81.807558) (xy 446.478406 -85.185758) (xy 446.102486 -85.561678) (xy 446.102486 -95.298514)
			(xy 443.6364 -97.7646) (xy 443.6364 -106.045) (xy 443.7634 -106.172) (xy 448.8434 -106.172)
		)
		(stroke
			(width 0)
			(type solid)
		)
		(fill yes)
		(layer "F.Cu")
		(net "SW_P3V3_HPDB_FLT")
	)
	(gr_poly
		(pts
			(xy 142.353284 -45.784516) (xy 142.353284 -42.048684) (xy 140.8176 -40.513) (xy 138.938 -40.513)
			(xy 137.541 -39.116) (xy 137.541 -33.3756) (xy 137.922 -32.9946) (xy 142.312136 -32.9946) (xy 142.362936 -32.9438)
			(xy 142.362936 -30.226) (xy 141.981936 -29.845) (xy 141.981936 -29.2608) (xy 142.354046 -28.88869)
			(xy 142.354046 -13.07211) (xy 142.185136 -12.9032) (xy 123.846336 -12.9032) (xy 123.516136 -13.2334)
			(xy 123.516136 -45.8724) (xy 123.795536 -46.1518) (xy 141.986 -46.1518)
		)
		(stroke
			(width 0)
			(type solid)
		)
		(fill yes)
		(layer "F.Cu")
		(net "P52V_HS2_DRAIN_2")
	)
	(gr_poly
		(pts
			(xy 419.2524 -35.01136) (xy 419.2524 -32.9946) (xy 419.16096 -32.90316) (xy 416.687 -32.90316)
			(arc
				(start 413.215582 -32.90316)
				(mid 413.196059 -32.907061)
				(end 413.179514 -32.918146)
			)
			(arc
				(start 413.123126 -32.974534)
				(mid 413.112015 -32.991068)
				(end 413.10814 -33.010602)
			)
			(arc
				(start 413.10814 -35.051238)
				(mid 413.112041 -35.070761)
				(end 413.123126 -35.087306)
			)
			(arc
				(start 413.235394 -35.199574)
				(mid 413.251928 -35.210685)
				(end 413.271462 -35.21456)
			)
			(xy 419.0492 -35.21456)
		)
		(stroke
			(width 0)
			(type solid)
		)
		(fill yes)
		(layer "F.Cu")
		(net "GND")
	)
	(gr_poly
		(pts
			(xy 136.368536 -79.629) (xy 136.368536 -68.0466) (xy 137.587736 -66.8274) (xy 142.312136 -66.8274)
			(xy 142.362936 -66.7766) (xy 142.362936 -64.0588) (xy 141.981936 -63.6778) (xy 141.981936 -63.6524)
			(xy 141.981936 -63.627) (xy 141.981936 -63.0936) (xy 142.354046 -62.72149) (xy 142.354046 -62.592712)
			(xy 142.354046 -46.90491) (xy 142.185136 -46.736) (xy 132.025136 -46.736) (xy 123.846336 -46.736)
			(xy 123.516136 -47.0662) (xy 123.516136 -79.7052) (xy 123.795536 -79.9846) (xy 132.050536 -79.9846)
			(xy 134.565136 -79.9846) (xy 136.012936 -79.9846)
		)
		(stroke
			(width 0)
			(type solid)
		)
		(fill yes)
		(layer "F.Cu")
		(net "P52V_HS2_DRAIN_1")
	)
	(gr_poly
		(pts
			(xy 324.104 -79.7052) (xy 324.104 -47.0662) (xy 323.7738 -46.736) (xy 315.595 -46.736) (xy 305.435 -46.736)
			(xy 305.26609 -46.90491) (xy 305.26609 -62.592712) (xy 305.26609 -62.72149) (xy 305.6382 -63.0936)
			(xy 305.6382 -63.627) (xy 305.6382 -63.6524) (xy 305.6382 -63.6778) (xy 305.2572 -64.0588) (xy 305.2572 -66.7766)
			(xy 305.308 -66.8274) (xy 310.0324 -66.8274) (xy 311.2516 -68.0466) (xy 311.2516 -79.629) (xy 311.6072 -79.9846)
			(xy 313.055 -79.9846) (xy 315.5696 -79.9846) (xy 323.8246 -79.9846)
		)
		(stroke
			(width 0)
			(type solid)
		)
		(fill yes)
		(layer "F.Cu")
		(net "P52V_HS1_DRAIN_1")
	)
	(gr_poly
		(pts
			(xy 324.104 -45.8724) (xy 324.104 -13.2334) (xy 323.7738 -12.9032) (xy 315.595 -12.9032) (xy 315.1632 -13.335)
			(xy 305.6382 -13.335) (xy 305.26609 -13.70711) (xy 305.26609 -28.88869) (xy 305.6382 -29.2608) (xy 305.6382 -29.845)
			(xy 305.2572 -30.226) (xy 305.2572 -32.9438) (xy 305.308 -32.9946) (xy 310.0324 -32.9946) (xy 311.2516 -34.2138)
			(xy 311.2516 -39.243) (xy 309.4736 -41.021) (xy 308.6608 -41.021) (xy 305.24958 -44.43222) (xy 305.24958 -45.847)
			(xy 305.55438 -46.1518) (xy 323.8246 -46.1518)
		)
		(stroke
			(width 0)
			(type solid)
		)
		(fill yes)
		(layer "F.Cu")
		(net "P52V_HS1_DRAIN_2")
	)
	(gr_poly
		(pts
			(xy 402.837396 -27.788616) (xy 402.837396 -24.943816)
			(arc
				(start 402.837396 -15.66799)
				(mid 402.833495 -15.648467)
				(end 402.82241 -15.631922)
			)
			(arc
				(start 402.449284 -15.258796)
				(mid 402.43275 -15.247685)
				(end 402.413216 -15.24381)
			)
			(arc
				(start 398.926558 -15.24381)
				(mid 398.907035 -15.247711)
				(end 398.89049 -15.258796)
			)
			(arc
				(start 397.912336 -16.23695)
				(mid 397.901225 -16.253484)
				(end 397.89735 -16.273018)
			)
			(xy 397.89735 -24.943816) (xy 397.89735 -27.664918) (xy 398.261586 -28.029154) (xy 402.596858 -28.029154)
		)
		(stroke
			(width 0)
			(type solid)
		)
		(fill yes)
		(layer "F.Cu")
		(net "P52V_HS1_EN_DISCHARGE_VBE_R")
	)
	(gr_poly
		(pts
			(xy 446.186306 -84.847938) (xy 446.186306 -81.6356) (xy 446.938908 -80.882998) (xy 449.06184 -80.882998)
			(xy 449.09486 -80.916018) (xy 449.09486 -80.916272) (xy 450.816472 -80.916272) (xy 451.3072 -81.407)
			(xy 451.3072 -82.2198) (xy 451.3326 -82.2452) (xy 452.0184 -82.2452) (xy 452.12 -82.1436) (xy 452.12 -77.6224)
			(xy 452.12 -77.3176) (xy 451.7644 -76.962) (xy 444.2714 -76.962) (xy 443.956186 -77.277214) (xy 443.956186 -77.71511)
			(xy 443.956186 -81.22539) (xy 445.884046 -83.15325) (xy 445.884046 -84.875878) (xy 445.952626 -84.944458)
			(xy 446.089786 -84.944458)
		)
		(stroke
			(width 0)
			(type solid)
		)
		(fill yes)
		(layer "F.Cu")
		(net "SW_P3V3_HPDB_PH")
	)
	(gr_poly
		(pts
			(arc
				(start 412.797498 -30.61716)
				(mid 412.817021 -30.613259)
				(end 412.833566 -30.602174)
			)
			(arc
				(start 412.905194 -30.530546)
				(mid 412.916305 -30.514012)
				(end 412.92018 -30.494478)
			)
			(xy 412.92018 -28.926282) (xy 412.91256 -28.90774)
			(arc
				(start 412.909766 -28.904946)
				(mid 412.893232 -28.893835)
				(end 412.873698 -28.88996)
			)
			(arc
				(start 411.899862 -28.88996)
				(mid 411.880339 -28.893861)
				(end 411.863794 -28.904946)
			)
			(arc
				(start 411.715966 -29.052774)
				(mid 411.704855 -29.069308)
				(end 411.70098 -29.088842)
			)
			(arc
				(start 411.70098 -30.418278)
				(mid 411.704881 -30.437801)
				(end 411.715966 -30.454346)
			)
			(arc
				(start 411.863794 -30.602174)
				(mid 411.880328 -30.613285)
				(end 411.899862 -30.61716)
			)
		)
		(stroke
			(width 0)
			(type solid)
		)
		(fill yes)
		(layer "F.Cu")
		(net "P3V3_AUX")
	)
	(gr_poly
		(pts
			(arc
				(start 52.572412 -25.4)
				(mid 52.591935 -25.396099)
				(end 52.60848 -25.385014)
			)
			(arc
				(start 52.832508 -25.160986)
				(mid 52.843619 -25.144452)
				(end 52.847494 -25.124918)
			)
			(arc
				(start 52.847494 -16.658082)
				(mid 52.843593 -16.638559)
				(end 52.832508 -16.622014)
			)
			(arc
				(start 52.48148 -16.270986)
				(mid 52.464946 -16.259875)
				(end 52.445412 -16.256)
			)
			(arc
				(start 48.931576 -16.256)
				(mid 48.912053 -16.259901)
				(end 48.895508 -16.270986)
			)
			(arc
				(start 48.54448 -16.622014)
				(mid 48.533369 -16.638548)
				(end 48.529494 -16.658082)
			)
			(arc
				(start 48.529494 -25.251918)
				(mid 48.533395 -25.271441)
				(end 48.54448 -25.287986)
			)
			(arc
				(start 48.641508 -25.385014)
				(mid 48.658042 -25.396125)
				(end 48.677576 -25.4)
			)
		)
		(stroke
			(width 0)
			(type solid)
		)
		(fill yes)
		(layer "F.Cu")
		(net "GND")
	)
	(gr_poly
		(pts
			(arc
				(start 414.092898 -27.69616)
				(mid 414.112421 -27.692259)
				(end 414.128966 -27.681174)
			)
			(arc
				(start 414.251394 -27.558746)
				(mid 414.262505 -27.542212)
				(end 414.26638 -27.522678)
			)
			(arc
				(start 414.26638 -25.355042)
				(mid 414.262479 -25.335519)
				(end 414.251394 -25.318974)
			)
			(arc
				(start 414.154366 -25.221946)
				(mid 414.137832 -25.210835)
				(end 414.118298 -25.20696)
			)
			(arc
				(start 413.423862 -25.20696)
				(mid 413.404339 -25.210861)
				(end 413.387794 -25.221946)
			)
			(arc
				(start 413.36722 -25.24252)
				(mid 413.356294 -25.258966)
				(end 413.352488 -25.278334)
			)
			(arc
				(start 413.352488 -27.548586)
				(mid 413.356321 -27.567943)
				(end 413.36722 -27.5844)
			)
			(arc
				(start 413.463994 -27.681174)
				(mid 413.480528 -27.692285)
				(end 413.500062 -27.69616)
			)
		)
		(stroke
			(width 0)
			(type solid)
		)
		(fill yes)
		(layer "F.Cu")
		(net "GND")
	)
	(gr_poly
		(pts
			(arc
				(start 415.62782 -27.75966)
				(mid 415.663741 -27.744781)
				(end 415.67862 -27.70886)
			)
			(xy 415.67862 -26.11882) (xy 415.63544 -26.07564) (xy 415.63544 -23.30958) (xy 415.614612 -23.288752)
			(xy 415.614612 -22.905212) (xy 415.51606 -22.80666)
			(arc
				(start 414.963102 -22.80666)
				(mid 414.943579 -22.810561)
				(end 414.927034 -22.821646)
			)
			(arc
				(start 414.804606 -22.944074)
				(mid 414.793495 -22.960608)
				(end 414.78962 -22.980142)
			)
			(arc
				(start 414.78962 -26.129996)
				(mid 414.793521 -26.149519)
				(end 414.804606 -26.166064)
			)
			(arc
				(start 415.231834 -26.593292)
				(mid 415.242945 -26.609826)
				(end 415.24682 -26.62936)
			)
			(arc
				(start 415.24682 -27.662378)
				(mid 415.250721 -27.681901)
				(end 415.261806 -27.698446)
			)
			(arc
				(start 415.308034 -27.744674)
				(mid 415.324568 -27.755785)
				(end 415.344102 -27.75966)
			)
		)
		(stroke
			(width 0)
			(type solid)
		)
		(fill yes)
		(layer "F.Cu")
		(net "P12V_LED_PD")
	)
	(gr_poly
		(pts
			(xy 450.52996 -85.73008) (xy 450.52996 -85.26018) (xy 450.52361 -85.25383) (xy 450.8881 -84.88934)
			(xy 451.58914 -84.88934) (xy 451.74154 -84.88934) (xy 451.79996 -84.83092) (xy 451.79996 -82.64144)
			(xy 451.74154 -82.58302) (xy 451.66534 -82.58302) (xy 449.51396 -82.58302) (xy 449.35521 -82.74177)
			(xy 448.13474 -83.96224) (xy 447.3575 -83.96224) (xy 447.33464 -83.9851) (xy 447.33464 -84.12734)
			(xy 447.358516 -84.151216) (xy 448.31 -84.151216) (xy 449.474336 -82.98688) (xy 449.5292 -82.98688)
			(xy 450.35978 -82.98688) (xy 450.4436 -83.0707) (xy 450.4436 -84.7471) (xy 450.18452 -85.00618) (xy 450.052186 -85.00618)
			(xy 449.486528 -85.571838) (xy 449.316602 -85.571838) (xy 449.202302 -85.571838) (xy 447.596006 -85.571838)
			(xy 447.348102 -85.571838) (xy 447.33464 -85.5853) (xy 447.33464 -85.725) (xy 447.355468 -85.745828)
			(xy 447.589148 -85.745828) (xy 448.61734 -85.745828) (xy 448.698112 -85.8266) (xy 450.19722 -85.8266)
			(xy 450.24802 -85.8266) (xy 450.43344 -85.8266)
		)
		(stroke
			(width 0)
			(type solid)
		)
		(fill yes)
		(layer "F.Cu")
		(net "GND")
	)
	(gr_poly
		(pts
			(arc
				(start 413.051498 -27.69616)
				(mid 413.071021 -27.692259)
				(end 413.087566 -27.681174)
			)
			(xy 413.09036 -27.67838) (xy 413.09798 -27.659838)
			(arc
				(start 413.09798 -24.999442)
				(mid 413.101881 -24.979919)
				(end 413.112966 -24.963374)
			)
			(arc
				(start 413.286194 -24.790146)
				(mid 413.302728 -24.779035)
				(end 413.322262 -24.77516)
			)
			(arc
				(start 414.143698 -24.77516)
				(mid 414.163221 -24.771259)
				(end 414.179766 -24.760174)
			)
			(arc
				(start 414.225994 -24.713946)
				(mid 414.237105 -24.697412)
				(end 414.24098 -24.677878)
			)
			(arc
				(start 414.24098 -23.958042)
				(mid 414.237079 -23.938519)
				(end 414.225994 -23.921974)
			)
			(arc
				(start 414.128966 -23.824946)
				(mid 414.112432 -23.813835)
				(end 414.092898 -23.80996)
			)
			(arc
				(start 412.890462 -23.80996)
				(mid 412.870939 -23.813861)
				(end 412.854394 -23.824946)
			)
			(arc
				(start 412.401766 -24.277574)
				(mid 412.390655 -24.294108)
				(end 412.38678 -24.313642)
			)
			(arc
				(start 412.38678 -27.624278)
				(mid 412.390681 -27.643801)
				(end 412.401766 -27.660346)
			)
			(arc
				(start 412.422594 -27.681174)
				(mid 412.439128 -27.692285)
				(end 412.458662 -27.69616)
			)
		)
		(stroke
			(width 0)
			(type solid)
		)
		(fill yes)
		(layer "F.Cu")
		(net "P12V_HPDB")
	)
	(gr_poly
		(pts
			(xy 303.969166 -66.760852) (xy 303.969166 -64.04483) (xy 303.572672 -63.648336) (xy 303.572672 -63.123318)
			(xy 303.96942 -62.72657) (xy 303.96942 -44.48302) (xy 301.7774 -42.291) (xy 301.752 -42.291) (xy 298.631864 -39.170864)
			(xy 298.631864 -33.31337) (xy 298.984162 -32.961072) (xy 303.936146 -32.961072) (xy 303.969166 -32.928052)
			(xy 303.969166 -30.21203) (xy 303.572672 -29.815536) (xy 303.572672 -29.290518) (xy 303.96942 -28.89377)
			(xy 303.96942 -14.5034) (xy 303.94402 -14.478) (xy 281.946096 -14.478) (xy 279.7556 -16.668496) (xy 279.7556 -27.142186)
			(xy 277.676356 -29.22143) (xy 277.128478 -29.22143)
			(arc
				(start 230.533956 -29.22143)
				(mid 230.514433 -29.225331)
				(end 230.497888 -29.236416)
			)
			(arc
				(start 230.011986 -29.722318)
				(mid 230.000875 -29.738852)
				(end 229.997 -29.758386)
			)
			(arc
				(start 229.997 -46.841918)
				(mid 230.000901 -46.861441)
				(end 230.011986 -46.877986)
			)
			(xy 230.251 -47.117) (xy 242.9764 -47.117) (xy 248.777252 -41.316148) (xy 256.149348 -41.316148)
			(xy 258.9022 -44.069) (xy 268.4018 -44.069) (xy 282.4861 -58.1533) (xy 293.6621 -58.1533) (xy 298.232322 -62.723522)
			(xy 298.232322 -66.410078) (xy 298.616116 -66.793872) (xy 303.936146 -66.793872)
		)
		(stroke
			(width 0)
			(type solid)
		)
		(fill yes)
		(layer "F.Cu")
		(net "P52V_1")
	)
	(gr_poly
		(pts
			(arc
				(start 176.917858 -73.610216)
				(mid 176.937381 -73.606315)
				(end 176.953926 -73.59523)
			)
			(arc
				(start 177.254408 -73.294748)
				(mid 177.265519 -73.278214)
				(end 177.269394 -73.25868)
			)
			(arc
				(start 177.269394 -68.818506)
				(mid 177.273295 -68.798983)
				(end 177.28438 -68.782438)
			)
			(xy 178.473862 -67.592956) (xy 178.473862 -62.47638)
			(arc
				(start 178.260248 -62.262766)
				(mid 178.243714 -62.251655)
				(end 178.22418 -62.24778)
			)
			(xy 177.549302 -62.24778) (xy 177.315368 -62.24778) (xy 177.14976 -62.413388) (xy 177.14976 -63.364872)
			(xy 176.99228 -63.522352)
			(arc
				(start 176.416462 -63.522352)
				(mid 176.396939 -63.526253)
				(end 176.380394 -63.537338)
			)
			(arc
				(start 176.292002 -63.62573)
				(mid 176.280891 -63.642264)
				(end 176.277016 -63.661798)
			)
			(arc
				(start 176.277016 -66.659252)
				(mid 176.273115 -66.678775)
				(end 176.26203 -66.69532)
			)
			(arc
				(start 175.944784 -67.012566)
				(mid 175.92825 -67.023677)
				(end 175.908716 -67.027552)
			)
			(arc
				(start 174.379636 -67.027552)
				(mid 174.360113 -67.031453)
				(end 174.343568 -67.042538)
			)
			(arc
				(start 174.092362 -67.293744)
				(mid 174.081251 -67.310278)
				(end 174.077376 -67.329812)
			)
			(arc
				(start 174.077376 -73.35774)
				(mid 174.081277 -73.377263)
				(end 174.092362 -73.393808)
			)
			(arc
				(start 174.293784 -73.59523)
				(mid 174.310318 -73.606341)
				(end 174.329852 -73.610216)
			)
		)
		(stroke
			(width 0)
			(type solid)
		)
		(fill yes)
		(layer "F.Cu")
		(net "GND1_FIELD_SIGNAL")
	)
	(gr_poly
		(pts
			(arc
				(start 45.563028 -29.560266)
				(mid 45.597752 -29.546638)
				(end 45.613828 -29.513022)
			)
			(xy 45.613828 -27.407616)
			(arc
				(start 47.327312 -27.407616)
				(mid 47.360847 -27.391465)
				(end 47.374556 -27.356816)
			)
			(xy 47.374556 -27.324812) (xy 47.368206 -27.308048)
			(arc
				(start 47.36211 -27.300936)
				(mid 47.268914 -27.051)
				(end 47.36211 -26.801064)
			)
			(xy 47.374556 -26.76779)
			(arc
				(start 47.374556 -17.160494)
				(mid 47.370655 -17.140971)
				(end 47.35957 -17.124426)
			)
			(arc
				(start 46.98619 -16.751046)
				(mid 46.969656 -16.739935)
				(end 46.950122 -16.73606)
			)
			(arc
				(start 43.806364 -16.73606)
				(mid 43.786841 -16.739961)
				(end 43.770296 -16.751046)
			)
			(arc
				(start 43.699684 -16.821658)
				(mid 43.688573 -16.838192)
				(end 43.684698 -16.857726)
			)
			(arc
				(start 43.684698 -27.356816)
				(mid 43.698326 -27.39154)
				(end 43.731942 -27.407616)
			)
			(xy 44.192952 -27.407616)
			(arc
				(start 44.192952 -29.513022)
				(mid 44.209103 -29.546557)
				(end 44.243752 -29.560266)
			)
		)
		(stroke
			(width 0)
			(type solid)
		)
		(fill yes)
		(layer "F.Cu")
		(net "P52V_HS2_EN_DISCHARGE_VBE_R")
	)
	(gr_poly
		(pts
			(xy 148.673312 -66.573654) (xy 149.460966 -65.786) (xy 149.460966 -60.403994) (xy 150.09876 -59.7662)
			(xy 150.1648 -59.7662) (xy 152.9842 -59.7662) (xy 156.3116 -56.4388) (xy 158.75635 -56.4388) (xy 160.349438 -54.845712)
			(xy 170.757088 -54.845712) (xy 174.879 -54.845712) (xy 175.0314 -54.693312) (xy 175.0314 -53.8226)
			(xy 173.4058 -52.197) (xy 171.4246 -52.197) (xy 169.741088 -50.513488) (xy 169.741088 -45.117512)
			(xy 173.542452 -41.316148) (xy 192.0113 -41.316148) (xy 197.862952 -47.1678) (xy 209.698336 -47.1678)
			(arc
				(start 209.98815 -46.877986)
				(mid 209.999261 -46.861452)
				(end 210.003136 -46.841918)
			)
			(xy 210.003136 -30.415484) (xy 209.995516 -30.407864)
			(arc
				(start 209.995516 -30.311598)
				(mid 209.991615 -30.292075)
				(end 209.98053 -30.27553)
			)
			(xy 208.92643 -29.22143) (xy 161.90595 -29.22143) (xy 159.9184 -27.23388) (xy 159.9184 -16.2306)
			(xy 158.4198 -14.732) (xy 144.0942 -14.732) (xy 143.650716 -15.175484) (xy 143.650716 -28.89377)
			(xy 144.047464 -29.290518) (xy 144.047464 -29.815536) (xy 143.65097 -30.21203) (xy 143.65097 -32.928052)
			(xy 143.68399 -32.961072) (xy 147.896072 -32.961072) (xy 148.344636 -33.409636) (xy 148.344636 -38.616636)
			(xy 146.448272 -40.513) (xy 145.2118 -40.513) (xy 143.637 -42.0878) (xy 143.637 -46.863) (xy 143.650716 -46.863)
			(xy 143.650716 -62.72657) (xy 144.047464 -63.123318) (xy 144.047464 -63.648336) (xy 143.65097 -64.04483)
			(xy 143.65097 -66.760852) (xy 143.68399 -66.793872) (xy 148.453094 -66.793872)
		)
		(stroke
			(width 0)
			(type solid)
		)
		(fill yes)
		(layer "F.Cu")
		(net "P52V_2")
	)
	(gr_poly
		(pts
			(xy 391.88644 -169.87266) (xy 391.896506 -169.872228) (xy 391.915096 -169.864499) (xy 391.922508 -169.857674)
			(xy 392.292332 -169.48785) (xy 392.299178 -169.480452) (xy 392.306905 -169.461853) (xy 392.307318 -169.451782)
			(xy 392.307318 -164.263578) (xy 392.306891 -164.253509) (xy 392.299173 -164.234909) (xy 392.292332 -164.22751)
			(xy 391.858246 -163.793424) (xy 391.850846 -163.786584) (xy 391.832247 -163.778865) (xy 391.822178 -163.778438)
			(xy 387.392164 -163.778438) (xy 387.388862 -163.778946) (xy 387.34183 -163.784701) (xy 387.247267 -163.790842)
			(xy 387.152505 -163.790842) (xy 387.057942 -163.784701) (xy 387.01091 -163.778946) (xy 387.007608 -163.778438)
			(xy 362.849922 -163.778438) (xy 362.839859 -163.778876) (xy 362.821279 -163.786615) (xy 362.813854 -163.793424)
			(xy 362.332016 -164.275262) (xy 362.325178 -164.282663) (xy 362.317463 -164.301262) (xy 362.31703 -164.31133)
			(xy 362.31703 -167.684408) (xy 365.513862 -167.684408) (xy 365.513862 -167.57578) (xy 365.521791 -167.467442)
			(xy 365.537608 -167.359971) (xy 365.561227 -167.253942) (xy 365.592523 -167.14992) (xy 365.631328 -167.048459)
			(xy 365.677436 -166.950102) (xy 365.7306 -166.855373) (xy 365.790538 -166.764778) (xy 365.856928 -166.678799)
			(xy 365.929418 -166.597896) (xy 366.007619 -166.5225) (xy 366.091116 -166.453014) (xy 366.179462 -166.389807)
			(xy 366.272186 -166.333219) (xy 366.368794 -166.283549) (xy 366.468769 -166.241064) (xy 366.571579 -166.205991)
			(xy 366.676675 -166.178515) (xy 366.783496 -166.158784) (xy 366.891472 -166.146903) (xy 367.000028 -166.142936)
			(xy 367.108584 -166.146903) (xy 367.21656 -166.158784) (xy 367.323381 -166.178515) (xy 367.428477 -166.205991)
			(xy 367.531287 -166.241064) (xy 367.631262 -166.283549) (xy 367.72787 -166.333219) (xy 367.820594 -166.389807)
			(xy 367.90894 -166.453014) (xy 367.992437 -166.5225) (xy 368.070638 -166.597896) (xy 368.143128 -166.678799)
			(xy 368.209518 -166.764778) (xy 368.269456 -166.855373) (xy 368.32262 -166.950102) (xy 368.368728 -167.048459)
			(xy 368.407533 -167.14992) (xy 368.438829 -167.253942) (xy 368.462448 -167.359971) (xy 368.478265 -167.467442)
			(xy 368.486194 -167.57578) (xy 368.48669 -167.630094) (xy 368.486194 -167.684408) (xy 368.478265 -167.792746)
			(xy 368.462448 -167.900217) (xy 368.438829 -168.006246) (xy 368.407533 -168.110268) (xy 368.368728 -168.211729)
			(xy 368.32262 -168.310086) (xy 368.269456 -168.404815) (xy 368.209518 -168.49541) (xy 368.143128 -168.581389)
			(xy 368.070638 -168.662292) (xy 367.992437 -168.737688) (xy 367.90894 -168.807174) (xy 367.820594 -168.870381)
			(xy 367.72787 -168.926969) (xy 367.631262 -168.976639) (xy 367.531287 -169.019124) (xy 367.428477 -169.054197)
			(xy 367.323381 -169.081673) (xy 367.21656 -169.101404) (xy 367.108584 -169.113285) (xy 367.000028 -169.117252)
			(xy 366.891472 -169.113285) (xy 366.783496 -169.101404) (xy 366.676675 -169.081673) (xy 366.571579 -169.054197)
			(xy 366.468769 -169.019124) (xy 366.368794 -168.976639) (xy 366.272186 -168.926969) (xy 366.179462 -168.870381)
			(xy 366.091116 -168.807174) (xy 366.007619 -168.737688) (xy 365.929418 -168.662292) (xy 365.856928 -168.581389)
			(xy 365.790538 -168.49541) (xy 365.7306 -168.404815) (xy 365.677436 -168.310086) (xy 365.631328 -168.211729)
			(xy 365.592523 -168.110268) (xy 365.561227 -168.006246) (xy 365.537608 -167.900217) (xy 365.521791 -167.792746)
			(xy 365.513862 -167.684408) (xy 362.31703 -167.684408) (xy 362.31703 -169.364152) (xy 362.317463 -169.374217)
			(xy 362.325194 -169.392805) (xy 362.332016 -169.40022) (xy 362.78947 -169.857674) (xy 362.796871 -169.864512)
			(xy 362.81547 -169.872225) (xy 362.825538 -169.87266)
		)
		(stroke
			(width 0)
			(type solid)
		)
		(fill yes)
		(layer "F.Cu")
		(net "GND")
	)
	(gr_poly
		(pts
			(xy 77.249782 -169.49928) (xy 77.259845 -169.498841) (xy 77.278426 -169.491104) (xy 77.28585 -169.484294)
			(xy 77.639672 -169.130472) (xy 77.646517 -169.123073) (xy 77.654246 -169.104475) (xy 77.654658 -169.094404)
			(xy 77.654658 -164.60978) (xy 77.65423 -164.599712) (xy 77.646506 -164.581117) (xy 77.639672 -164.573712)
			(xy 77.333602 -164.267642) (xy 77.326206 -164.260791) (xy 77.307607 -164.253049) (xy 77.297534 -164.252656)
			(xy 42.630852 -164.252656) (xy 42.620787 -164.252223) (xy 42.602199 -164.244491) (xy 42.594784 -164.23767)
			(xy 42.22496 -163.867846) (xy 42.218115 -163.860448) (xy 42.210391 -163.841849) (xy 42.209974 -163.831778)
			(xy 42.209974 -152.53335) (xy 42.209541 -152.523284) (xy 42.201811 -152.504696) (xy 42.194988 -152.497282)
			(xy 41.937178 -152.239472) (xy 41.929782 -152.232621) (xy 41.911183 -152.224883) (xy 41.90111 -152.224486)
			(xy 39.45382 -152.224486) (xy 39.435278 -152.232106) (xy 39.429436 -152.237948) (xy 39.429436 -167.684408)
			(xy 65.513954 -167.684408) (xy 65.513954 -167.57578) (xy 65.521883 -167.467442) (xy 65.5377 -167.359971)
			(xy 65.561319 -167.253942) (xy 65.592615 -167.14992) (xy 65.63142 -167.048459) (xy 65.677528 -166.950102)
			(xy 65.730692 -166.855373) (xy 65.79063 -166.764778) (xy 65.85702 -166.678799) (xy 65.92951 -166.597896)
			(xy 66.007711 -166.5225) (xy 66.091208 -166.453014) (xy 66.179554 -166.389807) (xy 66.272278 -166.333219)
			(xy 66.368886 -166.283549) (xy 66.468861 -166.241064) (xy 66.571671 -166.205991) (xy 66.676767 -166.178515)
			(xy 66.783588 -166.158784) (xy 66.891564 -166.146903) (xy 67.00012 -166.142936) (xy 67.108676 -166.146903)
			(xy 67.216652 -166.158784) (xy 67.323473 -166.178515) (xy 67.428569 -166.205991) (xy 67.531379 -166.241064)
			(xy 67.631354 -166.283549) (xy 67.727962 -166.333219) (xy 67.820686 -166.389807) (xy 67.909032 -166.453014)
			(xy 67.992529 -166.5225) (xy 68.07073 -166.597896) (xy 68.14322 -166.678799) (xy 68.20961 -166.764778)
			(xy 68.269548 -166.855373) (xy 68.322712 -166.950102) (xy 68.36882 -167.048459) (xy 68.407625 -167.14992)
			(xy 68.438921 -167.253942) (xy 68.46254 -167.359971) (xy 68.478357 -167.467442) (xy 68.486286 -167.57578)
			(xy 68.486782 -167.630094) (xy 68.486286 -167.684408) (xy 68.478357 -167.792746) (xy 68.46254 -167.900217)
			(xy 68.438921 -168.006246) (xy 68.407625 -168.110268) (xy 68.36882 -168.211729) (xy 68.322712 -168.310086)
			(xy 68.269548 -168.404815) (xy 68.20961 -168.49541) (xy 68.14322 -168.581389) (xy 68.07073 -168.662292)
			(xy 67.992529 -168.737688) (xy 67.909032 -168.807174) (xy 67.820686 -168.870381) (xy 67.727962 -168.926969)
			(xy 67.631354 -168.976639) (xy 67.531379 -169.019124) (xy 67.428569 -169.054197) (xy 67.323473 -169.081673)
			(xy 67.216652 -169.101404) (xy 67.108676 -169.113285) (xy 67.00012 -169.117252) (xy 66.891564 -169.113285)
			(xy 66.783588 -169.101404) (xy 66.676767 -169.081673) (xy 66.571671 -169.054197) (xy 66.468861 -169.019124)
			(xy 66.368886 -168.976639) (xy 66.272278 -168.926969) (xy 66.179554 -168.870381) (xy 66.091208 -168.807174)
			(xy 66.007711 -168.737688) (xy 65.92951 -168.662292) (xy 65.85702 -168.581389) (xy 65.79063 -168.49541)
			(xy 65.730692 -168.404815) (xy 65.677528 -168.310086) (xy 65.63142 -168.211729) (xy 65.592615 -168.110268)
			(xy 65.561319 -168.006246) (xy 65.5377 -167.900217) (xy 65.521883 -167.792746) (xy 65.513954 -167.684408)
			(xy 39.429436 -167.684408) (xy 39.429436 -169.44848) (xy 39.429853 -169.458501) (xy 39.43752 -169.477019)
			(xy 39.451695 -169.491189) (xy 39.470215 -169.49885) (xy 39.480236 -169.49928)
		)
		(stroke
			(width 0)
			(type solid)
		)
		(fill yes)
		(layer "F.Cu")
		(net "GND")
	)
	(gr_poly
		(pts
			(xy 216.949528 -7.298944)
			(arc
				(start 216.95156 -7.279132)
				(mid 217.614859 -5.925703)
				(end 219.001848 -5.335778)
			)
			(arc
				(start 219.001848 -5.335778)
				(mid 219.01556 -5.333175)
				(end 219.02801 -5.326888)
			)
			(arc
				(start 219.02801 -5.326888)
				(mid 219.607393 -5.048195)
				(end 220.243146 -4.952492)
			)
			(arc
				(start 220.2434 -4.952492)
				(mid 220.867575 -5.04474)
				(end 221.43847 -5.313426)
			)
			(arc
				(start 221.43847 -5.313426)
				(mid 221.453672 -5.320099)
				(end 221.47022 -5.321554)
			)
			(arc
				(start 221.47022 -5.321554)
				(mid 221.546754 -5.31753)
				(end 221.623382 -5.31622)
			)
			(arc
				(start 221.623382 -5.31622)
				(mid 223.079128 -5.880649)
				(end 223.774 -7.278878)
			)
			(xy 223.775778 -7.29869) (xy 223.80448 -7.324852)
			(arc
				(start 361.476036 -7.324852)
				(mid 361.495393 -7.321019)
				(end 361.51185 -7.31012)
			)
			(arc
				(start 361.810554 -7.011416)
				(mid 361.821665 -6.994882)
				(end 361.82554 -6.975348)
			)
			(arc
				(start 361.82554 -3.894582)
				(mid 361.829441 -3.875059)
				(end 361.840526 -3.858514)
			)
			(xy 361.861608 -3.837432) (xy 361.869228 -3.820922)
			(arc
				(start 361.869736 -3.811778)
				(mid 363.158768 -2.277577)
				(end 365.022892 -3.012948)
			)
			(arc
				(start 365.022892 -3.012948)
				(mid 365.051326 -3.034095)
				(end 365.086646 -3.03149)
			)
			(arc
				(start 365.086646 -3.03149)
				(mid 365.591166 -2.863343)
				(end 366.119918 -2.806446)
			)
			(arc
				(start 366.119918 -2.806446)
				(mid 366.764286 -2.891424)
				(end 367.364518 -3.14071)
			)
			(arc
				(start 367.364518 -3.14071)
				(mid 367.389918 -3.147523)
				(end 367.415318 -3.14071)
			)
			(arc
				(start 367.415318 -3.14071)
				(mid 368.01544 -2.891502)
				(end 368.659664 -2.806446)
			)
			(arc
				(start 368.659918 -2.806446)
				(mid 368.912694 -2.819395)
				(end 369.162838 -2.858008)
			)
			(xy 369.174268 -2.860294) (xy 369.196112 -2.85496)
			(arc
				(start 369.266216 -2.79781)
				(mid 369.280027 -2.78024)
				(end 369.285012 -2.75844)
			)
			(arc
				(start 369.285012 -1.221994)
				(mid 369.281111 -1.202471)
				(end 369.270026 -1.185926)
			)
			(arc
				(start 369.047776 -0.963676)
				(mid 369.031242 -0.952565)
				(end 369.011708 -0.94869)
			)
			(arc
				(start 82.407252 -0.94869)
				(mid 82.387729 -0.952591)
				(end 82.371184 -0.963676)
			)
			(arc
				(start 81.897474 -1.437386)
				(mid 81.886363 -1.45392)
				(end 81.882488 -1.473454)
			)
			(arc
				(start 81.882488 -6.896608)
				(mid 81.886389 -6.916131)
				(end 81.897474 -6.932676)
			)
			(xy 82.203798 -7.239) (xy 90.5002 -7.239) (xy 90.586052 -7.324852) (xy 216.920826 -7.324852)
		)
		(stroke
			(width 0)
			(type solid)
		)
		(fill yes)
		(layer "F.Cu")
		(net "P52V_FAN")
	)
	(gr_poly
		(pts
			(arc
				(start 32.015684 -163.299902)
				(mid 30.253716 -159.046134)
				(end 25.999948 -157.284166)
			)
			(arc
				(start 4.99999 -157.284166)
				(mid 2.182704 -156.117208)
				(end 1.015746 -153.299922)
			)
			(arc
				(start 1.015746 -4.99999)
				(mid 2.182704 -2.182704)
				(end 4.99999 -1.015746)
			)
			(xy 57.5564 -1.015746) (xy 57.5564 -0.508)
			(arc
				(start 4.99999 -0.508)
				(mid 1.823673 -1.823673)
				(end 0.508 -4.99999)
			)
			(arc
				(start 0.508 -153.299922)
				(mid 1.823673 -156.476239)
				(end 4.99999 -157.791912)
			)
			(arc
				(start 25.999948 -157.791912)
				(mid 29.894685 -159.405165)
				(end 31.507938 -163.299902)
			)
			(xy 31.507938 -164.206428) (xy 32.015684 -164.206428)
		)
		(stroke
			(width 0)
			(type solid)
		)
		(fill yes)
		(layer "F.Cu")
		(net "GND")
	)
	(gr_poly
		(pts
			(xy 20.00377 -104.544876) (xy 20.003269 -104.444746) (xy 19.995257 -104.244646) (xy 19.979245 -104.045027)
			(xy 19.955259 -103.846208) (xy 19.923338 -103.648509) (xy 19.883533 -103.452244) (xy 19.835907 -103.25773)
			(xy 19.780536 -103.065276) (xy 19.71751 -102.875193) (xy 19.64693 -102.687783) (xy 19.568907 -102.503347)
			(xy 19.483568 -102.32218) (xy 19.391049 -102.144573) (xy 19.291498 -101.970809) (xy 19.185074 -101.801168)
			(xy 19.071948 -101.63592) (xy 18.952302 -101.475331) (xy 18.826326 -101.319658) (xy 18.694222 -101.169149)
			(xy 18.556203 -101.024047) (xy 18.412488 -100.884583) (xy 18.263309 -100.75098) (xy 18.108904 -100.623453)
			(xy 17.94952 -100.502205) (xy 17.785412 -100.387432) (xy 17.616844 -100.279317) (xy 17.444086 -100.178032)
			(xy 17.267413 -100.08374) (xy 17.087109 -99.996593) (xy 16.903463 -99.916729) (xy 16.716768 -99.844277)
			(xy 16.527325 -99.779352) (xy 16.335435 -99.722059) (xy 16.141407 -99.672489) (xy 15.94555 -99.630722)
			(xy 15.74818 -99.596825) (xy 15.549611 -99.570851) (xy 15.350162 -99.552843) (xy 15.150153 -99.542829)
			(xy 14.949902 -99.540825) (xy 14.749732 -99.546835) (xy 14.549963 -99.560849) (xy 14.350915 -99.582845)
			(xy 14.152905 -99.612786) (xy 13.956253 -99.650626) (xy 13.761271 -99.696304) (xy 13.568274 -99.749746)
			(xy 13.377569 -99.810867) (xy 13.189462 -99.879569) (xy 13.004255 -99.955742) (xy 12.822243 -100.039265)
			(xy 12.643719 -100.130002) (xy 12.468968 -100.22781) (xy 12.298271 -100.332531) (xy 12.1319 -100.443998)
			(xy 11.970122 -100.562032) (xy 11.813196 -100.686444) (xy 11.661373 -100.817035) (xy 11.514897 -100.953596)
			(xy 11.374002 -101.095908) (xy 11.238913 -101.243743) (xy 11.109848 -101.396865) (xy 10.987012 -101.555027)
			(xy 10.870602 -101.717978) (xy 10.760806 -101.885456) (xy 10.657798 -102.057193) (xy 10.561743 -102.232913)
			(xy 10.472796 -102.412336) (xy 10.391099 -102.595174) (xy 10.316783 -102.781135) (xy 10.249966 -102.969919)
			(xy 10.190756 -103.161226) (xy 10.139247 -103.354749) (xy 10.095523 -103.550177) (xy 10.059652 -103.747199)
			(xy 10.031693 -103.945498) (xy 10.01169 -104.144756) (xy 9.999676 -104.344656) (xy 9.995669 -104.544876)
			(xy 12.482326 -104.544876) (xy 12.486358 -104.40244) (xy 12.498442 -104.260461) (xy 12.51854 -104.119392)
			(xy 12.546586 -103.979686) (xy 12.582491 -103.841791) (xy 12.62614 -103.706148) (xy 12.677393 -103.573192)
			(xy 12.736086 -103.443349) (xy 12.802031 -103.317034) (xy 12.875016 -103.194652) (xy 12.954809 -103.076595)
			(xy 13.041153 -102.963241) (xy 13.133771 -102.854954) (xy 13.232367 -102.752081) (xy 13.336626 -102.65495)
			(xy 13.446213 -102.563873) (xy 13.560777 -102.479142) (xy 13.679951 -102.401028) (xy 13.803353 -102.329782)
			(xy 13.930589 -102.265631) (xy 14.06125 -102.208781) (xy 14.194918 -102.159415) (xy 14.331165 -102.11769)
			(xy 14.469554 -102.083739) (xy 14.609643 -102.057673) (xy 14.750982 -102.039574) (xy 14.893118 -102.0295)
			(xy 15.035597 -102.027484) (xy 15.177961 -102.033531) (xy 15.319756 -102.047623) (xy 15.460526 -102.069715)
			(xy 15.59982 -102.099735) (xy 15.737194 -102.137588) (xy 15.872205 -102.183152) (xy 16.004423 -102.236282)
			(xy 16.133423 -102.296806) (xy 16.258792 -102.364532) (xy 16.380129 -102.439242) (xy 16.497045 -102.520697)
			(xy 16.609165 -102.608636) (xy 16.716131 -102.702778) (xy 16.817599 -102.80282) (xy 16.913244 -102.908443)
			(xy 17.002761 -103.019307) (xy 17.085863 -103.135059) (xy 17.162282 -103.255326) (xy 17.231775 -103.379724)
			(xy 17.294119 -103.507855) (xy 17.349114 -103.639308) (xy 17.396585 -103.773661) (xy 17.436378 -103.910485)
			(xy 17.468366 -104.049341) (xy 17.492447 -104.189784) (xy 17.508545 -104.331365) (xy 17.516606 -104.47363)
			(xy 17.51711 -104.544876) (xy 17.516606 -104.616122) (xy 17.508545 -104.758387) (xy 17.492447 -104.899968)
			(xy 17.468366 -105.040411) (xy 17.436378 -105.179267) (xy 17.396585 -105.316091) (xy 17.349114 -105.450444)
			(xy 17.294119 -105.581897) (xy 17.231775 -105.710028) (xy 17.162282 -105.834426) (xy 17.085863 -105.954693)
			(xy 17.002761 -106.070445) (xy 16.913244 -106.181309) (xy 16.817599 -106.286932) (xy 16.716131 -106.386974)
			(xy 16.609165 -106.481116) (xy 16.497045 -106.569055) (xy 16.380129 -106.65051) (xy 16.258792 -106.72522)
			(xy 16.133423 -106.792946) (xy 16.004423 -106.85347) (xy 15.872205 -106.9066) (xy 15.737194 -106.952164)
			(xy 15.59982 -106.990017) (xy 15.460526 -107.020037) (xy 15.319756 -107.042129) (xy 15.177961 -107.056221)
			(xy 15.035597 -107.062268) (xy 14.893118 -107.060252) (xy 14.750982 -107.050178) (xy 14.609643 -107.032079)
			(xy 14.469554 -107.006013) (xy 14.331165 -106.972062) (xy 14.194918 -106.930337) (xy 14.06125 -106.880971)
			(xy 13.930589 -106.824121) (xy 13.803353 -106.75997) (xy 13.679951 -106.688724) (xy 13.560777 -106.61061)
			(xy 13.446213 -106.525879) (xy 13.336626 -106.434802) (xy 13.232367 -106.337671) (xy 13.133771 -106.234798)
			(xy 13.041153 -106.126511) (xy 12.954809 -106.013157) (xy 12.875016 -105.8951) (xy 12.802031 -105.772718)
			(xy 12.736086 -105.646403) (xy 12.677393 -105.51656) (xy 12.62614 -105.383604) (xy 12.582491 -105.247961)
			(xy 12.546586 -105.110066) (xy 12.51854 -104.97036) (xy 12.498442 -104.829291) (xy 12.486358 -104.687312)
			(xy 12.482326 -104.544876) (xy 9.995669 -104.544876) (xy 9.999676 -104.745096) (xy 10.01169 -104.944996)
			(xy 10.031693 -105.144254) (xy 10.059652 -105.342553) (xy 10.095523 -105.539575) (xy 10.139247 -105.735003)
			(xy 10.190756 -105.928526) (xy 10.249966 -106.119833) (xy 10.316783 -106.308617) (xy 10.391099 -106.494578)
			(xy 10.472796 -106.677416) (xy 10.561743 -106.856839) (xy 10.657798 -107.032559) (xy 10.760806 -107.204296)
			(xy 10.870602 -107.371774) (xy 10.987012 -107.534725) (xy 11.109848 -107.692887) (xy 11.238913 -107.846009)
			(xy 11.374002 -107.993844) (xy 11.514897 -108.136156) (xy 11.661373 -108.272717) (xy 11.813196 -108.403308)
			(xy 11.970122 -108.52772) (xy 12.1319 -108.645754) (xy 12.298271 -108.757221) (xy 12.468968 -108.861942)
			(xy 12.643719 -108.95975) (xy 12.822243 -109.050487) (xy 13.004255 -109.13401) (xy 13.189462 -109.210183)
			(xy 13.377569 -109.278885) (xy 13.568274 -109.340006) (xy 13.761271 -109.393448) (xy 13.956253 -109.439126)
			(xy 14.152905 -109.476966) (xy 14.350915 -109.506907) (xy 14.549963 -109.528903) (xy 14.749732 -109.542917)
			(xy 14.949902 -109.548927) (xy 15.150153 -109.546923) (xy 15.350162 -109.536909) (xy 15.549611 -109.518901)
			(xy 15.74818 -109.492927) (xy 15.94555 -109.45903) (xy 16.141407 -109.417263) (xy 16.335435 -109.367693)
			(xy 16.527325 -109.3104) (xy 16.716768 -109.245475) (xy 16.903463 -109.173023) (xy 17.087109 -109.093159)
			(xy 17.267413 -109.006012) (xy 17.444086 -108.91172) (xy 17.616844 -108.810435) (xy 17.785412 -108.70232)
			(xy 17.94952 -108.587547) (xy 18.108904 -108.466299) (xy 18.263309 -108.338772) (xy 18.412488 -108.205169)
			(xy 18.556203 -108.065705) (xy 18.694222 -107.920603) (xy 18.826326 -107.770094) (xy 18.952302 -107.614421)
			(xy 19.071948 -107.453832) (xy 19.185074 -107.288584) (xy 19.291498 -107.118943) (xy 19.391049 -106.945179)
			(xy 19.483568 -106.767572) (xy 19.568907 -106.586405) (xy 19.64693 -106.401969) (xy 19.71751 -106.214559)
			(xy 19.780536 -106.024476) (xy 19.835907 -105.832022) (xy 19.883533 -105.637508) (xy 19.923338 -105.441243)
			(xy 19.955259 -105.243544) (xy 19.979245 -105.044725) (xy 19.995257 -104.845106) (xy 20.003269 -104.645006)
		)
		(stroke
			(width 0)
			(type solid)
		)
		(fill yes)
		(layer "F.Cu")
		(net "GND")
	)
	(gr_poly
		(pts
			(xy 20.00377 -60.099956) (xy 20.003269 -59.999826) (xy 19.995257 -59.799726) (xy 19.979245 -59.600107)
			(xy 19.955259 -59.401288) (xy 19.923338 -59.203589) (xy 19.883533 -59.007324) (xy 19.835907 -58.81281)
			(xy 19.780536 -58.620356) (xy 19.71751 -58.430273) (xy 19.64693 -58.242863) (xy 19.568907 -58.058427)
			(xy 19.483568 -57.87726) (xy 19.391049 -57.699653) (xy 19.291498 -57.525889) (xy 19.185074 -57.356248)
			(xy 19.071948 -57.191) (xy 18.952302 -57.030411) (xy 18.826326 -56.874738) (xy 18.694222 -56.724229)
			(xy 18.556203 -56.579127) (xy 18.412488 -56.439663) (xy 18.263309 -56.30606) (xy 18.108904 -56.178533)
			(xy 17.94952 -56.057285) (xy 17.785412 -55.942512) (xy 17.616844 -55.834397) (xy 17.444086 -55.733112)
			(xy 17.267413 -55.63882) (xy 17.087109 -55.551673) (xy 16.903463 -55.471809) (xy 16.716768 -55.399357)
			(xy 16.527325 -55.334432) (xy 16.335435 -55.277139) (xy 16.141407 -55.227569) (xy 15.94555 -55.185802)
			(xy 15.74818 -55.151905) (xy 15.549611 -55.125931) (xy 15.350162 -55.107923) (xy 15.150153 -55.097909)
			(xy 14.949902 -55.095905) (xy 14.749732 -55.101915) (xy 14.549963 -55.115929) (xy 14.350915 -55.137925)
			(xy 14.152905 -55.167866) (xy 13.956253 -55.205706) (xy 13.761271 -55.251384) (xy 13.568274 -55.304826)
			(xy 13.377569 -55.365947) (xy 13.189462 -55.434649) (xy 13.004255 -55.510822) (xy 12.822243 -55.594345)
			(xy 12.643719 -55.685082) (xy 12.468968 -55.78289) (xy 12.298271 -55.887611) (xy 12.1319 -55.999078)
			(xy 11.970122 -56.117112) (xy 11.813196 -56.241524) (xy 11.661373 -56.372115) (xy 11.514897 -56.508676)
			(xy 11.374002 -56.650988) (xy 11.238913 -56.798823) (xy 11.109848 -56.951945) (xy 10.987012 -57.110107)
			(xy 10.870602 -57.273058) (xy 10.760806 -57.440536) (xy 10.657798 -57.612273) (xy 10.561743 -57.787993)
			(xy 10.472796 -57.967416) (xy 10.391099 -58.150254) (xy 10.316783 -58.336215) (xy 10.249966 -58.524999)
			(xy 10.190756 -58.716306) (xy 10.139247 -58.909829) (xy 10.095523 -59.105257) (xy 10.059652 -59.302279)
			(xy 10.031693 -59.500578) (xy 10.01169 -59.699836) (xy 9.999676 -59.899736) (xy 9.995669 -60.099956)
			(xy 12.482326 -60.099956) (xy 12.486358 -59.95752) (xy 12.498442 -59.815541) (xy 12.51854 -59.674472)
			(xy 12.546586 -59.534766) (xy 12.582491 -59.396871) (xy 12.62614 -59.261228) (xy 12.677393 -59.128272)
			(xy 12.736086 -58.998429) (xy 12.802031 -58.872114) (xy 12.875016 -58.749732) (xy 12.954809 -58.631675)
			(xy 13.041153 -58.518321) (xy 13.133771 -58.410034) (xy 13.232367 -58.307161) (xy 13.336626 -58.21003)
			(xy 13.446213 -58.118953) (xy 13.560777 -58.034222) (xy 13.679951 -57.956108) (xy 13.803353 -57.884862)
			(xy 13.930589 -57.820711) (xy 14.06125 -57.763861) (xy 14.194918 -57.714495) (xy 14.331165 -57.67277)
			(xy 14.469554 -57.638819) (xy 14.609643 -57.612753) (xy 14.750982 -57.594654) (xy 14.893118 -57.58458)
			(xy 15.035597 -57.582564) (xy 15.177961 -57.588611) (xy 15.319756 -57.602703) (xy 15.460526 -57.624795)
			(xy 15.59982 -57.654815) (xy 15.737194 -57.692668) (xy 15.872205 -57.738232) (xy 16.004423 -57.791362)
			(xy 16.133423 -57.851886) (xy 16.258792 -57.919612) (xy 16.380129 -57.994322) (xy 16.497045 -58.075777)
			(xy 16.609165 -58.163716) (xy 16.716131 -58.257858) (xy 16.817599 -58.3579) (xy 16.913244 -58.463523)
			(xy 17.002761 -58.574387) (xy 17.085863 -58.690139) (xy 17.162282 -58.810406) (xy 17.231775 -58.934804)
			(xy 17.294119 -59.062935) (xy 17.349114 -59.194388) (xy 17.396585 -59.328741) (xy 17.436378 -59.465565)
			(xy 17.468366 -59.604421) (xy 17.492447 -59.744864) (xy 17.508545 -59.886445) (xy 17.516606 -60.02871)
			(xy 17.51711 -60.099956) (xy 17.516606 -60.171202) (xy 17.508545 -60.313467) (xy 17.492447 -60.455048)
			(xy 17.468366 -60.595491) (xy 17.436378 -60.734347) (xy 17.396585 -60.871171) (xy 17.349114 -61.005524)
			(xy 17.294119 -61.136977) (xy 17.231775 -61.265108) (xy 17.162282 -61.389506) (xy 17.085863 -61.509773)
			(xy 17.002761 -61.625525) (xy 16.913244 -61.736389) (xy 16.817599 -61.842012) (xy 16.716131 -61.942054)
			(xy 16.609165 -62.036196) (xy 16.497045 -62.124135) (xy 16.380129 -62.20559) (xy 16.258792 -62.2803)
			(xy 16.133423 -62.348026) (xy 16.004423 -62.40855) (xy 15.872205 -62.46168) (xy 15.737194 -62.507244)
			(xy 15.59982 -62.545097) (xy 15.460526 -62.575117) (xy 15.319756 -62.597209) (xy 15.177961 -62.611301)
			(xy 15.035597 -62.617348) (xy 14.893118 -62.615332) (xy 14.750982 -62.605258) (xy 14.609643 -62.587159)
			(xy 14.469554 -62.561093) (xy 14.331165 -62.527142) (xy 14.194918 -62.485417) (xy 14.06125 -62.436051)
			(xy 13.930589 -62.379201) (xy 13.803353 -62.31505) (xy 13.679951 -62.243804) (xy 13.560777 -62.16569)
			(xy 13.446213 -62.080959) (xy 13.336626 -61.989882) (xy 13.232367 -61.892751) (xy 13.133771 -61.789878)
			(xy 13.041153 -61.681591) (xy 12.954809 -61.568237) (xy 12.875016 -61.45018) (xy 12.802031 -61.327798)
			(xy 12.736086 -61.201483) (xy 12.677393 -61.07164) (xy 12.62614 -60.938684) (xy 12.582491 -60.803041)
			(xy 12.546586 -60.665146) (xy 12.51854 -60.52544) (xy 12.498442 -60.384371) (xy 12.486358 -60.242392)
			(xy 12.482326 -60.099956) (xy 9.995669 -60.099956) (xy 9.999676 -60.300176) (xy 10.01169 -60.500076)
			(xy 10.031693 -60.699334) (xy 10.059652 -60.897633) (xy 10.095523 -61.094655) (xy 10.139247 -61.290083)
			(xy 10.190756 -61.483606) (xy 10.249966 -61.674913) (xy 10.316783 -61.863697) (xy 10.391099 -62.049658)
			(xy 10.472796 -62.232496) (xy 10.561743 -62.411919) (xy 10.657798 -62.587639) (xy 10.760806 -62.759376)
			(xy 10.870602 -62.926854) (xy 10.987012 -63.089805) (xy 11.109848 -63.247967) (xy 11.238913 -63.401089)
			(xy 11.374002 -63.548924) (xy 11.514897 -63.691236) (xy 11.661373 -63.827797) (xy 11.813196 -63.958388)
			(xy 11.970122 -64.0828) (xy 12.1319 -64.200834) (xy 12.298271 -64.312301) (xy 12.468968 -64.417022)
			(xy 12.643719 -64.51483) (xy 12.822243 -64.605567) (xy 13.004255 -64.68909) (xy 13.189462 -64.765263)
			(xy 13.377569 -64.833965) (xy 13.568274 -64.895086) (xy 13.761271 -64.948528) (xy 13.956253 -64.994206)
			(xy 14.152905 -65.032046) (xy 14.350915 -65.061987) (xy 14.549963 -65.083983) (xy 14.749732 -65.097997)
			(xy 14.949902 -65.104007) (xy 15.150153 -65.102003) (xy 15.350162 -65.091989) (xy 15.549611 -65.073981)
			(xy 15.74818 -65.048007) (xy 15.94555 -65.01411) (xy 16.141407 -64.972343) (xy 16.335435 -64.922773)
			(xy 16.527325 -64.86548) (xy 16.716768 -64.800555) (xy 16.903463 -64.728103) (xy 17.087109 -64.648239)
			(xy 17.267413 -64.561092) (xy 17.444086 -64.4668) (xy 17.616844 -64.365515) (xy 17.785412 -64.2574)
			(xy 17.94952 -64.142627) (xy 18.108904 -64.021379) (xy 18.263309 -63.893852) (xy 18.412488 -63.760249)
			(xy 18.556203 -63.620785) (xy 18.694222 -63.475683) (xy 18.826326 -63.325174) (xy 18.952302 -63.169501)
			(xy 19.071948 -63.008912) (xy 19.185074 -62.843664) (xy 19.291498 -62.674023) (xy 19.391049 -62.500259)
			(xy 19.483568 -62.322652) (xy 19.568907 -62.141485) (xy 19.64693 -61.957049) (xy 19.71751 -61.769639)
			(xy 19.780536 -61.579556) (xy 19.835907 -61.387102) (xy 19.883533 -61.192588) (xy 19.923338 -60.996323)
			(xy 19.955259 -60.798624) (xy 19.979245 -60.599805) (xy 19.995257 -60.400186) (xy 20.003269 -60.200086)
		)
		(stroke
			(width 0)
			(type solid)
		)
		(fill yes)
		(layer "F.Cu")
		(net "GND")
	)
	(gr_poly
		(pts
			(xy 430.003712 -104.549956) (xy 430.003211 -104.449826) (xy 429.995199 -104.249726) (xy 429.979187 -104.050107)
			(xy 429.955201 -103.851288) (xy 429.92328 -103.653589) (xy 429.883475 -103.457324) (xy 429.835849 -103.26281)
			(xy 429.780478 -103.070356) (xy 429.717452 -102.880273) (xy 429.646872 -102.692863) (xy 429.568849 -102.508427)
			(xy 429.48351 -102.32726) (xy 429.390991 -102.149653) (xy 429.29144 -101.975889) (xy 429.185016 -101.806248)
			(xy 429.07189 -101.641) (xy 428.952244 -101.480411) (xy 428.826268 -101.324738) (xy 428.694164 -101.174229)
			(xy 428.556145 -101.029127) (xy 428.41243 -100.889663) (xy 428.263251 -100.75606) (xy 428.108846 -100.628533)
			(xy 427.949462 -100.507285) (xy 427.785354 -100.392512) (xy 427.616786 -100.284397) (xy 427.444028 -100.183112)
			(xy 427.267355 -100.08882) (xy 427.087051 -100.001673) (xy 426.903405 -99.921809) (xy 426.71671 -99.849357)
			(xy 426.527267 -99.784432) (xy 426.335377 -99.727139) (xy 426.141349 -99.677569) (xy 425.945492 -99.635802)
			(xy 425.748122 -99.601905) (xy 425.549553 -99.575931) (xy 425.350104 -99.557923) (xy 425.150095 -99.547909)
			(xy 424.949844 -99.545905) (xy 424.749674 -99.551915) (xy 424.549905 -99.565929) (xy 424.350857 -99.587925)
			(xy 424.152847 -99.617866) (xy 423.956195 -99.655706) (xy 423.761213 -99.701384) (xy 423.568216 -99.754826)
			(xy 423.377511 -99.815947) (xy 423.189404 -99.884649) (xy 423.004197 -99.960822) (xy 422.822185 -100.044345)
			(xy 422.643661 -100.135082) (xy 422.46891 -100.23289) (xy 422.298213 -100.337611) (xy 422.131842 -100.449078)
			(xy 421.970064 -100.567112) (xy 421.813138 -100.691524) (xy 421.661315 -100.822115) (xy 421.514839 -100.958676)
			(xy 421.373944 -101.100988) (xy 421.238855 -101.248823) (xy 421.10979 -101.401945) (xy 420.986954 -101.560107)
			(xy 420.870544 -101.723058) (xy 420.760748 -101.890536) (xy 420.65774 -102.062273) (xy 420.561685 -102.237993)
			(xy 420.472738 -102.417416) (xy 420.391041 -102.600254) (xy 420.316725 -102.786215) (xy 420.249908 -102.974999)
			(xy 420.190698 -103.166306) (xy 420.139189 -103.359829) (xy 420.095465 -103.555257) (xy 420.059594 -103.752279)
			(xy 420.031635 -103.950578) (xy 420.011632 -104.149836) (xy 419.999618 -104.349736) (xy 419.995611 -104.549956)
			(xy 422.482268 -104.549956) (xy 422.4863 -104.40752) (xy 422.498384 -104.265541) (xy 422.518482 -104.124472)
			(xy 422.546528 -103.984766) (xy 422.582433 -103.846871) (xy 422.626082 -103.711228) (xy 422.677335 -103.578272)
			(xy 422.736028 -103.448429) (xy 422.801973 -103.322114) (xy 422.874958 -103.199732) (xy 422.954751 -103.081675)
			(xy 423.041095 -102.968321) (xy 423.133713 -102.860034) (xy 423.232309 -102.757161) (xy 423.336568 -102.66003)
			(xy 423.446155 -102.568953) (xy 423.560719 -102.484222) (xy 423.679893 -102.406108) (xy 423.803295 -102.334862)
			(xy 423.930531 -102.270711) (xy 424.061192 -102.213861) (xy 424.19486 -102.164495) (xy 424.331107 -102.12277)
			(xy 424.469496 -102.088819) (xy 424.609585 -102.062753) (xy 424.750924 -102.044654) (xy 424.89306 -102.03458)
			(xy 425.035539 -102.032564) (xy 425.177903 -102.038611) (xy 425.319698 -102.052703) (xy 425.460468 -102.074795)
			(xy 425.599762 -102.104815) (xy 425.737136 -102.142668) (xy 425.872147 -102.188232) (xy 426.004365 -102.241362)
			(xy 426.133365 -102.301886) (xy 426.258734 -102.369612) (xy 426.380071 -102.444322) (xy 426.496987 -102.525777)
			(xy 426.609107 -102.613716) (xy 426.716073 -102.707858) (xy 426.817541 -102.8079) (xy 426.913186 -102.913523)
			(xy 427.002703 -103.024387) (xy 427.085805 -103.140139) (xy 427.162224 -103.260406) (xy 427.231717 -103.384804)
			(xy 427.294061 -103.512935) (xy 427.349056 -103.644388) (xy 427.396527 -103.778741) (xy 427.43632 -103.915565)
			(xy 427.468308 -104.054421) (xy 427.492389 -104.194864) (xy 427.508487 -104.336445) (xy 427.516548 -104.47871)
			(xy 427.517052 -104.549956) (xy 427.516548 -104.621202) (xy 427.508487 -104.763467) (xy 427.492389 -104.905048)
			(xy 427.468308 -105.045491) (xy 427.43632 -105.184347) (xy 427.396527 -105.321171) (xy 427.349056 -105.455524)
			(xy 427.294061 -105.586977) (xy 427.231717 -105.715108) (xy 427.162224 -105.839506) (xy 427.085805 -105.959773)
			(xy 427.002703 -106.075525) (xy 426.913186 -106.186389) (xy 426.817541 -106.292012) (xy 426.716073 -106.392054)
			(xy 426.609107 -106.486196) (xy 426.496987 -106.574135) (xy 426.380071 -106.65559) (xy 426.258734 -106.7303)
			(xy 426.133365 -106.798026) (xy 426.004365 -106.85855) (xy 425.872147 -106.91168) (xy 425.737136 -106.957244)
			(xy 425.599762 -106.995097) (xy 425.460468 -107.025117) (xy 425.319698 -107.047209) (xy 425.177903 -107.061301)
			(xy 425.035539 -107.067348) (xy 424.89306 -107.065332) (xy 424.750924 -107.055258) (xy 424.609585 -107.037159)
			(xy 424.469496 -107.011093) (xy 424.331107 -106.977142) (xy 424.19486 -106.935417) (xy 424.061192 -106.886051)
			(xy 423.930531 -106.829201) (xy 423.803295 -106.76505) (xy 423.679893 -106.693804) (xy 423.560719 -106.61569)
			(xy 423.446155 -106.530959) (xy 423.336568 -106.439882) (xy 423.232309 -106.342751) (xy 423.133713 -106.239878)
			(xy 423.041095 -106.131591) (xy 422.954751 -106.018237) (xy 422.874958 -105.90018) (xy 422.801973 -105.777798)
			(xy 422.736028 -105.651483) (xy 422.677335 -105.52164) (xy 422.626082 -105.388684) (xy 422.582433 -105.253041)
			(xy 422.546528 -105.115146) (xy 422.518482 -104.97544) (xy 422.498384 -104.834371) (xy 422.4863 -104.692392)
			(xy 422.482268 -104.549956) (xy 419.995611 -104.549956) (xy 419.999618 -104.750176) (xy 420.011632 -104.950076)
			(xy 420.031635 -105.149334) (xy 420.059594 -105.347633) (xy 420.095465 -105.544655) (xy 420.139189 -105.740083)
			(xy 420.190698 -105.933606) (xy 420.249908 -106.124913) (xy 420.316725 -106.313697) (xy 420.391041 -106.499658)
			(xy 420.472738 -106.682496) (xy 420.561685 -106.861919) (xy 420.65774 -107.037639) (xy 420.760748 -107.209376)
			(xy 420.870544 -107.376854) (xy 420.986954 -107.539805) (xy 421.10979 -107.697967) (xy 421.238855 -107.851089)
			(xy 421.373944 -107.998924) (xy 421.514839 -108.141236) (xy 421.661315 -108.277797) (xy 421.813138 -108.408388)
			(xy 421.970064 -108.5328) (xy 422.131842 -108.650834) (xy 422.298213 -108.762301) (xy 422.46891 -108.867022)
			(xy 422.643661 -108.96483) (xy 422.822185 -109.055567) (xy 423.004197 -109.13909) (xy 423.189404 -109.215263)
			(xy 423.377511 -109.283965) (xy 423.568216 -109.345086) (xy 423.761213 -109.398528) (xy 423.956195 -109.444206)
			(xy 424.152847 -109.482046) (xy 424.350857 -109.511987) (xy 424.549905 -109.533983) (xy 424.749674 -109.547997)
			(xy 424.949844 -109.554007) (xy 425.150095 -109.552003) (xy 425.350104 -109.541989) (xy 425.549553 -109.523981)
			(xy 425.748122 -109.498007) (xy 425.945492 -109.46411) (xy 426.141349 -109.422343) (xy 426.335377 -109.372773)
			(xy 426.527267 -109.31548) (xy 426.71671 -109.250555) (xy 426.903405 -109.178103) (xy 427.087051 -109.098239)
			(xy 427.267355 -109.011092) (xy 427.444028 -108.9168) (xy 427.616786 -108.815515) (xy 427.785354 -108.7074)
			(xy 427.949462 -108.592627) (xy 428.108846 -108.471379) (xy 428.263251 -108.343852) (xy 428.41243 -108.210249)
			(xy 428.556145 -108.070785) (xy 428.694164 -107.925683) (xy 428.826268 -107.775174) (xy 428.952244 -107.619501)
			(xy 429.07189 -107.458912) (xy 429.185016 -107.293664) (xy 429.29144 -107.124023) (xy 429.390991 -106.950259)
			(xy 429.48351 -106.772652) (xy 429.568849 -106.591485) (xy 429.646872 -106.407049) (xy 429.717452 -106.219639)
			(xy 429.780478 -106.029556) (xy 429.835849 -105.837102) (xy 429.883475 -105.642588) (xy 429.92328 -105.446323)
			(xy 429.955201 -105.248624) (xy 429.979187 -105.049805) (xy 429.995199 -104.850186) (xy 430.003211 -104.650086)
		)
		(stroke
			(width 0)
			(type solid)
		)
		(fill yes)
		(layer "F.Cu")
		(net "GND")
	)
	(gr_poly
		(pts
			(xy 430.003712 -60.099956) (xy 430.003211 -59.999826) (xy 429.995199 -59.799726) (xy 429.979187 -59.600107)
			(xy 429.955201 -59.401288) (xy 429.92328 -59.203589) (xy 429.883475 -59.007324) (xy 429.835849 -58.81281)
			(xy 429.780478 -58.620356) (xy 429.717452 -58.430273) (xy 429.646872 -58.242863) (xy 429.568849 -58.058427)
			(xy 429.48351 -57.87726) (xy 429.390991 -57.699653) (xy 429.29144 -57.525889) (xy 429.185016 -57.356248)
			(xy 429.07189 -57.191) (xy 428.952244 -57.030411) (xy 428.826268 -56.874738) (xy 428.694164 -56.724229)
			(xy 428.556145 -56.579127) (xy 428.41243 -56.439663) (xy 428.263251 -56.30606) (xy 428.108846 -56.178533)
			(xy 427.949462 -56.057285) (xy 427.785354 -55.942512) (xy 427.616786 -55.834397) (xy 427.444028 -55.733112)
			(xy 427.267355 -55.63882) (xy 427.087051 -55.551673) (xy 426.903405 -55.471809) (xy 426.71671 -55.399357)
			(xy 426.527267 -55.334432) (xy 426.335377 -55.277139) (xy 426.141349 -55.227569) (xy 425.945492 -55.185802)
			(xy 425.748122 -55.151905) (xy 425.549553 -55.125931) (xy 425.350104 -55.107923) (xy 425.150095 -55.097909)
			(xy 424.949844 -55.095905) (xy 424.749674 -55.101915) (xy 424.549905 -55.115929) (xy 424.350857 -55.137925)
			(xy 424.152847 -55.167866) (xy 423.956195 -55.205706) (xy 423.761213 -55.251384) (xy 423.568216 -55.304826)
			(xy 423.377511 -55.365947) (xy 423.189404 -55.434649) (xy 423.004197 -55.510822) (xy 422.822185 -55.594345)
			(xy 422.643661 -55.685082) (xy 422.46891 -55.78289) (xy 422.298213 -55.887611) (xy 422.131842 -55.999078)
			(xy 421.970064 -56.117112) (xy 421.813138 -56.241524) (xy 421.661315 -56.372115) (xy 421.514839 -56.508676)
			(xy 421.373944 -56.650988) (xy 421.238855 -56.798823) (xy 421.10979 -56.951945) (xy 420.986954 -57.110107)
			(xy 420.870544 -57.273058) (xy 420.760748 -57.440536) (xy 420.65774 -57.612273) (xy 420.561685 -57.787993)
			(xy 420.472738 -57.967416) (xy 420.391041 -58.150254) (xy 420.316725 -58.336215) (xy 420.249908 -58.524999)
			(xy 420.190698 -58.716306) (xy 420.139189 -58.909829) (xy 420.095465 -59.105257) (xy 420.059594 -59.302279)
			(xy 420.031635 -59.500578) (xy 420.011632 -59.699836) (xy 419.999618 -59.899736) (xy 419.995611 -60.099956)
			(xy 422.482268 -60.099956) (xy 422.4863 -59.95752) (xy 422.498384 -59.815541) (xy 422.518482 -59.674472)
			(xy 422.546528 -59.534766) (xy 422.582433 -59.396871) (xy 422.626082 -59.261228) (xy 422.677335 -59.128272)
			(xy 422.736028 -58.998429) (xy 422.801973 -58.872114) (xy 422.874958 -58.749732) (xy 422.954751 -58.631675)
			(xy 423.041095 -58.518321) (xy 423.133713 -58.410034) (xy 423.232309 -58.307161) (xy 423.336568 -58.21003)
			(xy 423.446155 -58.118953) (xy 423.560719 -58.034222) (xy 423.679893 -57.956108) (xy 423.803295 -57.884862)
			(xy 423.930531 -57.820711) (xy 424.061192 -57.763861) (xy 424.19486 -57.714495) (xy 424.331107 -57.67277)
			(xy 424.469496 -57.638819) (xy 424.609585 -57.612753) (xy 424.750924 -57.594654) (xy 424.89306 -57.58458)
			(xy 425.035539 -57.582564) (xy 425.177903 -57.588611) (xy 425.319698 -57.602703) (xy 425.460468 -57.624795)
			(xy 425.599762 -57.654815) (xy 425.737136 -57.692668) (xy 425.872147 -57.738232) (xy 426.004365 -57.791362)
			(xy 426.133365 -57.851886) (xy 426.258734 -57.919612) (xy 426.380071 -57.994322) (xy 426.496987 -58.075777)
			(xy 426.609107 -58.163716) (xy 426.716073 -58.257858) (xy 426.817541 -58.3579) (xy 426.913186 -58.463523)
			(xy 427.002703 -58.574387) (xy 427.085805 -58.690139) (xy 427.162224 -58.810406) (xy 427.231717 -58.934804)
			(xy 427.294061 -59.062935) (xy 427.349056 -59.194388) (xy 427.396527 -59.328741) (xy 427.43632 -59.465565)
			(xy 427.468308 -59.604421) (xy 427.492389 -59.744864) (xy 427.508487 -59.886445) (xy 427.516548 -60.02871)
			(xy 427.517052 -60.099956) (xy 427.516548 -60.171202) (xy 427.508487 -60.313467) (xy 427.492389 -60.455048)
			(xy 427.468308 -60.595491) (xy 427.43632 -60.734347) (xy 427.396527 -60.871171) (xy 427.349056 -61.005524)
			(xy 427.294061 -61.136977) (xy 427.231717 -61.265108) (xy 427.162224 -61.389506) (xy 427.085805 -61.509773)
			(xy 427.002703 -61.625525) (xy 426.913186 -61.736389) (xy 426.817541 -61.842012) (xy 426.716073 -61.942054)
			(xy 426.609107 -62.036196) (xy 426.496987 -62.124135) (xy 426.380071 -62.20559) (xy 426.258734 -62.2803)
			(xy 426.133365 -62.348026) (xy 426.004365 -62.40855) (xy 425.872147 -62.46168) (xy 425.737136 -62.507244)
			(xy 425.599762 -62.545097) (xy 425.460468 -62.575117) (xy 425.319698 -62.597209) (xy 425.177903 -62.611301)
			(xy 425.035539 -62.617348) (xy 424.89306 -62.615332) (xy 424.750924 -62.605258) (xy 424.609585 -62.587159)
			(xy 424.469496 -62.561093) (xy 424.331107 -62.527142) (xy 424.19486 -62.485417) (xy 424.061192 -62.436051)
			(xy 423.930531 -62.379201) (xy 423.803295 -62.31505) (xy 423.679893 -62.243804) (xy 423.560719 -62.16569)
			(xy 423.446155 -62.080959) (xy 423.336568 -61.989882) (xy 423.232309 -61.892751) (xy 423.133713 -61.789878)
			(xy 423.041095 -61.681591) (xy 422.954751 -61.568237) (xy 422.874958 -61.45018) (xy 422.801973 -61.327798)
			(xy 422.736028 -61.201483) (xy 422.677335 -61.07164) (xy 422.626082 -60.938684) (xy 422.582433 -60.803041)
			(xy 422.546528 -60.665146) (xy 422.518482 -60.52544) (xy 422.498384 -60.384371) (xy 422.4863 -60.242392)
			(xy 422.482268 -60.099956) (xy 419.995611 -60.099956) (xy 419.999618 -60.300176) (xy 420.011632 -60.500076)
			(xy 420.031635 -60.699334) (xy 420.059594 -60.897633) (xy 420.095465 -61.094655) (xy 420.139189 -61.290083)
			(xy 420.190698 -61.483606) (xy 420.249908 -61.674913) (xy 420.316725 -61.863697) (xy 420.391041 -62.049658)
			(xy 420.472738 -62.232496) (xy 420.561685 -62.411919) (xy 420.65774 -62.587639) (xy 420.760748 -62.759376)
			(xy 420.870544 -62.926854) (xy 420.986954 -63.089805) (xy 421.10979 -63.247967) (xy 421.238855 -63.401089)
			(xy 421.373944 -63.548924) (xy 421.514839 -63.691236) (xy 421.661315 -63.827797) (xy 421.813138 -63.958388)
			(xy 421.970064 -64.0828) (xy 422.131842 -64.200834) (xy 422.298213 -64.312301) (xy 422.46891 -64.417022)
			(xy 422.643661 -64.51483) (xy 422.822185 -64.605567) (xy 423.004197 -64.68909) (xy 423.189404 -64.765263)
			(xy 423.377511 -64.833965) (xy 423.568216 -64.895086) (xy 423.761213 -64.948528) (xy 423.956195 -64.994206)
			(xy 424.152847 -65.032046) (xy 424.350857 -65.061987) (xy 424.549905 -65.083983) (xy 424.749674 -65.097997)
			(xy 424.949844 -65.104007) (xy 425.150095 -65.102003) (xy 425.350104 -65.091989) (xy 425.549553 -65.073981)
			(xy 425.748122 -65.048007) (xy 425.945492 -65.01411) (xy 426.141349 -64.972343) (xy 426.335377 -64.922773)
			(xy 426.527267 -64.86548) (xy 426.71671 -64.800555) (xy 426.903405 -64.728103) (xy 427.087051 -64.648239)
			(xy 427.267355 -64.561092) (xy 427.444028 -64.4668) (xy 427.616786 -64.365515) (xy 427.785354 -64.2574)
			(xy 427.949462 -64.142627) (xy 428.108846 -64.021379) (xy 428.263251 -63.893852) (xy 428.41243 -63.760249)
			(xy 428.556145 -63.620785) (xy 428.694164 -63.475683) (xy 428.826268 -63.325174) (xy 428.952244 -63.169501)
			(xy 429.07189 -63.008912) (xy 429.185016 -62.843664) (xy 429.29144 -62.674023) (xy 429.390991 -62.500259)
			(xy 429.48351 -62.322652) (xy 429.568849 -62.141485) (xy 429.646872 -61.957049) (xy 429.717452 -61.769639)
			(xy 429.780478 -61.579556) (xy 429.835849 -61.387102) (xy 429.883475 -61.192588) (xy 429.92328 -60.996323)
			(xy 429.955201 -60.798624) (xy 429.979187 -60.599805) (xy 429.995199 -60.400186) (xy 430.003211 -60.200086)
		)
		(stroke
			(width 0)
			(type solid)
		)
		(fill yes)
		(layer "F.Cu")
		(net "GND")
	)
	(gr_poly
		(pts
			(arc
				(start 283.97327 -79.8576)
				(mid 283.992657 -79.85365)
				(end 284.009084 -79.842614)
			)
			(xy 284.932374 -78.919578)
			(arc
				(start 285.119064 -78.732888)
				(mid 285.129313 -78.716683)
				(end 285.13278 -78.697836)
			)
			(arc
				(start 285.13278 -74.998072)
				(mid 285.12883 -74.978685)
				(end 285.117794 -74.962258)
			)
			(xy 284.92831 -74.77252)
			(arc
				(start 283.984954 -73.829418)
				(mid 283.911058 -73.718825)
				(end 283.885132 -73.588372)
			)
			(arc
				(start 283.885132 -72.959214)
				(mid 283.881231 -72.939691)
				(end 283.870146 -72.923146)
			)
			(arc
				(start 283.478986 -72.531986)
				(mid 283.467875 -72.515452)
				(end 283.464 -72.495918)
			)
			(arc
				(start 283.464 -70.05193)
				(mid 283.46005 -70.032543)
				(end 283.449014 -70.016116)
			)
			(arc
				(start 282.749752 -69.316854)
				(mid 282.733335 -69.305792)
				(end 282.713938 -69.301868)
			)
			(xy 279.952704 -69.301868)
			(arc
				(start 279.942544 -69.306694)
				(mid 279.863735 -69.333446)
				(end 279.781 -69.342508)
			)
			(arc
				(start 279.781 -69.342508)
				(mid 279.511233 -69.230767)
				(end 279.399492 -68.961)
			)
			(arc
				(start 279.399492 -68.961)
				(mid 279.407542 -68.883295)
				(end 279.431242 -68.808854)
			)
			(xy 279.436322 -68.796916) (xy 279.434036 -68.77177)
			(arc
				(start 279.380442 -68.689728)
				(mid 279.362115 -68.672952)
				(end 279.338024 -68.666868)
			)
			(arc
				(start 278.7904 -68.666868)
				(mid 278.659955 -68.640921)
				(end 278.549354 -68.567046)
			)
			(xy 277.487634 -67.505072) (xy 277.27402 -67.291458)
			(arc
				(start 277.263352 -67.287648)
				(mid 277.081027 -67.148007)
				(end 277.011892 -66.929)
			)
			(arc
				(start 277.011892 -66.929)
				(mid 277.012374 -66.90878)
				(end 277.013924 -66.888614)
			)
			(xy 277.015194 -66.877692) (xy 277.00859 -66.857372)
			(arc
				(start 276.950678 -66.793364)
				(mid 276.933648 -66.781045)
				(end 276.913086 -66.7766)
			)
			(arc
				(start 274.483068 -66.7766)
				(mid 274.447147 -66.791479)
				(end 274.432268 -66.8274)
			)
			(arc
				(start 274.432268 -68.866004)
				(mid 274.436218 -68.885391)
				(end 274.447254 -68.901818)
			)
			(arc
				(start 274.660106 -69.114924)
				(mid 274.67785 -69.126364)
				(end 274.698714 -69.129656)
			)
			(xy 274.785074 -69.125084) (xy 274.804124 -69.115432)
			(arc
				(start 274.810982 -69.106796)
				(mid 274.943235 -69.002701)
				(end 275.1074 -68.965572)
			)
			(arc
				(start 275.1074 -68.965572)
				(mid 275.190143 -68.974597)
				(end 275.268944 -69.001386)
			)
			(xy 275.279104 -69.006212)
			(arc
				(start 275.323808 -69.006212)
				(mid 275.359729 -68.991333)
				(end 275.374608 -68.955412)
			)
			(xy 275.374608 -68.949062)
			(arc
				(start 275.373084 -68.942712)
				(mid 275.363969 -68.895473)
				(end 275.360892 -68.847462)
			)
			(arc
				(start 275.360892 -68.8467)
				(mid 275.472633 -68.576933)
				(end 275.7424 -68.465192)
			)
			(arc
				(start 275.7424 -68.465192)
				(mid 275.825143 -68.474217)
				(end 275.903944 -68.501006)
			)
			(xy 275.914104 -68.505832)
			(arc
				(start 276.8981 -68.505832)
				(mid 277.028545 -68.531779)
				(end 277.139146 -68.605654)
			)
			(arc
				(start 278.504396 -69.970904)
				(mid 278.549677 -70.027094)
				(end 278.58212 -70.091554)
			)
			(arc
				(start 278.58212 -70.091554)
				(mid 278.598515 -70.150761)
				(end 278.603964 -70.21195)
			)
			(arc
				(start 278.603964 -71.991982)
				(mid 278.610406 -72.016489)
				(end 278.62784 -72.034908)
			)
			(arc
				(start 278.700738 -72.080628)
				(mid 278.725047 -72.088267)
				(end 278.750014 -72.083168)
			)
			(arc
				(start 278.750014 -72.083168)
				(mid 278.822255 -72.057741)
				(end 278.89835 -72.049132)
			)
			(xy 280.415746 -72.049132) (xy 280.428446 -72.04583)
			(arc
				(start 280.434288 -72.042528)
				(mid 280.488339 -72.020229)
				(end 280.546302 -72.012556)
			)
			(xy 280.762964 -72.012556) (xy 280.7843 -72.012556) (xy 280.813764 -72.042528) (xy 280.813764 -72.042782)
			(xy 280.843736 -72.0725) (xy 281.02814 -72.0725) (xy 281.048968 -72.0725) (xy 281.07894 -72.102472)
			(xy 281.07894 -72.12076)
			(arc
				(start 281.07894 -72.52462)
				(mid 281.08289 -72.544007)
				(end 281.093926 -72.560434)
			)
			(xy 281.57678 -73.043542)
			(arc
				(start 281.587448 -73.047352)
				(mid 281.769773 -73.186993)
				(end 281.838908 -73.406)
			)
			(arc
				(start 281.838908 -73.406)
				(mid 281.727167 -73.675767)
				(end 281.4574 -73.787508)
			)
			(arc
				(start 281.4574 -73.787508)
				(mid 281.342766 -73.769891)
				(end 281.238706 -73.718674)
			)
			(xy 281.226768 -73.710292) (xy 281.198828 -73.708514)
			(arc
				(start 281.106372 -73.756774)
				(mid 281.086431 -73.775433)
				(end 281.07894 -73.801732)
			)
			(arc
				(start 281.07894 -74.479658)
				(mid 281.082841 -74.499181)
				(end 281.093926 -74.515726)
			)
			(arc
				(start 281.315414 -74.737214)
				(mid 281.331948 -74.748325)
				(end 281.351482 -74.7522)
			)
			(arc
				(start 283.432758 -74.7522)
				(mid 283.452281 -74.756101)
				(end 283.468826 -74.767186)
			)
			(arc
				(start 283.553408 -74.851768)
				(mid 283.569854 -74.862694)
				(end 283.589222 -74.8665)
			)
			(xy 283.61894 -74.896218) (xy 283.61894 -74.91476) (xy 283.61894 -75.4507) (xy 283.61894 -75.471528)
			(xy 283.588968 -75.5015) (xy 283.57068 -75.5015)
			(arc
				(start 283.404564 -75.5015)
				(mid 283.368643 -75.516379)
				(end 283.353764 -75.5523)
			)
			(xy 283.353764 -75.561444) (xy 283.33192 -75.561444) (xy 283.320998 -75.561444)
			(arc
				(start 283.12491 -75.757278)
				(mid 283.1111 -75.783307)
				(end 283.113988 -75.81265)
			)
			(xy 283.11983 -75.827128) (xy 283.14523 -75.843892)
			(arc
				(start 283.5148 -75.843892)
				(mid 283.604962 -75.881238)
				(end 283.642308 -75.9714)
			)
			(arc
				(start 283.642308 -76.6826)
				(mid 283.604962 -76.772762)
				(end 283.5148 -76.810108)
			)
			(arc
				(start 283.500068 -76.810108)
				(mid 283.464147 -76.824987)
				(end 283.449268 -76.860908)
			)
			(arc
				(start 283.449268 -76.945744)
				(mid 283.423321 -77.076189)
				(end 283.349446 -77.18679)
			)
			(xy 283.132784 -77.403198) (xy 283.126434 -77.431392)
			(arc
				(start 283.13126 -77.445362)
				(mid 283.221159 -77.795536)
				(end 283.251402 -78.1558)
			)
			(arc
				(start 283.251402 -78.1558)
				(mid 283.08669 -78.983052)
				(end 282.617672 -79.684118)
			)
			(arc
				(start 282.617672 -79.684118)
				(mid 282.608761 -79.696035)
				(end 282.603702 -79.710026)
			)
			(arc
				(start 282.603702 -79.710026)
				(mid 282.602901 -79.724967)
				(end 282.606496 -79.73949)
			)
			(arc
				(start 282.64231 -79.826104)
				(mid 282.649978 -79.838964)
				(end 282.661106 -79.848964)
			)
			(arc
				(start 282.661106 -79.848964)
				(mid 282.674558 -79.855403)
				(end 282.6893 -79.8576)
			)
		)
		(stroke
			(width 0)
			(type solid)
		)
		(fill yes)
		(layer "F.Cu")
		(net "GND_FIELD_SIGNAL")
	)
	(gr_poly
		(pts
			(arc
				(start 271.098518 -79.8576)
				(mid 271.118041 -79.853699)
				(end 271.134586 -79.842614)
			)
			(arc
				(start 271.257014 -79.720186)
				(mid 271.268125 -79.703652)
				(end 271.272 -79.684118)
			)
			(arc
				(start 271.272 -77.770482)
				(mid 271.268099 -77.750959)
				(end 271.257014 -77.734414)
			)
			(xy 271.116298 -77.593698) (xy 271.093692 -77.586332)
			(arc
				(start 271.0815 -77.58811)
				(mid 271.053006 -77.591337)
				(end 271.02435 -77.592428)
			)
			(arc
				(start 271.02435 -77.592428)
				(mid 270.642842 -77.21092)
				(end 271.02435 -76.829412)
			)
			(arc
				(start 271.02435 -76.829412)
				(mid 271.203186 -76.873925)
				(end 271.340326 -76.997052)
			)
			(arc
				(start 271.340326 -76.997052)
				(mid 271.358502 -77.013456)
				(end 271.382236 -77.019404)
			)
			(arc
				(start 271.466564 -77.019404)
				(mid 271.490269 -77.0134)
				(end 271.508474 -76.997052)
			)
			(arc
				(start 271.508474 -76.997052)
				(mid 271.645594 -76.873888)
				(end 271.82445 -76.829412)
			)
			(arc
				(start 271.82445 -76.829412)
				(mid 272.006359 -76.875573)
				(end 272.144236 -77.002894)
			)
			(xy 272.150586 -77.012546) (xy 272.170144 -77.024484)
			(arc
				(start 272.26006 -77.033882)
				(mid 272.282266 -77.031281)
				(end 272.301208 -77.019404)
			)
			(arc
				(start 272.9738 -76.346812)
				(mid 272.984774 -76.330249)
				(end 272.988532 -76.310744)
			)
			(arc
				(start 272.988532 -75.092306)
				(mid 272.984748 -75.072812)
				(end 272.9738 -75.056238)
			)
			(xy 272.508726 -74.591164)
			(arc
				(start 272.498058 -74.587354)
				(mid 272.33545 -74.473437)
				(end 272.252186 -74.293222)
			)
			(xy 272.2499 -74.280522) (xy 272.234914 -74.260964) (xy 272.1356 -74.215244) (xy 272.110962 -74.216514)
			(arc
				(start 272.099786 -74.223118)
				(mid 272.005765 -74.26325)
				(end 271.90446 -74.276966)
			)
			(arc
				(start 271.90446 -74.276966)
				(mid 271.634693 -74.165225)
				(end 271.522952 -73.895458)
			)
			(arc
				(start 271.522952 -73.895458)
				(mid 271.592079 -73.676446)
				(end 271.774412 -73.53681)
			)
			(xy 271.78508 -73.533)
			(arc
				(start 271.934686 -73.38314)
				(mid 272.045308 -73.309381)
				(end 272.175732 -73.283572)
			)
			(arc
				(start 273.471386 -73.283572)
				(mid 273.601801 -73.309402)
				(end 273.712432 -73.38314)
			)
			(arc
				(start 274.078446 -73.749154)
				(mid 274.152342 -73.859747)
				(end 274.178268 -73.9902)
			)
			(arc
				(start 274.178268 -74.233024)
				(mid 274.184346 -74.257119)
				(end 274.201128 -74.275442)
			)
			(xy 274.282916 -74.329036) (xy 274.308316 -74.331322)
			(arc
				(start 274.320254 -74.326242)
				(mid 274.394693 -74.302532)
				(end 274.4724 -74.294492)
			)
			(arc
				(start 274.4724 -74.294492)
				(mid 274.742167 -74.406233)
				(end 274.853908 -74.676)
			)
			(arc
				(start 274.853908 -74.676)
				(mid 274.844794 -74.758891)
				(end 274.81784 -74.837798)
			)
			(xy 274.813268 -74.847958)
			(arc
				(start 274.813268 -79.593186)
				(mid 274.817101 -79.612543)
				(end 274.828 -79.629)
			)
			(arc
				(start 275.041614 -79.842614)
				(mid 275.058148 -79.853725)
				(end 275.077682 -79.8576)
			)
			(arc
				(start 278.732488 -79.8576)
				(mid 278.760772 -79.848998)
				(end 278.779478 -79.826104)
			)
			(xy 278.821134 -79.725266) (xy 278.815038 -79.69504)
			(arc
				(start 278.804116 -79.684118)
				(mid 278.335107 -78.983048)
				(end 278.170386 -78.1558)
			)
			(arc
				(start 278.170386 -78.1558)
				(mid 278.291577 -77.442542)
				(end 278.641556 -76.809346)
			)
			(xy 278.6507 -76.797916) (xy 278.654002 -76.768706)
			(arc
				(start 278.608028 -76.673202)
				(mid 278.589186 -76.652216)
				(end 278.562054 -76.6445)
			)
			(arc
				(start 278.451564 -76.6445)
				(mid 278.415643 -76.659379)
				(end 278.400764 -76.6953)
			)
			(xy 278.400764 -76.704444)
			(arc
				(start 278.133302 -76.704444)
				(mid 277.972826 -76.637603)
				(end 277.907242 -76.476606)
			)
			(xy 277.907496 -76.476606)
			(arc
				(start 277.907496 -76.474066)
				(mid 277.903595 -76.454543)
				(end 277.89251 -76.437998)
			)
			(arc
				(start 275.882354 -74.428096)
				(mid 275.808458 -74.317503)
				(end 275.782532 -74.18705)
			)
			(arc
				(start 275.782532 -72.933306)
				(mid 275.778748 -72.913812)
				(end 275.7678 -72.897238)
			)
			(arc
				(start 275.247354 -72.377046)
				(mid 275.173458 -72.266453)
				(end 275.147532 -72.136)
			)
			(arc
				(start 275.147532 -71.397622)
				(mid 275.143767 -71.378431)
				(end 275.133054 -71.362062)
			)
			(arc
				(start 275.111972 -71.340472)
				(mid 275.09672 -71.329915)
				(end 275.078698 -71.325486)
			)
			(arc
				(start 275.078698 -71.325486)
				(mid 274.737788 -71.167049)
				(end 274.598892 -70.81774)
			)
			(arc
				(start 274.598892 -70.81774)
				(mid 274.747831 -70.458171)
				(end 275.1074 -70.309232)
			)
			(arc
				(start 275.1074 -70.309232)
				(mid 275.269529 -70.335771)
				(end 275.41474 -70.41261)
			)
			(xy 275.422868 -70.418706) (xy 275.44268 -70.423786) (xy 275.535136 -70.409816) (xy 275.552662 -70.398894)
			(arc
				(start 275.558758 -70.390512)
				(mid 275.572339 -70.372571)
				(end 275.586952 -70.35546)
			)
			(xy 275.597112 -70.344284) (xy 275.601938 -70.31482)
			(arc
				(start 275.55825 -70.216014)
				(mid 275.539499 -70.193987)
				(end 275.511768 -70.185788)
			)
			(arc
				(start 274.908264 -70.185788)
				(mid 274.777819 -70.159841)
				(end 274.667218 -70.085966)
			)
			(arc
				(start 273.850354 -69.269102)
				(mid 273.776458 -69.158509)
				(end 273.750532 -69.028056)
			)
			(arc
				(start 273.750532 -66.916554)
				(mid 273.746748 -66.89706)
				(end 273.7358 -66.880486)
			)
			(arc
				(start 273.646646 -66.791586)
				(mid 273.630229 -66.780524)
				(end 273.610832 -66.7766)
			)
			(xy 270.85544 -66.7766) (xy 270.645382 -66.986658) (xy 270.645382 -74.813414) (xy 268.415262 -77.043534)
			(xy 268.415262 -79.642462)
			(arc
				(start 268.615414 -79.842614)
				(mid 268.631948 -79.853725)
				(end 268.651482 -79.8576)
			)
		)
		(stroke
			(width 0)
			(type solid)
		)
		(fill yes)
		(layer "F.Cu")
		(net "GND_FIELD_SIGNAL")
	)
	(gr_poly
		(pts
			(xy 289.583876 -79.8576) (xy 289.593307 -79.857102) (xy 289.610862 -79.850182) (xy 289.62475 -79.837407)
			(xy 289.629342 -79.829152) (xy 289.676078 -79.73441) (xy 289.67303 -79.705454) (xy 289.66414 -79.694024)
			(xy 289.646615 -79.670337) (xy 289.618298 -79.618667) (xy 289.607752 -79.591154) (xy 289.603942 -79.580486)
			(xy 288.09823 -78.075028) (xy 288.082836 -78.059144) (xy 288.055863 -78.024087) (xy 288.03366 -77.985831)
			(xy 288.024824 -77.965554) (xy 288.019998 -77.953616) (xy 288.00044 -77.937868) (xy 287.90519 -77.919072)
			(xy 287.892793 -77.917265) (xy 287.868822 -77.924452) (xy 287.85947 -77.932788) (xy 287.511998 -78.28026)
			(xy 287.508188 -78.290928) (xy 287.497724 -78.318168) (xy 287.469716 -78.369358) (xy 287.43424 -78.415687)
			(xy 287.392123 -78.456073) (xy 287.344348 -78.489575) (xy 287.292029 -78.515412) (xy 287.236385 -78.532981)
			(xy 287.178716 -78.541872) (xy 287.14954 -78.542388) (xy 287.122286 -78.541927) (xy 287.068332 -78.534175)
			(xy 287.01603 -78.518822) (xy 286.966446 -78.496182) (xy 286.92059 -78.466714) (xy 286.879394 -78.43102)
			(xy 286.843698 -78.389827) (xy 286.814228 -78.343971) (xy 286.791585 -78.294389) (xy 286.776229 -78.242088)
			(xy 286.768474 -78.188134) (xy 286.768032 -78.16088) (xy 286.76852 -78.132948) (xy 286.776667 -78.077681)
			(xy 286.792783 -78.024192) (xy 286.816524 -77.973623) (xy 286.831532 -77.95006) (xy 286.836866 -77.941932)
			(xy 286.84093 -77.923644) (xy 286.82696 -77.836522) (xy 286.817308 -77.820012) (xy 286.809688 -77.81417)
			(xy 286.787382 -77.795976) (xy 286.74798 -77.754017) (xy 286.715328 -77.706614) (xy 286.690168 -77.654845)
			(xy 286.67307 -77.599883) (xy 286.664424 -77.542976) (xy 286.663892 -77.514196) (xy 286.664372 -77.48633)
			(xy 286.67249 -77.431194) (xy 286.688565 -77.377832) (xy 286.69996 -77.352398) (xy 286.704532 -77.342238)
			(xy 286.704532 -68.421504) (xy 286.705057 -68.394718) (xy 286.713435 -68.341804) (xy 286.729985 -68.290851)
			(xy 286.7543 -68.243114) (xy 286.785782 -68.199767) (xy 286.804354 -68.180458) (xy 287.00603 -67.979036)
			(xy 287.01365 -67.960494) (xy 287.013396 -67.95008) (xy 287.013396 -67.945) (xy 287.015428 -67.90055)
			(xy 287.01619 -67.89039) (xy 287.010348 -67.871594) (xy 286.952944 -67.801236) (xy 286.935672 -67.791838)
			(xy 286.925766 -67.790568) (xy 286.898211 -67.786898) (xy 286.844491 -67.77261) (xy 286.793413 -67.750678)
			(xy 286.746058 -67.721566) (xy 286.703429 -67.685891) (xy 286.666428 -67.644407) (xy 286.635837 -67.597994)
			(xy 286.612305 -67.547633) (xy 286.59633 -67.494391) (xy 286.588249 -67.439394) (xy 286.587692 -67.4116)
			(xy 286.588178 -67.384349) (xy 286.595934 -67.330401) (xy 286.611289 -67.278106) (xy 286.633931 -67.228529)
			(xy 286.663397 -67.182679) (xy 286.699088 -67.141488) (xy 286.740279 -67.105797) (xy 286.786129 -67.076331)
			(xy 286.835706 -67.053689) (xy 286.888001 -67.038334) (xy 286.941949 -67.030578) (xy 286.9692 -67.030092)
			(xy 286.996317 -67.030569) (xy 287.050005 -67.038252) (xy 287.102063 -67.053462) (xy 287.151442 -67.075893)
			(xy 287.197145 -67.105093) (xy 287.23825 -67.140473) (xy 287.27393 -67.181319) (xy 287.303464 -67.226807)
			(xy 287.326256 -67.27602) (xy 287.341847 -67.327965) (xy 287.34639 -67.354704) (xy 287.347914 -67.36461)
			(xy 287.358074 -67.381628) (xy 287.430464 -67.436492) (xy 287.449514 -67.441572) (xy 287.45942 -67.440302)
			(xy 287.474978 -67.438501) (xy 287.506243 -67.436593) (xy 287.521904 -67.436492) (xy 287.553865 -67.436994)
			(xy 287.617283 -67.445006) (xy 287.679196 -67.460903) (xy 287.738629 -67.484435) (xy 287.794644 -67.51523)
			(xy 287.846357 -67.552802) (xy 287.892954 -67.59656) (xy 287.933699 -67.645812) (xy 287.96795 -67.699783)
			(xy 287.995166 -67.757622) (xy 288.014919 -67.818415) (xy 288.026897 -67.881204) (xy 288.030911 -67.945)
			(xy 288.026897 -68.008796) (xy 288.014919 -68.071585) (xy 287.995166 -68.132378) (xy 287.96795 -68.190217)
			(xy 287.933699 -68.244188) (xy 287.892954 -68.29344) (xy 287.846357 -68.337198) (xy 287.794644 -68.37477)
			(xy 287.738629 -68.405565) (xy 287.679196 -68.429097) (xy 287.617283 -68.444994) (xy 287.553865 -68.453006)
			(xy 287.521904 -68.453508) (xy 287.516824 -68.453508) (xy 287.50641 -68.453254) (xy 287.487868 -68.460874)
			(xy 287.401 -68.547742) (xy 287.394213 -68.555163) (xy 287.386598 -68.57376) (xy 287.386268 -68.58381)
			(xy 287.386268 -69.244972) (xy 287.386789 -69.2559) (xy 287.395877 -69.275775) (xy 287.403794 -69.283326)
			(xy 287.470342 -69.340984) (xy 287.49117 -69.34708) (xy 287.502346 -69.345302) (xy 287.515862 -69.343495)
			(xy 287.543066 -69.341589) (xy 287.556702 -69.341492) (xy 287.583953 -69.341978) (xy 287.637901 -69.349735)
			(xy 287.690195 -69.36509) (xy 287.739772 -69.387731) (xy 287.785622 -69.417198) (xy 287.826812 -69.452889)
			(xy 287.862504 -69.494079) (xy 287.89197 -69.53993) (xy 287.914611 -69.589507) (xy 287.929966 -69.641801)
			(xy 287.937722 -69.695749) (xy 287.93821 -69.723) (xy 287.93773 -69.750866) (xy 287.929613 -69.806002)
			(xy 287.913539 -69.859365) (xy 287.902142 -69.884798) (xy 287.897316 -69.894958) (xy 287.897316 -70.012052)
			(xy 287.918652 -70.03923) (xy 287.935416 -70.043802) (xy 287.964825 -70.051922) (xy 288.021608 -70.074245)
			(xy 288.075311 -70.1032) (xy 288.125165 -70.138373) (xy 288.170453 -70.179257) (xy 288.210525 -70.225266)
			(xy 288.244804 -70.275739) (xy 288.272799 -70.32995) (xy 288.294107 -70.387121) (xy 288.301684 -70.416674)
			(xy 288.304224 -70.426834) (xy 288.316924 -70.443598) (xy 288.399728 -70.490588) (xy 288.420556 -70.492874)
			(xy 288.430716 -70.489826) (xy 288.458341 -70.481764) (xy 288.515228 -70.473094) (xy 288.544 -70.472554)
			(xy 288.571252 -70.47304) (xy 288.625202 -70.480796) (xy 288.677499 -70.496151) (xy 288.727079 -70.518791)
			(xy 288.772932 -70.548257) (xy 288.814125 -70.583948) (xy 288.84982 -70.625138) (xy 288.87929 -70.670988)
			(xy 288.901936 -70.720565) (xy 288.917296 -70.772861) (xy 288.925058 -70.82681) (xy 288.925508 -70.854062)
			(xy 288.925056 -70.880881) (xy 288.91755 -70.93399) (xy 288.902682 -70.985525) (xy 288.880743 -71.034471)
			(xy 288.852167 -71.079862) (xy 288.817516 -71.120804) (xy 288.777474 -71.156491) (xy 288.732828 -71.186219)
			(xy 288.708846 -71.198232) (xy 288.695638 -71.204582) (xy 288.680144 -71.22922) (xy 288.680144 -77.510894)
			(xy 289.584382 -77.510894) (xy 289.588453 -77.455272) (xy 289.600579 -77.400835) (xy 289.620502 -77.348744)
			(xy 289.647798 -77.300109) (xy 289.681884 -77.255966) (xy 289.722033 -77.217257) (xy 289.767391 -77.184806)
			(xy 289.816991 -77.159305) (xy 289.869775 -77.141298) (xy 289.924618 -77.131168) (xy 289.980352 -77.129131)
			(xy 290.035789 -77.135231) (xy 290.089746 -77.149337) (xy 290.141075 -77.171149) (xy 290.188681 -77.200203)
			(xy 290.231549 -77.235878) (xy 290.268766 -77.277415) (xy 290.299539 -77.323928) (xy 290.323211 -77.374425)
			(xy 290.339279 -77.427832) (xy 290.347399 -77.483008) (xy 290.347908 -77.510894) (xy 290.347399 -77.53878)
			(xy 290.339279 -77.593956) (xy 290.323211 -77.647363) (xy 290.299539 -77.69786) (xy 290.268766 -77.744373)
			(xy 290.231549 -77.78591) (xy 290.188681 -77.821585) (xy 290.141075 -77.850639) (xy 290.089746 -77.872451)
			(xy 290.035789 -77.886557) (xy 289.980352 -77.892657) (xy 289.924618 -77.89062) (xy 289.869775 -77.88049)
			(xy 289.816991 -77.862483) (xy 289.767391 -77.836982) (xy 289.722033 -77.804531) (xy 289.681884 -77.765822)
			(xy 289.647798 -77.721679) (xy 289.620502 -77.673044) (xy 289.600579 -77.620953) (xy 289.588453 -77.566516)
			(xy 289.584382 -77.510894) (xy 288.680144 -77.510894) (xy 288.680144 -77.671676) (xy 288.680587 -77.681705)
			(xy 288.688172 -77.700271) (xy 288.694876 -77.707744) (xy 290.08578 -79.098648) (xy 290.096448 -79.102458)
			(xy 290.123685 -79.112924) (xy 290.174869 -79.140935) (xy 290.221191 -79.176412) (xy 290.26157 -79.21853)
			(xy 290.295065 -79.266306) (xy 290.320894 -79.318624) (xy 290.338455 -79.374266) (xy 290.347339 -79.431932)
			(xy 290.347908 -79.461106) (xy 290.347508 -79.486165) (xy 290.340945 -79.535853) (xy 290.327946 -79.584256)
			(xy 290.308734 -79.630547) (xy 290.283638 -79.67393) (xy 290.26866 -79.694024) (xy 290.25977 -79.705454)
			(xy 290.256722 -79.73441) (xy 290.303458 -79.829152) (xy 290.30795 -79.83748) (xy 290.321854 -79.850295)
			(xy 290.339469 -79.85717) (xy 290.348924 -79.8576) (xy 291.784532 -79.8576) (xy 291.794535 -79.857106)
			(xy 291.813016 -79.849441) (xy 291.827159 -79.835289) (xy 291.834813 -79.816804) (xy 291.835332 -79.8068)
			(xy 291.835332 -76.60767) (xy 291.835859 -76.580885) (xy 291.844242 -76.527974) (xy 291.860796 -76.477025)
			(xy 291.885114 -76.429291) (xy 291.916598 -76.385948) (xy 291.935154 -76.366624) (xy 293.390828 -74.911204)
			(xy 293.394638 -74.900536) (xy 293.40396 -74.876085) (xy 293.428349 -74.829789) (xy 293.458839 -74.787263)
			(xy 293.494857 -74.749303) (xy 293.515034 -74.732642) (xy 293.523924 -74.72553) (xy 293.53383 -74.705718)
			(xy 293.53637 -74.605134) (xy 293.527734 -74.584814) (xy 293.519098 -74.577194) (xy 293.499301 -74.559024)
			(xy 293.464501 -74.518078) (xy 293.435798 -74.47265) (xy 293.413759 -74.423642) (xy 293.398821 -74.372024)
			(xy 293.391281 -74.31882) (xy 293.390828 -74.291952) (xy 293.391318 -74.264704) (xy 293.39908 -74.210763)
			(xy 293.414439 -74.158477) (xy 293.437084 -74.108908) (xy 293.466552 -74.063066) (xy 293.502244 -74.021884)
			(xy 293.543433 -73.986202) (xy 293.589282 -73.956744) (xy 293.638855 -73.93411) (xy 293.691146 -73.918762)
			(xy 293.745088 -73.911012) (xy 293.772336 -73.910444) (xy 293.801508 -73.911001) (xy 293.859171 -73.919891)
			(xy 293.914807 -73.937458) (xy 293.96712 -73.963293) (xy 294.014888 -73.996793) (xy 294.056998 -74.037176)
			(xy 294.092467 -74.083501) (xy 294.120468 -74.134686) (xy 294.130984 -74.161904) (xy 294.134794 -74.172572)
			(xy 294.512238 -74.549762) (xy 294.530827 -74.569057) (xy 294.562316 -74.612403) (xy 294.586633 -74.660143)
			(xy 294.60318 -74.711101) (xy 294.611547 -74.76402) (xy 294.61206 -74.790808) (xy 294.61206 -75.324208)
			(xy 294.611535 -75.350995) (xy 294.603157 -75.403909) (xy 294.586609 -75.454863) (xy 294.562298 -75.502603)
			(xy 294.530821 -75.545955) (xy 294.512238 -75.565254) (xy 293.00932 -77.067918) (xy 293.002543 -77.075343)
			(xy 292.994953 -77.09394) (xy 292.994588 -77.103986) (xy 292.994588 -79.8068) (xy 292.995076 -79.816809)
			(xy 293.002735 -79.835302) (xy 293.016888 -79.849458) (xy 293.03538 -79.857122) (xy 293.045388 -79.8576)
			(xy 293.090092 -79.8576) (xy 293.100114 -79.857182) (xy 293.118634 -79.849513) (xy 293.132809 -79.835341)
			(xy 293.14048 -79.816822) (xy 293.140892 -79.8068) (xy 293.140892 -77.352652) (xy 293.141446 -77.322671)
			(xy 293.150824 -77.263446) (xy 293.169355 -77.206418) (xy 293.196583 -77.152994) (xy 293.231838 -77.10449)
			(xy 293.252652 -77.082904) (xy 293.643304 -76.692252) (xy 293.664918 -76.671473) (xy 293.713423 -76.636236)
			(xy 293.766842 -76.609018) (xy 293.823861 -76.590489) (xy 293.883075 -76.581105) (xy 293.913052 -76.580492)
			(xy 293.940307 -76.580952) (xy 293.994263 -76.588703) (xy 294.046567 -76.604055) (xy 294.096153 -76.626695)
			(xy 294.142012 -76.656162) (xy 294.183211 -76.691855) (xy 294.218909 -76.733049) (xy 294.248382 -76.778905)
			(xy 294.271028 -76.828488) (xy 294.286386 -76.88079) (xy 294.294145 -76.934745) (xy 294.29456 -76.962)
			(xy 294.294002 -76.99198) (xy 294.284619 -77.051202) (xy 294.266084 -77.108226) (xy 294.238854 -77.161647)
			(xy 294.203599 -77.210148) (xy 294.1828 -77.231748) (xy 293.91864 -77.495654) (xy 293.911861 -77.503079)
			(xy 293.90426 -77.521675) (xy 293.903908 -77.531722) (xy 293.903908 -79.8068) (xy 293.904328 -79.816821)
			(xy 293.911998 -79.835336) (xy 293.92617 -79.849507) (xy 293.944687 -79.857174) (xy 293.954708 -79.8576)
			(xy 294.237918 -79.8576) (xy 294.247987 -79.857173) (xy 294.266586 -79.849454) (xy 294.273986 -79.842614)
			(xy 295.996614 -78.119986) (xy 296.003468 -78.112591) (xy 296.01121 -78.093992) (xy 296.0116 -78.083918)
			(xy 296.0116 -76.482956) (xy 296.011554 -76.479085) (xy 296.010409 -76.471429) (xy 296.009314 -76.467716)
			(xy 295.989981 -76.404718) (xy 295.958113 -76.276837) (xy 295.934104 -76.147251) (xy 295.918042 -76.016441)
			(xy 295.909986 -75.884896) (xy 295.909492 -75.819) (xy 295.909991 -75.753104) (xy 295.918041 -75.621558)
			(xy 295.934099 -75.490748) (xy 295.958105 -75.36116) (xy 295.989969 -75.233278) (xy 296.009314 -75.170284)
			(xy 296.010377 -75.166564) (xy 296.011518 -75.158912) (xy 296.0116 -75.155044) (xy 296.0116 -68.702682)
			(xy 296.011173 -68.692613) (xy 296.003454 -68.674014) (xy 295.996614 -68.666614) (xy 294.121586 -66.791586)
			(xy 294.114191 -66.784732) (xy 294.095592 -66.77699) (xy 294.085518 -66.7766) (xy 283.6164 -66.7766)
			(xy 283.476446 -66.916554) (xy 283.476446 -68.186554) (xy 284.231842 -68.94195) (xy 285.266382 -68.94195)
			(xy 285.270453 -68.886328) (xy 285.282579 -68.831891) (xy 285.302502 -68.7798) (xy 285.329798 -68.731165)
			(xy 285.363884 -68.687022) (xy 285.404033 -68.648313) (xy 285.449391 -68.615862) (xy 285.498991 -68.590361)
			(xy 285.551775 -68.572354) (xy 285.606618 -68.562224) (xy 285.662352 -68.560187) (xy 285.717789 -68.566287)
			(xy 285.771746 -68.580393) (xy 285.823075 -68.602205) (xy 285.870681 -68.631259) (xy 285.913549 -68.666934)
			(xy 285.950766 -68.708471) (xy 285.981539 -68.754984) (xy 286.005211 -68.805481) (xy 286.021279 -68.858888)
			(xy 286.029399 -68.914064) (xy 286.029908 -68.94195) (xy 286.029399 -68.969836) (xy 286.021279 -69.025012)
			(xy 286.005211 -69.078419) (xy 285.981539 -69.128916) (xy 285.950766 -69.175429) (xy 285.913549 -69.216966)
			(xy 285.870681 -69.252641) (xy 285.823075 -69.281695) (xy 285.771746 -69.303507) (xy 285.717789 -69.317613)
			(xy 285.662352 -69.323713) (xy 285.606618 -69.321676) (xy 285.551775 -69.311546) (xy 285.498991 -69.293539)
			(xy 285.449391 -69.268038) (xy 285.404033 -69.235587) (xy 285.363884 -69.196878) (xy 285.329798 -69.152735)
			(xy 285.302502 -69.1041) (xy 285.282579 -69.052009) (xy 285.270453 -68.997572) (xy 285.266382 -68.94195)
			(xy 284.231842 -68.94195) (xy 285.711646 -70.421754) (xy 285.730236 -70.441049) (xy 285.761725 -70.484395)
			(xy 285.786043 -70.532135) (xy 285.80259 -70.583092) (xy 285.810959 -70.636011) (xy 285.811468 -70.6628)
			(xy 285.811468 -72.4408) (xy 285.810943 -72.467586) (xy 285.802564 -72.5205) (xy 285.786014 -72.571452)
			(xy 285.761698 -72.619188) (xy 285.730216 -72.662535) (xy 285.711646 -72.681846) (xy 285.248858 -73.14438)
			(xy 285.245048 -73.155048) (xy 285.23184 -73.186798) (xy 285.227268 -73.196958) (xy 285.227268 -73.243694)
			(xy 285.227713 -73.253724) (xy 285.235294 -73.272291) (xy 285.242 -73.279762) (xy 286.346646 -74.384154)
			(xy 286.365236 -74.403449) (xy 286.396725 -74.446795) (xy 286.421043 -74.494535) (xy 286.43759 -74.545492)
			(xy 286.445959 -74.598411) (xy 286.446468 -74.6252) (xy 286.446468 -79.1718) (xy 286.445943 -79.198586)
			(xy 286.437564 -79.2515) (xy 286.421014 -79.302452) (xy 286.396698 -79.350188) (xy 286.365216 -79.393535)
			(xy 286.346646 -79.412846) (xy 285.988252 -79.770986) (xy 285.981554 -79.778428) (xy 285.973947 -79.796928)
			(xy 285.973959 -79.81693) (xy 285.97733 -79.826358) (xy 285.983426 -79.840582) (xy 286.008572 -79.8576)
		)
		(stroke
			(width 0)
			(type solid)
		)
		(fill yes)
		(layer "F.Cu")
		(net "GND_FIELD_SIGNAL")
	)
	(gr_poly
		(pts
			(arc
				(start 75.000104 -171.141898)
				(mid 78.176421 -169.826225)
				(end 79.492094 -166.649908)
			)
			(arc
				(start 79.492094 -161.299906)
				(mid 80.519562 -158.81938)
				(end 83.000088 -157.791912)
			)
			(arc
				(start 83.49996 -157.791912)
				(mid 86.676277 -156.476239)
				(end 87.99195 -153.299922)
			)
			(arc
				(start 87.99195 -110.499906)
				(mid 90.337472 -104.83757)
				(end 95.999808 -102.492048)
			)
			(arc
				(start 344.000074 -102.492048)
				(mid 349.662485 -104.837495)
				(end 352.007932 -110.499906)
			)
			(arc
				(start 352.007932 -153.299922)
				(mid 353.323605 -156.476239)
				(end 356.499922 -157.791912)
			)
			(arc
				(start 357.000048 -157.791912)
				(mid 359.480574 -158.81938)
				(end 360.508042 -161.299906)
			)
			(arc
				(start 360.508042 -166.649908)
				(mid 361.823715 -169.826225)
				(end 365.000032 -171.141898)
			)
			(arc
				(start 403.999954 -171.141898)
				(mid 407.176271 -169.826225)
				(end 408.491944 -166.649908)
			)
			(arc
				(start 408.491944 -163.299902)
				(mid 410.105197 -159.405165)
				(end 413.999934 -157.791912)
			)
			(arc
				(start 434.999892 -157.791912)
				(mid 438.176209 -156.476239)
				(end 439.491882 -153.299922)
			)
			(arc
				(start 439.491882 -136.77011)
				(mid 441.105209 -132.875447)
				(end 444.999872 -131.26212)
			)
			(arc
				(start 471.000074 -131.26212)
				(mid 474.176391 -129.946447)
				(end 475.492064 -126.77013)
			)
			(arc
				(start 475.492064 -21.770086)
				(mid 474.176391 -18.593769)
				(end 471.000074 -17.278096)
			)
			(arc
				(start 444.999872 -17.278096)
				(mid 441.105209 -15.664769)
				(end 439.491882 -11.770106)
			)
			(arc
				(start 439.491882 -4.99999)
				(mid 438.176209 -1.823673)
				(end 434.999892 -0.508)
			)
			(xy 379.886972 -0.508) (xy 379.886972 -1.015746)
			(arc
				(start 434.999892 -1.015746)
				(mid 437.817178 -2.182704)
				(end 438.984136 -4.99999)
			)
			(arc
				(start 438.984136 -11.770106)
				(mid 440.746179 -16.023799)
				(end 444.999872 -17.785842)
			)
			(arc
				(start 471.000074 -17.785842)
				(mid 473.81736 -18.9528)
				(end 474.984318 -21.770086)
			)
			(arc
				(start 474.984318 -126.77013)
				(mid 473.81736 -129.587416)
				(end 471.000074 -130.754374)
			)
			(arc
				(start 444.999872 -130.754374)
				(mid 440.746179 -132.516417)
				(end 438.984136 -136.77011)
			)
			(arc
				(start 438.984136 -153.299922)
				(mid 437.817178 -156.117208)
				(end 434.999892 -157.284166)
			)
			(arc
				(start 413.999934 -157.284166)
				(mid 409.746166 -159.046134)
				(end 407.984198 -163.299902)
			)
			(arc
				(start 407.984198 -166.649908)
				(mid 406.81724 -169.467194)
				(end 403.999954 -170.634152)
			)
			(arc
				(start 365.000032 -170.634152)
				(mid 362.182746 -169.467194)
				(end 361.015788 -166.649908)
			)
			(arc
				(start 361.015788 -161.299906)
				(mid 359.839605 -158.460349)
				(end 357.000048 -157.284166)
			)
			(arc
				(start 356.499922 -157.284166)
				(mid 353.682636 -156.117208)
				(end 352.515678 -153.299922)
			)
			(arc
				(start 352.515678 -110.499906)
				(mid 350.021515 -104.478465)
				(end 344.000074 -101.984302)
			)
			(arc
				(start 95.999808 -101.984302)
				(mid 89.978441 -104.478539)
				(end 87.484204 -110.499906)
			)
			(arc
				(start 87.484204 -153.299922)
				(mid 86.317246 -156.117208)
				(end 83.49996 -157.284166)
			)
			(arc
				(start 83.000088 -157.284166)
				(mid 80.160531 -158.460349)
				(end 78.984348 -161.299906)
			)
			(arc
				(start 78.984348 -166.649908)
				(mid 77.81739 -169.467194)
				(end 75.000104 -170.634152)
			)
			(xy 39.108126 -170.634152) (xy 39.108126 -171.141898)
		)
		(stroke
			(width 0)
			(type solid)
		)
		(fill yes)
		(layer "F.Cu")
		(net "GND")
	)
	(gr_poly
		(pts
			(xy 37.524182 -169.321988) (xy 37.524182 -150.383494) (xy 37.987224 -149.920452) (xy 45.344842 -149.920452)
			(xy 45.713396 -150.289006) (xy 45.713396 -159.684433) (xy 71.513688 -159.684433) (xy 71.513688 -159.575787)
			(xy 71.521619 -159.46743) (xy 71.537438 -159.359941) (xy 71.561061 -159.253894) (xy 71.592362 -159.149854)
			(xy 71.631174 -159.048376) (xy 71.677289 -158.950002) (xy 71.730463 -158.855257) (xy 71.790411 -158.764646)
			(xy 71.856813 -158.678652) (xy 71.929315 -158.597735) (xy 72.00753 -158.522327) (xy 72.091041 -158.452828)
			(xy 72.179402 -158.389611) (xy 72.272142 -158.333013) (xy 72.368766 -158.283335) (xy 72.468758 -158.240843)
			(xy 72.571586 -158.205763) (xy 72.6767 -158.178283) (xy 72.783539 -158.158548) (xy 72.891534 -158.146665)
			(xy 73.000108 -158.142698) (xy 73.108682 -158.146665) (xy 73.216677 -158.158548) (xy 73.323516 -158.178283)
			(xy 73.42863 -158.205763) (xy 73.531458 -158.240843) (xy 73.63145 -158.283335) (xy 73.728074 -158.333013)
			(xy 73.820814 -158.389611) (xy 73.909175 -158.452828) (xy 73.992686 -158.522327) (xy 74.070901 -158.597735)
			(xy 74.143403 -158.678652) (xy 74.209805 -158.764646) (xy 74.269753 -158.855257) (xy 74.322927 -158.950002)
			(xy 74.369042 -159.048376) (xy 74.407854 -159.149854) (xy 74.439155 -159.253894) (xy 74.462778 -159.359941)
			(xy 74.478597 -159.46743) (xy 74.486528 -159.575787) (xy 74.487024 -159.63011) (xy 74.486528 -159.684433)
			(xy 74.478597 -159.79279) (xy 74.462778 -159.900279) (xy 74.439155 -160.006326) (xy 74.407854 -160.110366)
			(xy 74.369042 -160.211844) (xy 74.322927 -160.310218) (xy 74.269753 -160.404963) (xy 74.209805 -160.495574)
			(xy 74.143403 -160.581568) (xy 74.070901 -160.662485) (xy 73.992686 -160.737893) (xy 73.909175 -160.807392)
			(xy 73.820814 -160.870609) (xy 73.728074 -160.927207) (xy 73.63145 -160.976885) (xy 73.531458 -161.019377)
			(xy 73.42863 -161.054457) (xy 73.323516 -161.081937) (xy 73.216677 -161.101672) (xy 73.108682 -161.113555)
			(xy 73.000108 -161.117523) (xy 72.891534 -161.113555) (xy 72.783539 -161.101672) (xy 72.6767 -161.081937)
			(xy 72.571586 -161.054457) (xy 72.468758 -161.019377) (xy 72.368766 -160.976885) (xy 72.272142 -160.927207)
			(xy 72.179402 -160.870609) (xy 72.091041 -160.807392) (xy 72.00753 -160.737893) (xy 71.929315 -160.662485)
			(xy 71.856813 -160.581568) (xy 71.790411 -160.495574) (xy 71.730463 -160.404963) (xy 71.677289 -160.310218)
			(xy 71.631174 -160.211844) (xy 71.592362 -160.110366) (xy 71.561061 -160.006326) (xy 71.537438 -159.900279)
			(xy 71.521619 -159.79279) (xy 71.513688 -159.684433) (xy 45.713396 -159.684433) (xy 45.713396 -160.83915)
			(xy 46.545246 -161.671) (xy 51.495452 -161.671) (xy 51.520124 -161.623253) (xy 51.575512 -161.531139)
			(xy 51.637518 -161.443343) (xy 51.705806 -161.360339) (xy 51.780007 -161.282576) (xy 51.859721 -161.210474)
			(xy 51.944516 -161.144423) (xy 52.033934 -161.08478) (xy 52.127492 -161.031868) (xy 52.224685 -160.985971)
			(xy 52.324987 -160.947338) (xy 52.427856 -160.916179) (xy 52.532735 -160.892661) (xy 52.63906 -160.876911)
			(xy 52.746254 -160.869015) (xy 52.853738 -160.869015) (xy 52.960932 -160.876911) (xy 53.067257 -160.892661)
			(xy 53.172136 -160.916179) (xy 53.275005 -160.947338) (xy 53.375307 -160.985971) (xy 53.4725 -161.031868)
			(xy 53.566058 -161.08478) (xy 53.655476 -161.144423) (xy 53.740271 -161.210474) (xy 53.819985 -161.282576)
			(xy 53.894186 -161.360339) (xy 53.962474 -161.443343) (xy 54.02448 -161.531139) (xy 54.079868 -161.623253)
			(xy 54.10454 -161.671) (xy 77.337412 -161.671) (xy 77.432408 -161.576004) (xy 77.432408 -154.538934)
			(xy 73.467468 -150.573994) (xy 73.467468 -150.566882) (xy 73.185528 -150.284942) (xy 73.185528 -139.073382)
			(xy 76.431902 -135.827008) (xy 83.678522 -135.827008) (xy 85.09 -134.41553) (xy 85.09 -91.5924) (xy 102.068122 -74.614278)
			(xy 111.866172 -74.614278) (xy 111.873571 -74.607435) (xy 111.89217 -74.599714) (xy 111.90224 -74.599292)
			(xy 118.751096 -74.599292) (xy 118.957852 -74.392536) (xy 118.957852 -69.97319) (xy 118.68277 -69.698108)
			(xy 108.331508 -69.698108) (xy 108.077 -69.4436) (xy 108.077 -63.7032) (xy 108.443522 -63.336678)
			(xy 110.323122 -63.336678) (xy 110.338108 -63.321692) (xy 118.751096 -63.321692) (xy 118.957852 -63.114936)
			(xy 118.957852 -58.69559) (xy 118.68277 -58.420508) (xy 108.407708 -58.420508) (xy 108.077 -58.0898)
			(xy 108.077 -52.4256) (xy 108.443522 -52.059078) (xy 111.866172 -52.059078) (xy 111.873571 -52.052235)
			(xy 111.89217 -52.044514) (xy 111.90224 -52.044092) (xy 118.751096 -52.044092) (xy 118.957852 -51.837336)
			(xy 118.957852 -47.41799) (xy 118.68277 -47.142908) (xy 108.433108 -47.142908) (xy 108.0516 -46.7614)
			(xy 108.0516 -41.1226) (xy 108.392722 -40.781478) (xy 111.866172 -40.781478) (xy 111.873571 -40.774635)
			(xy 111.89217 -40.766914) (xy 111.90224 -40.766492) (xy 118.751096 -40.766492) (xy 118.957852 -40.559736)
			(xy 118.957852 -36.14039) (xy 118.68277 -35.865308) (xy 108.483908 -35.865308) (xy 108.0516 -35.433)
			(xy 108.0516 -29.9212) (xy 108.468922 -29.503878) (xy 111.866172 -29.503878) (xy 111.873571 -29.497035)
			(xy 111.89217 -29.489314) (xy 111.90224 -29.488892) (xy 118.751096 -29.488892) (xy 118.957852 -29.282136)
			(xy 118.957852 -24.86279) (xy 118.68277 -24.587708) (xy 108.560108 -24.587708) (xy 108.0516 -24.0792)
			(xy 108.0516 -18.542) (xy 108.4072 -18.1864) (xy 111.826294 -18.1864) (xy 111.851186 -18.211292)
			(xy 118.751096 -18.211292) (xy 118.957852 -18.004536) (xy 118.957852 -13.58519) (xy 118.68277 -13.310108)
			(xy 101.467666 -13.310108) (xy 99.719892 -13.310108) (xy 99.653852 -13.376148) (xy 99.653852 -15.10284)
			(xy 99.610926 -15.145766) (xy 90.493088 -24.263604) (xy 81.898998 -24.263604) (xy 72.126602 -34.036)
			(xy 61.117734 -34.036) (xy 60.24499 -34.908744) (xy 51.146456 -34.908744) (xy 50.292254 -35.762946)
			(xy 47.772574 -35.762946) (xy 47.31639 -35.306762) (xy 47.26163 -35.280758) (xy 47.155185 -35.222727)
			(xy 47.052645 -35.158045) (xy 46.954424 -35.086975) (xy 46.86092 -35.009805) (xy 46.772511 -34.926846)
			(xy 46.689555 -34.838434) (xy 46.612387 -34.744928) (xy 46.541321 -34.646705) (xy 46.476642 -34.544162)
			(xy 46.418614 -34.437715) (xy 46.392592 -34.382964) (xy 46.113446 -34.103818) (xy 38.613334 -34.103818)
			(xy 38.613334 -38.75405) (xy 36.638484 -40.7289) (xy 34.946336 -40.7289) (xy 34.946336 -42.3291)
			(xy 34.057082 -43.218354) (xy 34.057082 -45.7454) (xy 101.49739 -45.7454) (xy 101.501407 -45.613717)
			(xy 101.513445 -45.482524) (xy 101.533459 -45.352309) (xy 101.561374 -45.223556) (xy 101.597086 -45.096745)
			(xy 101.640463 -44.972347) (xy 101.691343 -44.850824) (xy 101.749537 -44.732629) (xy 101.814828 -44.618202)
			(xy 101.886974 -44.507968) (xy 101.965706 -44.402338) (xy 102.050731 -44.301704) (xy 102.141733 -44.20644)
			(xy 102.238373 -44.116901) (xy 102.340292 -44.033421) (xy 102.447111 -43.956309) (xy 102.558432 -43.885853)
			(xy 102.673842 -43.822314) (xy 102.79291 -43.76593) (xy 102.915195 -43.716909) (xy 103.04024 -43.675434)
			(xy 103.167581 -43.64166) (xy 103.296745 -43.615711) (xy 103.42725 -43.597686) (xy 103.558611 -43.58765)
			(xy 103.69034 -43.585641) (xy 103.821946 -43.591666) (xy 103.95294 -43.605703) (xy 104.082835 -43.627701)
			(xy 104.211147 -43.657576) (xy 104.337399 -43.695218) (xy 104.461121 -43.740487) (xy 104.581854 -43.793214)
			(xy 104.699147 -43.853204) (xy 104.812566 -43.920232) (xy 104.921686 -43.99405) (xy 105.026104 -44.074384)
			(xy 105.12543 -44.160934) (xy 105.219295 -44.253378) (xy 105.307349 -44.351372) (xy 105.389266 -44.454553)
			(xy 105.46474 -44.562535) (xy 105.53349 -44.674918) (xy 105.595261 -44.791283) (xy 105.649823 -44.911197)
			(xy 105.696974 -45.034215) (xy 105.736537 -45.159878) (xy 105.768365 -45.28772) (xy 105.792341 -45.417264)
			(xy 105.808374 -45.548029) (xy 105.816406 -45.679528) (xy 105.816908 -45.7454) (xy 105.816406 -45.811272)
			(xy 105.808374 -45.942771) (xy 105.792341 -46.073536) (xy 105.768365 -46.20308) (xy 105.736537 -46.330922)
			(xy 105.696974 -46.456585) (xy 105.649823 -46.579603) (xy 105.595261 -46.699517) (xy 105.53349 -46.815882)
			(xy 105.46474 -46.928265) (xy 105.389266 -47.036247) (xy 105.307349 -47.139428) (xy 105.219295 -47.237422)
			(xy 105.12543 -47.329866) (xy 105.026104 -47.416416) (xy 104.921686 -47.49675) (xy 104.812566 -47.570568)
			(xy 104.699147 -47.637596) (xy 104.581854 -47.697586) (xy 104.461121 -47.750313) (xy 104.337399 -47.795582)
			(xy 104.211147 -47.833224) (xy 104.082835 -47.863099) (xy 103.95294 -47.885097) (xy 103.821946 -47.899134)
			(xy 103.69034 -47.905159) (xy 103.558611 -47.90315) (xy 103.42725 -47.893114) (xy 103.296745 -47.875089)
			(xy 103.167581 -47.84914) (xy 103.04024 -47.815366) (xy 102.915195 -47.773891) (xy 102.79291 -47.72487)
			(xy 102.673842 -47.668486) (xy 102.558432 -47.604947) (xy 102.447111 -47.534491) (xy 102.340292 -47.457379)
			(xy 102.238373 -47.373899) (xy 102.141733 -47.28436) (xy 102.050731 -47.189096) (xy 101.965706 -47.088462)
			(xy 101.886974 -46.982832) (xy 101.814828 -46.872598) (xy 101.749537 -46.758171) (xy 101.691343 -46.639976)
			(xy 101.640463 -46.518453) (xy 101.597086 -46.394055) (xy 101.561374 -46.267244) (xy 101.533459 -46.138491)
			(xy 101.513445 -46.008276) (xy 101.501407 -45.877083) (xy 101.49739 -45.7454) (xy 34.057082 -45.7454)
			(xy 34.057082 -50.919888) (xy 39.568378 -50.919888) (xy 39.572407 -50.769861) (xy 39.584484 -50.620267)
			(xy 39.604573 -50.471537) (xy 39.632616 -50.324099) (xy 39.668533 -50.178379) (xy 39.712219 -50.034797)
			(xy 39.76355 -49.893767) (xy 39.822377 -49.755696) (xy 39.88853 -49.620981) (xy 39.961819 -49.490012)
			(xy 40.042032 -49.363165) (xy 40.128938 -49.240806) (xy 40.222287 -49.123289) (xy 40.321809 -49.010952)
			(xy 40.427217 -48.904119) (xy 40.538208 -48.803097) (xy 40.654462 -48.708179) (xy 40.775642 -48.619638)
			(xy 40.901401 -48.537729) (xy 41.031375 -48.462689) (xy 41.165189 -48.394733) (xy 41.302458 -48.334058)
			(xy 41.442786 -48.280839) (xy 41.585769 -48.235228) (xy 41.730993 -48.197359) (xy 41.878041 -48.167339)
			(xy 42.026489 -48.145255) (xy 42.175907 -48.131171) (xy 42.325866 -48.125128) (xy 42.475934 -48.127143)
			(xy 42.625677 -48.13721) (xy 42.774663 -48.1553) (xy 42.922464 -48.181361) (xy 43.068653 -48.215319)
			(xy 43.212809 -48.257074) (xy 43.354515 -48.306506) (xy 43.493364 -48.363474) (xy 43.628954 -48.427813)
			(xy 43.760896 -48.499337) (xy 43.888808 -48.57784) (xy 44.012323 -48.663095) (xy 44.131082 -48.754858)
			(xy 44.244746 -48.852863) (xy 44.352984 -48.956827) (xy 44.455487 -49.066452) (xy 44.551957 -49.181421)
			(xy 44.642117 -49.301402) (xy 44.725706 -49.42605) (xy 44.802485 -49.555004) (xy 44.872231 -49.687894)
			(xy 44.934744 -49.824337) (xy 44.989842 -49.963938) (xy 45.037368 -50.106295) (xy 45.077184 -50.250998)
			(xy 45.109176 -50.397629) (xy 45.13325 -50.545767) (xy 45.149339 -50.694983) (xy 45.157394 -50.844848)
			(xy 45.157898 -50.919888) (xy 59.126378 -50.919888) (xy 59.130407 -50.769861) (xy 59.142484 -50.620267)
			(xy 59.162573 -50.471537) (xy 59.190616 -50.324099) (xy 59.226533 -50.178379) (xy 59.270219 -50.034797)
			(xy 59.32155 -49.893767) (xy 59.380377 -49.755696) (xy 59.44653 -49.620981) (xy 59.519819 -49.490012)
			(xy 59.600032 -49.363165) (xy 59.686938 -49.240806) (xy 59.780287 -49.123289) (xy 59.879809 -49.010952)
			(xy 59.985217 -48.904119) (xy 60.096208 -48.803097) (xy 60.212462 -48.708179) (xy 60.333642 -48.619638)
			(xy 60.459401 -48.537729) (xy 60.589375 -48.462689) (xy 60.723189 -48.394733) (xy 60.860458 -48.334058)
			(xy 61.000786 -48.280839) (xy 61.143769 -48.235228) (xy 61.288993 -48.197359) (xy 61.436041 -48.167339)
			(xy 61.584489 -48.145255) (xy 61.733907 -48.131171) (xy 61.883866 -48.125128) (xy 62.033934 -48.127143)
			(xy 62.183677 -48.13721) (xy 62.332663 -48.1553) (xy 62.480464 -48.181361) (xy 62.626653 -48.215319)
			(xy 62.770809 -48.257074) (xy 62.912515 -48.306506) (xy 63.051364 -48.363474) (xy 63.186954 -48.427813)
			(xy 63.318896 -48.499337) (xy 63.446808 -48.57784) (xy 63.570323 -48.663095) (xy 63.689082 -48.754858)
			(xy 63.802746 -48.852863) (xy 63.910984 -48.956827) (xy 64.013487 -49.066452) (xy 64.109957 -49.181421)
			(xy 64.200117 -49.301402) (xy 64.283706 -49.42605) (xy 64.360485 -49.555004) (xy 64.430231 -49.687894)
			(xy 64.492744 -49.824337) (xy 64.547842 -49.963938) (xy 64.595368 -50.106295) (xy 64.635184 -50.250998)
			(xy 64.667176 -50.397629) (xy 64.69125 -50.545767) (xy 64.707339 -50.694983) (xy 64.715394 -50.844848)
			(xy 64.715898 -50.919888) (xy 64.715394 -50.994928) (xy 64.707339 -51.144793) (xy 64.69125 -51.294009)
			(xy 64.667176 -51.442147) (xy 64.635184 -51.588778) (xy 64.595368 -51.733481) (xy 64.547842 -51.875838)
			(xy 64.492744 -52.015439) (xy 64.430231 -52.151882) (xy 64.360485 -52.284772) (xy 64.283706 -52.413726)
			(xy 64.200117 -52.538374) (xy 64.109957 -52.658355) (xy 64.013487 -52.773324) (xy 63.910984 -52.882949)
			(xy 63.802746 -52.986913) (xy 63.689082 -53.084918) (xy 63.570323 -53.176681) (xy 63.446808 -53.261936)
			(xy 63.318896 -53.340439) (xy 63.186954 -53.411963) (xy 63.051364 -53.476302) (xy 62.912515 -53.53327)
			(xy 62.770809 -53.582702) (xy 62.626653 -53.624457) (xy 62.480464 -53.658415) (xy 62.332663 -53.684476)
			(xy 62.183677 -53.702566) (xy 62.033934 -53.712633) (xy 61.883866 -53.714648) (xy 61.733907 -53.708605)
			(xy 61.584489 -53.694521) (xy 61.436041 -53.672437) (xy 61.288993 -53.642417) (xy 61.143769 -53.604548)
			(xy 61.000786 -53.558937) (xy 60.860458 -53.505718) (xy 60.723189 -53.445043) (xy 60.589375 -53.377087)
			(xy 60.459401 -53.302047) (xy 60.333642 -53.220138) (xy 60.212462 -53.131597) (xy 60.096208 -53.036679)
			(xy 59.985217 -52.935657) (xy 59.879809 -52.828824) (xy 59.780287 -52.716487) (xy 59.686938 -52.59897)
			(xy 59.600032 -52.476611) (xy 59.519819 -52.349764) (xy 59.44653 -52.218795) (xy 59.380377 -52.08408)
			(xy 59.32155 -51.946009) (xy 59.270219 -51.804979) (xy 59.226533 -51.661397) (xy 59.190616 -51.515677)
			(xy 59.162573 -51.368239) (xy 59.142484 -51.219509) (xy 59.130407 -51.069915) (xy 59.126378 -50.919888)
			(xy 45.157898 -50.919888) (xy 45.157394 -50.994928) (xy 45.149339 -51.144793) (xy 45.13325 -51.294009)
			(xy 45.109176 -51.442147) (xy 45.077184 -51.588778) (xy 45.037368 -51.733481) (xy 44.989842 -51.875838)
			(xy 44.934744 -52.015439) (xy 44.872231 -52.151882) (xy 44.802485 -52.284772) (xy 44.725706 -52.413726)
			(xy 44.642117 -52.538374) (xy 44.551957 -52.658355) (xy 44.455487 -52.773324) (xy 44.352984 -52.882949)
			(xy 44.244746 -52.986913) (xy 44.131082 -53.084918) (xy 44.012323 -53.176681) (xy 43.888808 -53.261936)
			(xy 43.760896 -53.340439) (xy 43.628954 -53.411963) (xy 43.493364 -53.476302) (xy 43.354515 -53.53327)
			(xy 43.212809 -53.582702) (xy 43.068653 -53.624457) (xy 42.922464 -53.658415) (xy 42.774663 -53.684476)
			(xy 42.625677 -53.702566) (xy 42.475934 -53.712633) (xy 42.325866 -53.714648) (xy 42.175907 -53.708605)
			(xy 42.026489 -53.694521) (xy 41.878041 -53.672437) (xy 41.730993 -53.642417) (xy 41.585769 -53.604548)
			(xy 41.442786 -53.558937) (xy 41.302458 -53.505718) (xy 41.165189 -53.445043) (xy 41.031375 -53.377087)
			(xy 40.901401 -53.302047) (xy 40.775642 -53.220138) (xy 40.654462 -53.131597) (xy 40.538208 -53.036679)
			(xy 40.427217 -52.935657) (xy 40.321809 -52.828824) (xy 40.222287 -52.716487) (xy 40.128938 -52.59897)
			(xy 40.042032 -52.476611) (xy 39.961819 -52.349764) (xy 39.88853 -52.218795) (xy 39.822377 -52.08408)
			(xy 39.76355 -51.946009) (xy 39.712219 -51.804979) (xy 39.668533 -51.661397) (xy 39.632616 -51.515677)
			(xy 39.604573 -51.368239) (xy 39.584484 -51.219509) (xy 39.572407 -51.069915) (xy 39.568378 -50.919888)
			(xy 34.057082 -50.919888) (xy 34.057082 -57.023) (xy 101.49739 -57.023) (xy 101.501407 -56.891317)
			(xy 101.513445 -56.760124) (xy 101.533459 -56.629909) (xy 101.561374 -56.501156) (xy 101.597086 -56.374345)
			(xy 101.640463 -56.249947) (xy 101.691343 -56.128424) (xy 101.749537 -56.010229) (xy 101.814828 -55.895802)
			(xy 101.886974 -55.785568) (xy 101.965706 -55.679938) (xy 102.050731 -55.579304) (xy 102.141733 -55.48404)
			(xy 102.238373 -55.394501) (xy 102.340292 -55.311021) (xy 102.447111 -55.233909) (xy 102.558432 -55.163453)
			(xy 102.673842 -55.099914) (xy 102.79291 -55.04353) (xy 102.915195 -54.994509) (xy 103.04024 -54.953034)
			(xy 103.167581 -54.91926) (xy 103.296745 -54.893311) (xy 103.42725 -54.875286) (xy 103.558611 -54.86525)
			(xy 103.69034 -54.863241) (xy 103.821946 -54.869266) (xy 103.95294 -54.883303) (xy 104.082835 -54.905301)
			(xy 104.211147 -54.935176) (xy 104.337399 -54.972818) (xy 104.461121 -55.018087) (xy 104.581854 -55.070814)
			(xy 104.699147 -55.130804) (xy 104.812566 -55.197832) (xy 104.921686 -55.27165) (xy 105.026104 -55.351984)
			(xy 105.12543 -55.438534) (xy 105.219295 -55.530978) (xy 105.307349 -55.628972) (xy 105.389266 -55.732153)
			(xy 105.46474 -55.840135) (xy 105.53349 -55.952518) (xy 105.595261 -56.068883) (xy 105.649823 -56.188797)
			(xy 105.696974 -56.311815) (xy 105.736537 -56.437478) (xy 105.768365 -56.56532) (xy 105.792341 -56.694864)
			(xy 105.808374 -56.825629) (xy 105.816406 -56.957128) (xy 105.816908 -57.023) (xy 105.816406 -57.088872)
			(xy 105.808374 -57.220371) (xy 105.792341 -57.351136) (xy 105.768365 -57.48068) (xy 105.736537 -57.608522)
			(xy 105.696974 -57.734185) (xy 105.649823 -57.857203) (xy 105.595261 -57.977117) (xy 105.53349 -58.093482)
			(xy 105.46474 -58.205865) (xy 105.389266 -58.313847) (xy 105.307349 -58.417028) (xy 105.219295 -58.515022)
			(xy 105.12543 -58.607466) (xy 105.026104 -58.694016) (xy 104.921686 -58.77435) (xy 104.812566 -58.848168)
			(xy 104.699147 -58.915196) (xy 104.581854 -58.975186) (xy 104.461121 -59.027913) (xy 104.337399 -59.073182)
			(xy 104.211147 -59.110824) (xy 104.082835 -59.140699) (xy 103.95294 -59.162697) (xy 103.821946 -59.176734)
			(xy 103.69034 -59.182759) (xy 103.558611 -59.18075) (xy 103.42725 -59.170714) (xy 103.296745 -59.152689)
			(xy 103.167581 -59.12674) (xy 103.04024 -59.092966) (xy 102.915195 -59.051491) (xy 102.79291 -59.00247)
			(xy 102.673842 -58.946086) (xy 102.558432 -58.882547) (xy 102.447111 -58.812091) (xy 102.340292 -58.734979)
			(xy 102.238373 -58.651499) (xy 102.141733 -58.56196) (xy 102.050731 -58.466696) (xy 101.965706 -58.366062)
			(xy 101.886974 -58.260432) (xy 101.814828 -58.150198) (xy 101.749537 -58.035771) (xy 101.691343 -57.917576)
			(xy 101.640463 -57.796053) (xy 101.597086 -57.671655) (xy 101.561374 -57.544844) (xy 101.533459 -57.416091)
			(xy 101.513445 -57.285876) (xy 101.501407 -57.154683) (xy 101.49739 -57.023) (xy 34.057082 -57.023)
			(xy 34.057082 -59.309508) (xy 41.347136 -59.309508) (xy 41.347136 -57.531) (xy 41.347635 -57.514302)
			(xy 41.35627 -57.482043) (xy 41.372951 -57.453113) (xy 41.396546 -57.42948) (xy 41.425448 -57.41275)
			(xy 41.457693 -57.404063) (xy 41.47439 -57.403492) (xy 43.25239 -57.403492) (xy 43.269054 -57.403997)
			(xy 43.301249 -57.412612) (xy 43.330122 -57.429258) (xy 43.353708 -57.452804) (xy 43.370404 -57.481649)
			(xy 43.379075 -57.513829) (xy 43.379644 -57.530492) (xy 43.379644 -59.309) (xy 43.379626 -59.309508)
			(xy 60.905136 -59.309508) (xy 60.905136 -57.531) (xy 60.905635 -57.514302) (xy 60.91427 -57.482043)
			(xy 60.930951 -57.453113) (xy 60.954546 -57.42948) (xy 60.983448 -57.41275) (xy 61.015693 -57.404063)
			(xy 61.03239 -57.403492) (xy 62.81039 -57.403492) (xy 62.827054 -57.403997) (xy 62.859249 -57.412612)
			(xy 62.888122 -57.429258) (xy 62.911708 -57.452804) (xy 62.928404 -57.481649) (xy 62.937075 -57.513829)
			(xy 62.937644 -57.530492) (xy 62.937644 -59.309) (xy 62.937066 -59.325691) (xy 62.928438 -59.357939)
			(xy 62.911769 -59.386861) (xy 62.888192 -59.410492) (xy 62.859308 -59.427227) (xy 62.82708 -59.435928)
			(xy 62.81039 -59.436508) (xy 61.03239 -59.436508) (xy 61.015725 -59.436021) (xy 60.983529 -59.427401)
			(xy 60.954657 -59.41075) (xy 60.931071 -59.387201) (xy 60.914375 -59.358354) (xy 60.905705 -59.326172)
			(xy 60.905136 -59.309508) (xy 43.379626 -59.309508) (xy 43.379066 -59.325691) (xy 43.370438 -59.357939)
			(xy 43.353769 -59.386861) (xy 43.330192 -59.410492) (xy 43.301308 -59.427227) (xy 43.26908 -59.435928)
			(xy 43.25239 -59.436508) (xy 41.47439 -59.436508) (xy 41.457725 -59.436021) (xy 41.425529 -59.427401)
			(xy 41.396657 -59.41075) (xy 41.373071 -59.387201) (xy 41.356375 -59.358354) (xy 41.347705 -59.326172)
			(xy 41.347136 -59.309508) (xy 34.057082 -59.309508) (xy 34.057082 -71.239888) (xy 39.568378 -71.239888)
			(xy 39.572407 -71.089861) (xy 39.584484 -70.940267) (xy 39.604573 -70.791537) (xy 39.632616 -70.644099)
			(xy 39.668533 -70.498379) (xy 39.712219 -70.354797) (xy 39.76355 -70.213767) (xy 39.822377 -70.075696)
			(xy 39.88853 -69.940981) (xy 39.961819 -69.810012) (xy 40.042032 -69.683165) (xy 40.128938 -69.560806)
			(xy 40.222287 -69.443289) (xy 40.321809 -69.330952) (xy 40.427217 -69.224119) (xy 40.538208 -69.123097)
			(xy 40.654462 -69.028179) (xy 40.775642 -68.939638) (xy 40.901401 -68.857729) (xy 41.031375 -68.782689)
			(xy 41.165189 -68.714733) (xy 41.302458 -68.654058) (xy 41.442786 -68.600839) (xy 41.585769 -68.555228)
			(xy 41.730993 -68.517359) (xy 41.878041 -68.487339) (xy 42.026489 -68.465255) (xy 42.175907 -68.451171)
			(xy 42.325866 -68.445128) (xy 42.475934 -68.447143) (xy 42.625677 -68.45721) (xy 42.774663 -68.4753)
			(xy 42.922464 -68.501361) (xy 43.068653 -68.535319) (xy 43.212809 -68.577074) (xy 43.354515 -68.626506)
			(xy 43.493364 -68.683474) (xy 43.628954 -68.747813) (xy 43.760896 -68.819337) (xy 43.888808 -68.89784)
			(xy 44.012323 -68.983095) (xy 44.131082 -69.074858) (xy 44.244746 -69.172863) (xy 44.352984 -69.276827)
			(xy 44.455487 -69.386452) (xy 44.551957 -69.501421) (xy 44.642117 -69.621402) (xy 44.725706 -69.74605)
			(xy 44.802485 -69.875004) (xy 44.872231 -70.007894) (xy 44.934744 -70.144337) (xy 44.989842 -70.283938)
			(xy 45.037368 -70.426295) (xy 45.077184 -70.570998) (xy 45.109176 -70.717629) (xy 45.13325 -70.865767)
			(xy 45.149339 -71.014983) (xy 45.157394 -71.164848) (xy 45.157898 -71.239888) (xy 59.126378 -71.239888)
			(xy 59.130407 -71.089861) (xy 59.142484 -70.940267) (xy 59.162573 -70.791537) (xy 59.190616 -70.644099)
			(xy 59.226533 -70.498379) (xy 59.270219 -70.354797) (xy 59.32155 -70.213767) (xy 59.380377 -70.075696)
			(xy 59.44653 -69.940981) (xy 59.519819 -69.810012) (xy 59.600032 -69.683165) (xy 59.686938 -69.560806)
			(xy 59.780287 -69.443289) (xy 59.879809 -69.330952) (xy 59.985217 -69.224119) (xy 60.096208 -69.123097)
			(xy 60.212462 -69.028179) (xy 60.333642 -68.939638) (xy 60.459401 -68.857729) (xy 60.589375 -68.782689)
			(xy 60.723189 -68.714733) (xy 60.860458 -68.654058) (xy 61.000786 -68.600839) (xy 61.143769 -68.555228)
			(xy 61.288993 -68.517359) (xy 61.436041 -68.487339) (xy 61.584489 -68.465255) (xy 61.733907 -68.451171)
			(xy 61.883866 -68.445128) (xy 62.033934 -68.447143) (xy 62.183677 -68.45721) (xy 62.332663 -68.4753)
			(xy 62.480464 -68.501361) (xy 62.626653 -68.535319) (xy 62.770809 -68.577074) (xy 62.912515 -68.626506)
			(xy 63.051364 -68.683474) (xy 63.186954 -68.747813) (xy 63.318896 -68.819337) (xy 63.446808 -68.89784)
			(xy 63.570323 -68.983095) (xy 63.689082 -69.074858) (xy 63.802746 -69.172863) (xy 63.910984 -69.276827)
			(xy 64.013487 -69.386452) (xy 64.109957 -69.501421) (xy 64.200117 -69.621402) (xy 64.283706 -69.74605)
			(xy 64.360485 -69.875004) (xy 64.430231 -70.007894) (xy 64.492744 -70.144337) (xy 64.547842 -70.283938)
			(xy 64.595368 -70.426295) (xy 64.635184 -70.570998) (xy 64.667176 -70.717629) (xy 64.69125 -70.865767)
			(xy 64.707339 -71.014983) (xy 64.715394 -71.164848) (xy 64.715898 -71.239888) (xy 64.715394 -71.314928)
			(xy 64.707339 -71.464793) (xy 64.69125 -71.614009) (xy 64.667176 -71.762147) (xy 64.635184 -71.908778)
			(xy 64.595368 -72.053481) (xy 64.547842 -72.195838) (xy 64.492744 -72.335439) (xy 64.430231 -72.471882)
			(xy 64.360485 -72.604772) (xy 64.283706 -72.733726) (xy 64.200117 -72.858374) (xy 64.109957 -72.978355)
			(xy 64.013487 -73.093324) (xy 63.910984 -73.202949) (xy 63.802746 -73.306913) (xy 63.689082 -73.404918)
			(xy 63.570323 -73.496681) (xy 63.446808 -73.581936) (xy 63.318896 -73.660439) (xy 63.186954 -73.731963)
			(xy 63.051364 -73.796302) (xy 62.912515 -73.85327) (xy 62.770809 -73.902702) (xy 62.626653 -73.944457)
			(xy 62.480464 -73.978415) (xy 62.332663 -74.004476) (xy 62.183677 -74.022566) (xy 62.033934 -74.032633)
			(xy 61.883866 -74.034648) (xy 61.733907 -74.028605) (xy 61.584489 -74.014521) (xy 61.436041 -73.992437)
			(xy 61.288993 -73.962417) (xy 61.143769 -73.924548) (xy 61.000786 -73.878937) (xy 60.860458 -73.825718)
			(xy 60.723189 -73.765043) (xy 60.589375 -73.697087) (xy 60.459401 -73.622047) (xy 60.333642 -73.540138)
			(xy 60.212462 -73.451597) (xy 60.096208 -73.356679) (xy 59.985217 -73.255657) (xy 59.879809 -73.148824)
			(xy 59.780287 -73.036487) (xy 59.686938 -72.91897) (xy 59.600032 -72.796611) (xy 59.519819 -72.669764)
			(xy 59.44653 -72.538795) (xy 59.380377 -72.40408) (xy 59.32155 -72.266009) (xy 59.270219 -72.124979)
			(xy 59.226533 -71.981397) (xy 59.190616 -71.835677) (xy 59.162573 -71.688239) (xy 59.142484 -71.539509)
			(xy 59.130407 -71.389915) (xy 59.126378 -71.239888) (xy 45.157898 -71.239888) (xy 45.157394 -71.314928)
			(xy 45.149339 -71.464793) (xy 45.13325 -71.614009) (xy 45.109176 -71.762147) (xy 45.077184 -71.908778)
			(xy 45.037368 -72.053481) (xy 44.989842 -72.195838) (xy 44.934744 -72.335439) (xy 44.872231 -72.471882)
			(xy 44.802485 -72.604772) (xy 44.725706 -72.733726) (xy 44.642117 -72.858374) (xy 44.551957 -72.978355)
			(xy 44.455487 -73.093324) (xy 44.352984 -73.202949) (xy 44.244746 -73.306913) (xy 44.131082 -73.404918)
			(xy 44.012323 -73.496681) (xy 43.888808 -73.581936) (xy 43.760896 -73.660439) (xy 43.628954 -73.731963)
			(xy 43.493364 -73.796302) (xy 43.354515 -73.85327) (xy 43.212809 -73.902702) (xy 43.068653 -73.944457)
			(xy 42.922464 -73.978415) (xy 42.774663 -74.004476) (xy 42.625677 -74.022566) (xy 42.475934 -74.032633)
			(xy 42.325866 -74.034648) (xy 42.175907 -74.028605) (xy 42.026489 -74.014521) (xy 41.878041 -73.992437)
			(xy 41.730993 -73.962417) (xy 41.585769 -73.924548) (xy 41.442786 -73.878937) (xy 41.302458 -73.825718)
			(xy 41.165189 -73.765043) (xy 41.031375 -73.697087) (xy 40.901401 -73.622047) (xy 40.775642 -73.540138)
			(xy 40.654462 -73.451597) (xy 40.538208 -73.356679) (xy 40.427217 -73.255657) (xy 40.321809 -73.148824)
			(xy 40.222287 -73.036487) (xy 40.128938 -72.91897) (xy 40.042032 -72.796611) (xy 39.961819 -72.669764)
			(xy 39.88853 -72.538795) (xy 39.822377 -72.40408) (xy 39.76355 -72.266009) (xy 39.712219 -72.124979)
			(xy 39.668533 -71.981397) (xy 39.632616 -71.835677) (xy 39.604573 -71.688239) (xy 39.584484 -71.539509)
			(xy 39.572407 -71.389915) (xy 39.568378 -71.239888) (xy 34.057082 -71.239888) (xy 34.057082 -79.629508)
			(xy 41.347136 -79.629508) (xy 41.347136 -77.851) (xy 41.347635 -77.834302) (xy 41.35627 -77.802043)
			(xy 41.372951 -77.773113) (xy 41.396546 -77.74948) (xy 41.425448 -77.73275) (xy 41.457693 -77.724063)
			(xy 41.47439 -77.723492) (xy 43.25239 -77.723492) (xy 43.269054 -77.723997) (xy 43.301249 -77.732612)
			(xy 43.330122 -77.749258) (xy 43.353708 -77.772804) (xy 43.370404 -77.801649) (xy 43.379075 -77.833829)
			(xy 43.379644 -77.850492) (xy 43.379644 -79.629) (xy 43.379626 -79.629508) (xy 60.905136 -79.629508)
			(xy 60.905136 -77.851) (xy 60.905635 -77.834302) (xy 60.91427 -77.802043) (xy 60.930951 -77.773113)
			(xy 60.954546 -77.74948) (xy 60.983448 -77.73275) (xy 61.015693 -77.724063) (xy 61.03239 -77.723492)
			(xy 62.81039 -77.723492) (xy 62.827054 -77.723997) (xy 62.859249 -77.732612) (xy 62.888122 -77.749258)
			(xy 62.911708 -77.772804) (xy 62.928404 -77.801649) (xy 62.937075 -77.833829) (xy 62.937644 -77.850492)
			(xy 62.937644 -79.629) (xy 62.937066 -79.645691) (xy 62.928438 -79.677939) (xy 62.911769 -79.706861)
			(xy 62.888192 -79.730492) (xy 62.859308 -79.747227) (xy 62.82708 -79.755928) (xy 62.81039 -79.756508)
			(xy 61.03239 -79.756508) (xy 61.015725 -79.756021) (xy 60.983529 -79.747401) (xy 60.954657 -79.73075)
			(xy 60.931071 -79.707201) (xy 60.914375 -79.678354) (xy 60.905705 -79.646172) (xy 60.905136 -79.629508)
			(xy 43.379626 -79.629508) (xy 43.379066 -79.645691) (xy 43.370438 -79.677939) (xy 43.353769 -79.706861)
			(xy 43.330192 -79.730492) (xy 43.301308 -79.747227) (xy 43.26908 -79.755928) (xy 43.25239 -79.756508)
			(xy 41.47439 -79.756508) (xy 41.457725 -79.756021) (xy 41.425529 -79.747401) (xy 41.396657 -79.73075)
			(xy 41.373071 -79.707201) (xy 41.356375 -79.678354) (xy 41.347705 -79.646172) (xy 41.347136 -79.629508)
			(xy 34.057082 -79.629508) (xy 34.057082 -91.559888) (xy 39.568378 -91.559888) (xy 39.572407 -91.409861)
			(xy 39.584484 -91.260267) (xy 39.604573 -91.111537) (xy 39.632616 -90.964099) (xy 39.668533 -90.818379)
			(xy 39.712219 -90.674797) (xy 39.76355 -90.533767) (xy 39.822377 -90.395696) (xy 39.88853 -90.260981)
			(xy 39.961819 -90.130012) (xy 40.042032 -90.003165) (xy 40.128938 -89.880806) (xy 40.222287 -89.763289)
			(xy 40.321809 -89.650952) (xy 40.427217 -89.544119) (xy 40.538208 -89.443097) (xy 40.654462 -89.348179)
			(xy 40.775642 -89.259638) (xy 40.901401 -89.177729) (xy 41.031375 -89.102689) (xy 41.165189 -89.034733)
			(xy 41.302458 -88.974058) (xy 41.442786 -88.920839) (xy 41.585769 -88.875228) (xy 41.730993 -88.837359)
			(xy 41.878041 -88.807339) (xy 42.026489 -88.785255) (xy 42.175907 -88.771171) (xy 42.325866 -88.765128)
			(xy 42.475934 -88.767143) (xy 42.625677 -88.77721) (xy 42.774663 -88.7953) (xy 42.922464 -88.821361)
			(xy 43.068653 -88.855319) (xy 43.212809 -88.897074) (xy 43.354515 -88.946506) (xy 43.493364 -89.003474)
			(xy 43.628954 -89.067813) (xy 43.760896 -89.139337) (xy 43.888808 -89.21784) (xy 44.012323 -89.303095)
			(xy 44.131082 -89.394858) (xy 44.244746 -89.492863) (xy 44.352984 -89.596827) (xy 44.455487 -89.706452)
			(xy 44.551957 -89.821421) (xy 44.642117 -89.941402) (xy 44.725706 -90.06605) (xy 44.802485 -90.195004)
			(xy 44.872231 -90.327894) (xy 44.934744 -90.464337) (xy 44.989842 -90.603938) (xy 45.037368 -90.746295)
			(xy 45.077184 -90.890998) (xy 45.109176 -91.037629) (xy 45.13325 -91.185767) (xy 45.149339 -91.334983)
			(xy 45.157394 -91.484848) (xy 45.157898 -91.559888) (xy 59.126378 -91.559888) (xy 59.130407 -91.409861)
			(xy 59.142484 -91.260267) (xy 59.162573 -91.111537) (xy 59.190616 -90.964099) (xy 59.226533 -90.818379)
			(xy 59.270219 -90.674797) (xy 59.32155 -90.533767) (xy 59.380377 -90.395696) (xy 59.44653 -90.260981)
			(xy 59.519819 -90.130012) (xy 59.600032 -90.003165) (xy 59.686938 -89.880806) (xy 59.780287 -89.763289)
			(xy 59.879809 -89.650952) (xy 59.985217 -89.544119) (xy 60.096208 -89.443097) (xy 60.212462 -89.348179)
			(xy 60.333642 -89.259638) (xy 60.459401 -89.177729) (xy 60.589375 -89.102689) (xy 60.723189 -89.034733)
			(xy 60.860458 -88.974058) (xy 61.000786 -88.920839) (xy 61.143769 -88.875228) (xy 61.288993 -88.837359)
			(xy 61.436041 -88.807339) (xy 61.584489 -88.785255) (xy 61.733907 -88.771171) (xy 61.883866 -88.765128)
			(xy 62.033934 -88.767143) (xy 62.183677 -88.77721) (xy 62.332663 -88.7953) (xy 62.480464 -88.821361)
			(xy 62.626653 -88.855319) (xy 62.770809 -88.897074) (xy 62.912515 -88.946506) (xy 63.051364 -89.003474)
			(xy 63.186954 -89.067813) (xy 63.318896 -89.139337) (xy 63.446808 -89.21784) (xy 63.570323 -89.303095)
			(xy 63.689082 -89.394858) (xy 63.802746 -89.492863) (xy 63.910984 -89.596827) (xy 64.013487 -89.706452)
			(xy 64.109957 -89.821421) (xy 64.200117 -89.941402) (xy 64.283706 -90.06605) (xy 64.360485 -90.195004)
			(xy 64.430231 -90.327894) (xy 64.492744 -90.464337) (xy 64.547842 -90.603938) (xy 64.595368 -90.746295)
			(xy 64.635184 -90.890998) (xy 64.667176 -91.037629) (xy 64.69125 -91.185767) (xy 64.707339 -91.334983)
			(xy 64.715394 -91.484848) (xy 64.715898 -91.559888) (xy 64.715394 -91.634928) (xy 64.707339 -91.784793)
			(xy 64.69125 -91.934009) (xy 64.667176 -92.082147) (xy 64.635184 -92.228778) (xy 64.595368 -92.373481)
			(xy 64.547842 -92.515838) (xy 64.492744 -92.655439) (xy 64.430231 -92.791882) (xy 64.360485 -92.924772)
			(xy 64.283706 -93.053726) (xy 64.200117 -93.178374) (xy 64.109957 -93.298355) (xy 64.013487 -93.413324)
			(xy 63.910984 -93.522949) (xy 63.802746 -93.626913) (xy 63.689082 -93.724918) (xy 63.570323 -93.816681)
			(xy 63.446808 -93.901936) (xy 63.318896 -93.980439) (xy 63.186954 -94.051963) (xy 63.051364 -94.116302)
			(xy 62.912515 -94.17327) (xy 62.770809 -94.222702) (xy 62.626653 -94.264457) (xy 62.480464 -94.298415)
			(xy 62.332663 -94.324476) (xy 62.183677 -94.342566) (xy 62.033934 -94.352633) (xy 61.883866 -94.354648)
			(xy 61.733907 -94.348605) (xy 61.584489 -94.334521) (xy 61.436041 -94.312437) (xy 61.288993 -94.282417)
			(xy 61.143769 -94.244548) (xy 61.000786 -94.198937) (xy 60.860458 -94.145718) (xy 60.723189 -94.085043)
			(xy 60.589375 -94.017087) (xy 60.459401 -93.942047) (xy 60.333642 -93.860138) (xy 60.212462 -93.771597)
			(xy 60.096208 -93.676679) (xy 59.985217 -93.575657) (xy 59.879809 -93.468824) (xy 59.780287 -93.356487)
			(xy 59.686938 -93.23897) (xy 59.600032 -93.116611) (xy 59.519819 -92.989764) (xy 59.44653 -92.858795)
			(xy 59.380377 -92.72408) (xy 59.32155 -92.586009) (xy 59.270219 -92.444979) (xy 59.226533 -92.301397)
			(xy 59.190616 -92.155677) (xy 59.162573 -92.008239) (xy 59.142484 -91.859509) (xy 59.130407 -91.709915)
			(xy 59.126378 -91.559888) (xy 45.157898 -91.559888) (xy 45.157394 -91.634928) (xy 45.149339 -91.784793)
			(xy 45.13325 -91.934009) (xy 45.109176 -92.082147) (xy 45.077184 -92.228778) (xy 45.037368 -92.373481)
			(xy 44.989842 -92.515838) (xy 44.934744 -92.655439) (xy 44.872231 -92.791882) (xy 44.802485 -92.924772)
			(xy 44.725706 -93.053726) (xy 44.642117 -93.178374) (xy 44.551957 -93.298355) (xy 44.455487 -93.413324)
			(xy 44.352984 -93.522949) (xy 44.244746 -93.626913) (xy 44.131082 -93.724918) (xy 44.012323 -93.816681)
			(xy 43.888808 -93.901936) (xy 43.760896 -93.980439) (xy 43.628954 -94.051963) (xy 43.493364 -94.116302)
			(xy 43.354515 -94.17327) (xy 43.212809 -94.222702) (xy 43.068653 -94.264457) (xy 42.922464 -94.298415)
			(xy 42.774663 -94.324476) (xy 42.625677 -94.342566) (xy 42.475934 -94.352633) (xy 42.325866 -94.354648)
			(xy 42.175907 -94.348605) (xy 42.026489 -94.334521) (xy 41.878041 -94.312437) (xy 41.730993 -94.282417)
			(xy 41.585769 -94.244548) (xy 41.442786 -94.198937) (xy 41.302458 -94.145718) (xy 41.165189 -94.085043)
			(xy 41.031375 -94.017087) (xy 40.901401 -93.942047) (xy 40.775642 -93.860138) (xy 40.654462 -93.771597)
			(xy 40.538208 -93.676679) (xy 40.427217 -93.575657) (xy 40.321809 -93.468824) (xy 40.222287 -93.356487)
			(xy 40.128938 -93.23897) (xy 40.042032 -93.116611) (xy 39.961819 -92.989764) (xy 39.88853 -92.858795)
			(xy 39.822377 -92.72408) (xy 39.76355 -92.586009) (xy 39.712219 -92.444979) (xy 39.668533 -92.301397)
			(xy 39.632616 -92.155677) (xy 39.604573 -92.008239) (xy 39.584484 -91.859509) (xy 39.572407 -91.709915)
			(xy 39.568378 -91.559888) (xy 34.057082 -91.559888) (xy 34.057082 -99.949508) (xy 41.347136 -99.949508)
			(xy 41.347136 -98.171) (xy 41.347635 -98.154302) (xy 41.35627 -98.122043) (xy 41.372951 -98.093113)
			(xy 41.396546 -98.06948) (xy 41.425448 -98.05275) (xy 41.457693 -98.044063) (xy 41.47439 -98.043492)
			(xy 43.25239 -98.043492) (xy 43.269054 -98.043997) (xy 43.301249 -98.052612) (xy 43.330122 -98.069258)
			(xy 43.353708 -98.092804) (xy 43.370404 -98.121649) (xy 43.379075 -98.153829) (xy 43.379644 -98.170492)
			(xy 43.379644 -99.949) (xy 43.379626 -99.949508) (xy 60.905136 -99.949508) (xy 60.905136 -98.171)
			(xy 60.905635 -98.154302) (xy 60.91427 -98.122043) (xy 60.930951 -98.093113) (xy 60.954546 -98.06948)
			(xy 60.983448 -98.05275) (xy 61.015693 -98.044063) (xy 61.03239 -98.043492) (xy 62.81039 -98.043492)
			(xy 62.827054 -98.043997) (xy 62.859249 -98.052612) (xy 62.888122 -98.069258) (xy 62.911708 -98.092804)
			(xy 62.928404 -98.121649) (xy 62.937075 -98.153829) (xy 62.937644 -98.170492) (xy 62.937644 -99.949)
			(xy 62.937066 -99.965691) (xy 62.928438 -99.997939) (xy 62.911769 -100.026861) (xy 62.888192 -100.050492)
			(xy 62.859308 -100.067227) (xy 62.82708 -100.075928) (xy 62.81039 -100.076508) (xy 61.03239 -100.076508)
			(xy 61.015725 -100.076021) (xy 60.983529 -100.067401) (xy 60.954657 -100.05075) (xy 60.931071 -100.027201)
			(xy 60.914375 -99.998354) (xy 60.905705 -99.966172) (xy 60.905136 -99.949508) (xy 43.379626 -99.949508)
			(xy 43.379066 -99.965691) (xy 43.370438 -99.997939) (xy 43.353769 -100.026861) (xy 43.330192 -100.050492)
			(xy 43.301308 -100.067227) (xy 43.26908 -100.075928) (xy 43.25239 -100.076508) (xy 41.47439 -100.076508)
			(xy 41.457725 -100.076021) (xy 41.425529 -100.067401) (xy 41.396657 -100.05075) (xy 41.373071 -100.027201)
			(xy 41.356375 -99.998354) (xy 41.347705 -99.966172) (xy 41.347136 -99.949508) (xy 34.057082 -99.949508)
			(xy 34.057082 -111.879888) (xy 39.568378 -111.879888) (xy 39.572407 -111.729861) (xy 39.584484 -111.580267)
			(xy 39.604573 -111.431537) (xy 39.632616 -111.284099) (xy 39.668533 -111.138379) (xy 39.712219 -110.994797)
			(xy 39.76355 -110.853767) (xy 39.822377 -110.715696) (xy 39.88853 -110.580981) (xy 39.961819 -110.450012)
			(xy 40.042032 -110.323165) (xy 40.128938 -110.200806) (xy 40.222287 -110.083289) (xy 40.321809 -109.970952)
			(xy 40.427217 -109.864119) (xy 40.538208 -109.763097) (xy 40.654462 -109.668179) (xy 40.775642 -109.579638)
			(xy 40.901401 -109.497729) (xy 41.031375 -109.422689) (xy 41.165189 -109.354733) (xy 41.302458 -109.294058)
			(xy 41.442786 -109.240839) (xy 41.585769 -109.195228) (xy 41.730993 -109.157359) (xy 41.878041 -109.127339)
			(xy 42.026489 -109.105255) (xy 42.175907 -109.091171) (xy 42.325866 -109.085128) (xy 42.475934 -109.087143)
			(xy 42.625677 -109.09721) (xy 42.774663 -109.1153) (xy 42.922464 -109.141361) (xy 43.068653 -109.175319)
			(xy 43.212809 -109.217074) (xy 43.354515 -109.266506) (xy 43.493364 -109.323474) (xy 43.628954 -109.387813)
			(xy 43.760896 -109.459337) (xy 43.888808 -109.53784) (xy 44.012323 -109.623095) (xy 44.131082 -109.714858)
			(xy 44.244746 -109.812863) (xy 44.352984 -109.916827) (xy 44.455487 -110.026452) (xy 44.551957 -110.141421)
			(xy 44.642117 -110.261402) (xy 44.725706 -110.38605) (xy 44.802485 -110.515004) (xy 44.872231 -110.647894)
			(xy 44.934744 -110.784337) (xy 44.989842 -110.923938) (xy 45.037368 -111.066295) (xy 45.077184 -111.210998)
			(xy 45.109176 -111.357629) (xy 45.13325 -111.505767) (xy 45.149339 -111.654983) (xy 45.157394 -111.804848)
			(xy 45.157898 -111.879888) (xy 59.126378 -111.879888) (xy 59.130407 -111.729861) (xy 59.142484 -111.580267)
			(xy 59.162573 -111.431537) (xy 59.190616 -111.284099) (xy 59.226533 -111.138379) (xy 59.270219 -110.994797)
			(xy 59.32155 -110.853767) (xy 59.380377 -110.715696) (xy 59.44653 -110.580981) (xy 59.519819 -110.450012)
			(xy 59.600032 -110.323165) (xy 59.686938 -110.200806) (xy 59.780287 -110.083289) (xy 59.879809 -109.970952)
			(xy 59.985217 -109.864119) (xy 60.096208 -109.763097) (xy 60.212462 -109.668179) (xy 60.333642 -109.579638)
			(xy 60.459401 -109.497729) (xy 60.589375 -109.422689) (xy 60.723189 -109.354733) (xy 60.860458 -109.294058)
			(xy 61.000786 -109.240839) (xy 61.143769 -109.195228) (xy 61.288993 -109.157359) (xy 61.436041 -109.127339)
			(xy 61.584489 -109.105255) (xy 61.733907 -109.091171) (xy 61.883866 -109.085128) (xy 62.033934 -109.087143)
			(xy 62.183677 -109.09721) (xy 62.332663 -109.1153) (xy 62.480464 -109.141361) (xy 62.626653 -109.175319)
			(xy 62.770809 -109.217074) (xy 62.912515 -109.266506) (xy 63.051364 -109.323474) (xy 63.186954 -109.387813)
			(xy 63.318896 -109.459337) (xy 63.446808 -109.53784) (xy 63.570323 -109.623095) (xy 63.689082 -109.714858)
			(xy 63.802746 -109.812863) (xy 63.910984 -109.916827) (xy 64.013487 -110.026452) (xy 64.109957 -110.141421)
			(xy 64.200117 -110.261402) (xy 64.283706 -110.38605) (xy 64.360485 -110.515004) (xy 64.430231 -110.647894)
			(xy 64.492744 -110.784337) (xy 64.547842 -110.923938) (xy 64.595368 -111.066295) (xy 64.635184 -111.210998)
			(xy 64.667176 -111.357629) (xy 64.69125 -111.505767) (xy 64.707339 -111.654983) (xy 64.715394 -111.804848)
			(xy 64.715898 -111.879888) (xy 64.715394 -111.954928) (xy 64.707339 -112.104793) (xy 64.69125 -112.254009)
			(xy 64.667176 -112.402147) (xy 64.635184 -112.548778) (xy 64.595368 -112.693481) (xy 64.547842 -112.835838)
			(xy 64.492744 -112.975439) (xy 64.430231 -113.111882) (xy 64.360485 -113.244772) (xy 64.283706 -113.373726)
			(xy 64.200117 -113.498374) (xy 64.109957 -113.618355) (xy 64.013487 -113.733324) (xy 63.910984 -113.842949)
			(xy 63.802746 -113.946913) (xy 63.689082 -114.044918) (xy 63.570323 -114.136681) (xy 63.446808 -114.221936)
			(xy 63.318896 -114.300439) (xy 63.186954 -114.371963) (xy 63.051364 -114.436302) (xy 62.912515 -114.49327)
			(xy 62.770809 -114.542702) (xy 62.626653 -114.584457) (xy 62.480464 -114.618415) (xy 62.332663 -114.644476)
			(xy 62.183677 -114.662566) (xy 62.033934 -114.672633) (xy 61.883866 -114.674648) (xy 61.733907 -114.668605)
			(xy 61.584489 -114.654521) (xy 61.436041 -114.632437) (xy 61.288993 -114.602417) (xy 61.143769 -114.564548)
			(xy 61.000786 -114.518937) (xy 60.860458 -114.465718) (xy 60.723189 -114.405043) (xy 60.589375 -114.337087)
			(xy 60.459401 -114.262047) (xy 60.333642 -114.180138) (xy 60.212462 -114.091597) (xy 60.096208 -113.996679)
			(xy 59.985217 -113.895657) (xy 59.879809 -113.788824) (xy 59.780287 -113.676487) (xy 59.686938 -113.55897)
			(xy 59.600032 -113.436611) (xy 59.519819 -113.309764) (xy 59.44653 -113.178795) (xy 59.380377 -113.04408)
			(xy 59.32155 -112.906009) (xy 59.270219 -112.764979) (xy 59.226533 -112.621397) (xy 59.190616 -112.475677)
			(xy 59.162573 -112.328239) (xy 59.142484 -112.179509) (xy 59.130407 -112.029915) (xy 59.126378 -111.879888)
			(xy 45.157898 -111.879888) (xy 45.157394 -111.954928) (xy 45.149339 -112.104793) (xy 45.13325 -112.254009)
			(xy 45.109176 -112.402147) (xy 45.077184 -112.548778) (xy 45.037368 -112.693481) (xy 44.989842 -112.835838)
			(xy 44.934744 -112.975439) (xy 44.872231 -113.111882) (xy 44.802485 -113.244772) (xy 44.725706 -113.373726)
			(xy 44.642117 -113.498374) (xy 44.551957 -113.618355) (xy 44.455487 -113.733324) (xy 44.352984 -113.842949)
			(xy 44.244746 -113.946913) (xy 44.131082 -114.044918) (xy 44.012323 -114.136681) (xy 43.888808 -114.221936)
			(xy 43.760896 -114.300439) (xy 43.628954 -114.371963) (xy 43.493364 -114.436302) (xy 43.354515 -114.49327)
			(xy 43.212809 -114.542702) (xy 43.068653 -114.584457) (xy 42.922464 -114.618415) (xy 42.774663 -114.644476)
			(xy 42.625677 -114.662566) (xy 42.475934 -114.672633) (xy 42.325866 -114.674648) (xy 42.175907 -114.668605)
			(xy 42.026489 -114.654521) (xy 41.878041 -114.632437) (xy 41.730993 -114.602417) (xy 41.585769 -114.564548)
			(xy 41.442786 -114.518937) (xy 41.302458 -114.465718) (xy 41.165189 -114.405043) (xy 41.031375 -114.337087)
			(xy 40.901401 -114.262047) (xy 40.775642 -114.180138) (xy 40.654462 -114.091597) (xy 40.538208 -113.996679)
			(xy 40.427217 -113.895657) (xy 40.321809 -113.788824) (xy 40.222287 -113.676487) (xy 40.128938 -113.55897)
			(xy 40.042032 -113.436611) (xy 39.961819 -113.309764) (xy 39.88853 -113.178795) (xy 39.822377 -113.04408)
			(xy 39.76355 -112.906009) (xy 39.712219 -112.764979) (xy 39.668533 -112.621397) (xy 39.632616 -112.475677)
			(xy 39.604573 -112.328239) (xy 39.584484 -112.179509) (xy 39.572407 -112.029915) (xy 39.568378 -111.879888)
			(xy 34.057082 -111.879888) (xy 34.057082 -120.269508) (xy 41.347136 -120.269508) (xy 41.347136 -118.491)
			(xy 41.347635 -118.474302) (xy 41.35627 -118.442043) (xy 41.372951 -118.413113) (xy 41.396546 -118.38948)
			(xy 41.425448 -118.37275) (xy 41.457693 -118.364063) (xy 41.47439 -118.363492) (xy 43.25239 -118.363492)
			(xy 43.269054 -118.363997) (xy 43.301249 -118.372612) (xy 43.330122 -118.389258) (xy 43.353708 -118.412804)
			(xy 43.370404 -118.441649) (xy 43.379075 -118.473829) (xy 43.379644 -118.490492) (xy 43.379644 -120.269)
			(xy 43.379626 -120.269508) (xy 60.905136 -120.269508) (xy 60.905136 -118.491) (xy 60.905635 -118.474302)
			(xy 60.91427 -118.442043) (xy 60.930951 -118.413113) (xy 60.954546 -118.38948) (xy 60.983448 -118.37275)
			(xy 61.015693 -118.364063) (xy 61.03239 -118.363492) (xy 62.81039 -118.363492) (xy 62.827054 -118.363997)
			(xy 62.859249 -118.372612) (xy 62.888122 -118.389258) (xy 62.911708 -118.412804) (xy 62.928404 -118.441649)
			(xy 62.937075 -118.473829) (xy 62.937644 -118.490492) (xy 62.937644 -120.269) (xy 62.937066 -120.285691)
			(xy 62.928438 -120.317939) (xy 62.911769 -120.346861) (xy 62.888192 -120.370492) (xy 62.859308 -120.387227)
			(xy 62.82708 -120.395928) (xy 62.81039 -120.396508) (xy 61.03239 -120.396508) (xy 61.015725 -120.396021)
			(xy 60.983529 -120.387401) (xy 60.954657 -120.37075) (xy 60.931071 -120.347201) (xy 60.914375 -120.318354)
			(xy 60.905705 -120.286172) (xy 60.905136 -120.269508) (xy 43.379626 -120.269508) (xy 43.379066 -120.285691)
			(xy 43.370438 -120.317939) (xy 43.353769 -120.346861) (xy 43.330192 -120.370492) (xy 43.301308 -120.387227)
			(xy 43.26908 -120.395928) (xy 43.25239 -120.396508) (xy 41.47439 -120.396508) (xy 41.457725 -120.396021)
			(xy 41.425529 -120.387401) (xy 41.396657 -120.37075) (xy 41.373071 -120.347201) (xy 41.356375 -120.318354)
			(xy 41.347705 -120.286172) (xy 41.347136 -120.269508) (xy 34.057082 -120.269508) (xy 34.057082 -132.199888)
			(xy 39.568378 -132.199888) (xy 39.572407 -132.049861) (xy 39.584484 -131.900267) (xy 39.604573 -131.751537)
			(xy 39.632616 -131.604099) (xy 39.668533 -131.458379) (xy 39.712219 -131.314797) (xy 39.76355 -131.173767)
			(xy 39.822377 -131.035696) (xy 39.88853 -130.900981) (xy 39.961819 -130.770012) (xy 40.042032 -130.643165)
			(xy 40.128938 -130.520806) (xy 40.222287 -130.403289) (xy 40.321809 -130.290952) (xy 40.427217 -130.184119)
			(xy 40.538208 -130.083097) (xy 40.654462 -129.988179) (xy 40.775642 -129.899638) (xy 40.901401 -129.817729)
			(xy 41.031375 -129.742689) (xy 41.165189 -129.674733) (xy 41.302458 -129.614058) (xy 41.442786 -129.560839)
			(xy 41.585769 -129.515228) (xy 41.730993 -129.477359) (xy 41.878041 -129.447339) (xy 42.026489 -129.425255)
			(xy 42.175907 -129.411171) (xy 42.325866 -129.405128) (xy 42.475934 -129.407143) (xy 42.625677 -129.41721)
			(xy 42.774663 -129.4353) (xy 42.922464 -129.461361) (xy 43.068653 -129.495319) (xy 43.212809 -129.537074)
			(xy 43.354515 -129.586506) (xy 43.493364 -129.643474) (xy 43.628954 -129.707813) (xy 43.760896 -129.779337)
			(xy 43.888808 -129.85784) (xy 44.012323 -129.943095) (xy 44.131082 -130.034858) (xy 44.244746 -130.132863)
			(xy 44.352984 -130.236827) (xy 44.455487 -130.346452) (xy 44.551957 -130.461421) (xy 44.642117 -130.581402)
			(xy 44.725706 -130.70605) (xy 44.802485 -130.835004) (xy 44.872231 -130.967894) (xy 44.934744 -131.104337)
			(xy 44.989842 -131.243938) (xy 45.037368 -131.386295) (xy 45.077184 -131.530998) (xy 45.109176 -131.677629)
			(xy 45.13325 -131.825767) (xy 45.149339 -131.974983) (xy 45.157394 -132.124848) (xy 45.157898 -132.199888)
			(xy 59.126378 -132.199888) (xy 59.130407 -132.049861) (xy 59.142484 -131.900267) (xy 59.162573 -131.751537)
			(xy 59.190616 -131.604099) (xy 59.226533 -131.458379) (xy 59.270219 -131.314797) (xy 59.32155 -131.173767)
			(xy 59.380377 -131.035696) (xy 59.44653 -130.900981) (xy 59.519819 -130.770012) (xy 59.600032 -130.643165)
			(xy 59.686938 -130.520806) (xy 59.780287 -130.403289) (xy 59.879809 -130.290952) (xy 59.985217 -130.184119)
			(xy 60.096208 -130.083097) (xy 60.212462 -129.988179) (xy 60.333642 -129.899638) (xy 60.459401 -129.817729)
			(xy 60.589375 -129.742689) (xy 60.723189 -129.674733) (xy 60.860458 -129.614058) (xy 61.000786 -129.560839)
			(xy 61.143769 -129.515228) (xy 61.288993 -129.477359) (xy 61.436041 -129.447339) (xy 61.584489 -129.425255)
			(xy 61.733907 -129.411171) (xy 61.883866 -129.405128) (xy 62.033934 -129.407143) (xy 62.183677 -129.41721)
			(xy 62.332663 -129.4353) (xy 62.480464 -129.461361) (xy 62.626653 -129.495319) (xy 62.770809 -129.537074)
			(xy 62.912515 -129.586506) (xy 63.051364 -129.643474) (xy 63.186954 -129.707813) (xy 63.318896 -129.779337)
			(xy 63.446808 -129.85784) (xy 63.570323 -129.943095) (xy 63.689082 -130.034858) (xy 63.802746 -130.132863)
			(xy 63.910984 -130.236827) (xy 64.013487 -130.346452) (xy 64.109957 -130.461421) (xy 64.200117 -130.581402)
			(xy 64.283706 -130.70605) (xy 64.360485 -130.835004) (xy 64.430231 -130.967894) (xy 64.492744 -131.104337)
			(xy 64.547842 -131.243938) (xy 64.595368 -131.386295) (xy 64.635184 -131.530998) (xy 64.667176 -131.677629)
			(xy 64.69125 -131.825767) (xy 64.707339 -131.974983) (xy 64.715394 -132.124848) (xy 64.715898 -132.199888)
			(xy 64.715394 -132.274928) (xy 64.707339 -132.424793) (xy 64.69125 -132.574009) (xy 64.667176 -132.722147)
			(xy 64.635184 -132.868778) (xy 64.595368 -133.013481) (xy 64.547842 -133.155838) (xy 64.492744 -133.295439)
			(xy 64.430231 -133.431882) (xy 64.360485 -133.564772) (xy 64.283706 -133.693726) (xy 64.200117 -133.818374)
			(xy 64.109957 -133.938355) (xy 64.013487 -134.053324) (xy 63.910984 -134.162949) (xy 63.802746 -134.266913)
			(xy 63.689082 -134.364918) (xy 63.570323 -134.456681) (xy 63.446808 -134.541936) (xy 63.318896 -134.620439)
			(xy 63.186954 -134.691963) (xy 63.051364 -134.756302) (xy 62.912515 -134.81327) (xy 62.770809 -134.862702)
			(xy 62.626653 -134.904457) (xy 62.480464 -134.938415) (xy 62.332663 -134.964476) (xy 62.183677 -134.982566)
			(xy 62.033934 -134.992633) (xy 61.883866 -134.994648) (xy 61.733907 -134.988605) (xy 61.584489 -134.974521)
			(xy 61.436041 -134.952437) (xy 61.288993 -134.922417) (xy 61.143769 -134.884548) (xy 61.000786 -134.838937)
			(xy 60.860458 -134.785718) (xy 60.723189 -134.725043) (xy 60.589375 -134.657087) (xy 60.459401 -134.582047)
			(xy 60.333642 -134.500138) (xy 60.212462 -134.411597) (xy 60.096208 -134.316679) (xy 59.985217 -134.215657)
			(xy 59.879809 -134.108824) (xy 59.780287 -133.996487) (xy 59.686938 -133.87897) (xy 59.600032 -133.756611)
			(xy 59.519819 -133.629764) (xy 59.44653 -133.498795) (xy 59.380377 -133.36408) (xy 59.32155 -133.226009)
			(xy 59.270219 -133.084979) (xy 59.226533 -132.941397) (xy 59.190616 -132.795677) (xy 59.162573 -132.648239)
			(xy 59.142484 -132.499509) (xy 59.130407 -132.349915) (xy 59.126378 -132.199888) (xy 45.157898 -132.199888)
			(xy 45.157394 -132.274928) (xy 45.149339 -132.424793) (xy 45.13325 -132.574009) (xy 45.109176 -132.722147)
			(xy 45.077184 -132.868778) (xy 45.037368 -133.013481) (xy 44.989842 -133.155838) (xy 44.934744 -133.295439)
			(xy 44.872231 -133.431882) (xy 44.802485 -133.564772) (xy 44.725706 -133.693726) (xy 44.642117 -133.818374)
			(xy 44.551957 -133.938355) (xy 44.455487 -134.053324) (xy 44.352984 -134.162949) (xy 44.244746 -134.266913)
			(xy 44.131082 -134.364918) (xy 44.012323 -134.456681) (xy 43.888808 -134.541936) (xy 43.760896 -134.620439)
			(xy 43.628954 -134.691963) (xy 43.493364 -134.756302) (xy 43.354515 -134.81327) (xy 43.212809 -134.862702)
			(xy 43.068653 -134.904457) (xy 42.922464 -134.938415) (xy 42.774663 -134.964476) (xy 42.625677 -134.982566)
			(xy 42.475934 -134.992633) (xy 42.325866 -134.994648) (xy 42.175907 -134.988605) (xy 42.026489 -134.974521)
			(xy 41.878041 -134.952437) (xy 41.730993 -134.922417) (xy 41.585769 -134.884548) (xy 41.442786 -134.838937)
			(xy 41.302458 -134.785718) (xy 41.165189 -134.725043) (xy 41.031375 -134.657087) (xy 40.901401 -134.582047)
			(xy 40.775642 -134.500138) (xy 40.654462 -134.411597) (xy 40.538208 -134.316679) (xy 40.427217 -134.215657)
			(xy 40.321809 -134.108824) (xy 40.222287 -133.996487) (xy 40.128938 -133.87897) (xy 40.042032 -133.756611)
			(xy 39.961819 -133.629764) (xy 39.88853 -133.498795) (xy 39.822377 -133.36408) (xy 39.76355 -133.226009)
			(xy 39.712219 -133.084979) (xy 39.668533 -132.941397) (xy 39.632616 -132.795677) (xy 39.604573 -132.648239)
			(xy 39.584484 -132.499509) (xy 39.572407 -132.349915) (xy 39.568378 -132.199888) (xy 34.057082 -132.199888)
			(xy 34.057082 -140.589508) (xy 41.347136 -140.589508) (xy 41.347136 -138.811) (xy 41.347635 -138.794302)
			(xy 41.35627 -138.762043) (xy 41.372951 -138.733113) (xy 41.396546 -138.70948) (xy 41.425448 -138.69275)
			(xy 41.457693 -138.684063) (xy 41.47439 -138.683492) (xy 43.25239 -138.683492) (xy 43.269054 -138.683997)
			(xy 43.301249 -138.692612) (xy 43.330122 -138.709258) (xy 43.353708 -138.732804) (xy 43.370404 -138.761649)
			(xy 43.379075 -138.793829) (xy 43.379644 -138.810492) (xy 43.379644 -140.589) (xy 43.379626 -140.589508)
			(xy 60.905136 -140.589508) (xy 60.905136 -138.811) (xy 60.905635 -138.794302) (xy 60.91427 -138.762043)
			(xy 60.930951 -138.733113) (xy 60.954546 -138.70948) (xy 60.983448 -138.69275) (xy 61.015693 -138.684063)
			(xy 61.03239 -138.683492) (xy 62.81039 -138.683492) (xy 62.827054 -138.683997) (xy 62.859249 -138.692612)
			(xy 62.888122 -138.709258) (xy 62.911708 -138.732804) (xy 62.928404 -138.761649) (xy 62.937075 -138.793829)
			(xy 62.937644 -138.810492) (xy 62.937644 -140.589) (xy 62.937066 -140.605691) (xy 62.928438 -140.637939)
			(xy 62.911769 -140.666861) (xy 62.888192 -140.690492) (xy 62.859308 -140.707227) (xy 62.82708 -140.715928)
			(xy 62.81039 -140.716508) (xy 61.03239 -140.716508) (xy 61.015725 -140.716021) (xy 60.983529 -140.707401)
			(xy 60.954657 -140.69075) (xy 60.931071 -140.667201) (xy 60.914375 -140.638354) (xy 60.905705 -140.606172)
			(xy 60.905136 -140.589508) (xy 43.379626 -140.589508) (xy 43.379066 -140.605691) (xy 43.370438 -140.637939)
			(xy 43.353769 -140.666861) (xy 43.330192 -140.690492) (xy 43.301308 -140.707227) (xy 43.26908 -140.715928)
			(xy 43.25239 -140.716508) (xy 41.47439 -140.716508) (xy 41.457725 -140.716021) (xy 41.425529 -140.707401)
			(xy 41.396657 -140.69075) (xy 41.373071 -140.667201) (xy 41.356375 -140.638354) (xy 41.347705 -140.606172)
			(xy 41.347136 -140.589508) (xy 34.057082 -140.589508) (xy 34.057082 -169.159682) (xy 34.3408 -169.4434)
			(xy 37.40277 -169.4434)
		)
		(stroke
			(width 0)
			(type solid)
		)
		(fill yes)
		(layer "F.Cu")
		(net "P52V_HS2")
	)
	(gr_poly
		(pts
			(xy 400.790918 -169.545) (xy 400.800795 -169.54454) (xy 400.819094 -169.537097) (xy 400.826478 -169.530522)
			(xy 400.953224 -169.403776) (xy 400.953224 -149.591776) (xy 401.207732 -149.337268) (xy 401.207986 -149.337014)
			(xy 402.194014 -148.350986) (xy 402.201409 -148.344132) (xy 402.220008 -148.33639) (xy 402.230082 -148.336)
			(xy 413.871918 -148.336) (xy 413.881795 -148.33554) (xy 413.900094 -148.328097) (xy 413.907478 -148.321522)
			(xy 415.006028 -147.222972) (xy 415.006536 -147.222464) (xy 415.013123 -147.215084) (xy 415.020582 -147.196785)
			(xy 415.021014 -147.186904) (xy 415.021014 -136.814814) (xy 415.021234 -136.807774) (xy 415.025094 -136.794233)
			(xy 415.028634 -136.788144) (xy 415.03219 -136.782048) (xy 415.036 -136.76884) (xy 415.036 -55.9308)
			(xy 415.02838 -55.912004) (xy 415.021014 -55.904892) (xy 412.38424 -53.268118) (xy 412.38424 -50.66284)
			(xy 411.774386 -50.052986) (xy 411.767274 -50.04562) (xy 411.748478 -50.038) (xy 409.175204 -50.038)
			(xy 409.165133 -50.037577) (xy 409.146528 -50.029864) (xy 409.139136 -50.023014) (xy 405.78024 -46.664118)
			(xy 405.78024 -41.4782) (xy 405.600154 -41.4782) (xy 405.054054 -40.9321) (xy 405.054054 -39.3319)
			(xy 403.5933 -39.3319) (xy 402.0566 -37.7952) (xy 402.0566 -32.9692) (xy 401.667218 -32.579818) (xy 393.759182 -32.579818)
			(xy 392.24204 -34.09696) (xy 392.23464 -34.103801) (xy 392.216042 -34.11152) (xy 392.205972 -34.111946)
			(xy 389.656828 -34.111946) (xy 389.646765 -34.111508) (xy 389.628185 -34.103769) (xy 389.62076 -34.09696)
			(xy 388.92353 -33.39973) (xy 388.916129 -33.392891) (xy 388.897531 -33.385178) (xy 388.887462 -33.384744)
			(xy 368.065812 -33.384744) (xy 368.055742 -33.384322) (xy 368.03714 -33.376604) (xy 368.029744 -33.369758)
			(xy 355.552248 -20.892262) (xy 355.55047 -20.890738) (xy 354.359718 -19.699986) (xy 354.352319 -19.693143)
			(xy 354.33372 -19.685425) (xy 354.32365 -19.685) (xy 328.703432 -19.685) (xy 328.693367 -19.685436)
			(xy 328.674781 -19.693167) (xy 328.667364 -19.699986) (xy 328.589386 -19.777964) (xy 328.58202 -19.785076)
			(xy 328.5744 -19.803872) (xy 328.5744 -24.383492) (xy 328.574818 -24.393514) (xy 328.582487 -24.412034)
			(xy 328.596659 -24.426209) (xy 328.615178 -24.43388) (xy 328.6252 -24.434292) (xy 338.63661 -24.434292)
			(xy 338.64668 -24.434716) (xy 338.665282 -24.442433) (xy 338.672678 -24.449278) (xy 339.481414 -25.258014)
			(xy 339.488268 -25.265409) (xy 339.49601 -25.284008) (xy 339.4964 -25.294082) (xy 339.4964 -29.950918)
			(xy 339.495973 -29.960987) (xy 339.488254 -29.979586) (xy 339.481414 -29.986986) (xy 338.647278 -30.821122)
			(xy 338.639882 -30.827973) (xy 338.621283 -30.835712) (xy 338.61121 -30.836108) (xy 328.712068 -30.836108)
			(xy 328.702001 -30.836537) (xy 328.683405 -30.844261) (xy 328.676 -30.851094) (xy 328.589386 -30.937708)
			(xy 328.58202 -30.94482) (xy 328.5744 -30.963616) (xy 328.5744 -35.661092) (xy 328.574818 -35.671114)
			(xy 328.582487 -35.689634) (xy 328.596659 -35.703809) (xy 328.615178 -35.71148) (xy 328.6252 -35.711892)
			(xy 338.61121 -35.711892) (xy 338.62128 -35.712316) (xy 338.639882 -35.720033) (xy 338.647278 -35.726878)
			(xy 339.481414 -36.561014) (xy 339.488268 -36.568409) (xy 339.49601 -36.587008) (xy 339.4964 -36.597082)
			(xy 339.4964 -38.181788) (xy 339.496908 -38.227) (xy 339.4964 -38.272212) (xy 339.4964 -40.64) (xy 342.03539 -40.64)
			(xy 342.039407 -40.508317) (xy 342.051445 -40.377124) (xy 342.071459 -40.246909) (xy 342.099374 -40.118156)
			(xy 342.135086 -39.991345) (xy 342.178463 -39.866947) (xy 342.229343 -39.745424) (xy 342.287537 -39.627229)
			(xy 342.352828 -39.512802) (xy 342.424974 -39.402568) (xy 342.503706 -39.296938) (xy 342.588731 -39.196304)
			(xy 342.679733 -39.10104) (xy 342.776373 -39.011501) (xy 342.878292 -38.928021) (xy 342.985111 -38.850909)
			(xy 343.096432 -38.780453) (xy 343.211842 -38.716914) (xy 343.33091 -38.66053) (xy 343.453195 -38.611509)
			(xy 343.57824 -38.570034) (xy 343.705581 -38.53626) (xy 343.834745 -38.510311) (xy 343.96525 -38.492286)
			(xy 344.096611 -38.48225) (xy 344.22834 -38.480241) (xy 344.359946 -38.486266) (xy 344.49094 -38.500303)
			(xy 344.620835 -38.522301) (xy 344.749147 -38.552176) (xy 344.875399 -38.589818) (xy 344.999121 -38.635087)
			(xy 345.119854 -38.687814) (xy 345.237147 -38.747804) (xy 345.350566 -38.814832) (xy 345.459686 -38.88865)
			(xy 345.564104 -38.968984) (xy 345.66343 -39.055534) (xy 345.757295 -39.147978) (xy 345.845349 -39.245972)
			(xy 345.927266 -39.349153) (xy 346.00274 -39.457135) (xy 346.07149 -39.569518) (xy 346.133261 -39.685883)
			(xy 346.187823 -39.805797) (xy 346.234974 -39.928815) (xy 346.274537 -40.054478) (xy 346.306365 -40.18232)
			(xy 346.330341 -40.311864) (xy 346.346374 -40.442629) (xy 346.354406 -40.574128) (xy 346.354908 -40.64)
			(xy 346.354406 -40.705872) (xy 346.346374 -40.837371) (xy 346.330341 -40.968136) (xy 346.306365 -41.09768)
			(xy 346.274537 -41.225522) (xy 346.234974 -41.351185) (xy 346.187823 -41.474203) (xy 346.133261 -41.594117)
			(xy 346.07149 -41.710482) (xy 346.00274 -41.822865) (xy 345.927266 -41.930847) (xy 345.845349 -42.034028)
			(xy 345.757295 -42.132022) (xy 345.66343 -42.224466) (xy 345.564104 -42.311016) (xy 345.459686 -42.39135)
			(xy 345.350566 -42.465168) (xy 345.237147 -42.532196) (xy 345.119854 -42.592186) (xy 344.999121 -42.644913)
			(xy 344.875399 -42.690182) (xy 344.749147 -42.727824) (xy 344.620835 -42.757699) (xy 344.49094 -42.779697)
			(xy 344.359946 -42.793734) (xy 344.22834 -42.799759) (xy 344.096611 -42.79775) (xy 343.96525 -42.787714)
			(xy 343.834745 -42.769689) (xy 343.705581 -42.74374) (xy 343.57824 -42.709966) (xy 343.453195 -42.668491)
			(xy 343.33091 -42.61947) (xy 343.211842 -42.563086) (xy 343.096432 -42.499547) (xy 342.985111 -42.429091)
			(xy 342.878292 -42.351979) (xy 342.776373 -42.268499) (xy 342.679733 -42.17896) (xy 342.588731 -42.083696)
			(xy 342.503706 -41.983062) (xy 342.424974 -41.877432) (xy 342.352828 -41.767198) (xy 342.287537 -41.652771)
			(xy 342.229343 -41.534576) (xy 342.178463 -41.413053) (xy 342.135086 -41.288655) (xy 342.099374 -41.161844)
			(xy 342.071459 -41.033091) (xy 342.051445 -40.902876) (xy 342.039407 -40.771683) (xy 342.03539 -40.64)
			(xy 339.4964 -40.64) (xy 339.4964 -41.126918) (xy 339.495973 -41.136987) (xy 339.488254 -41.155586)
			(xy 339.481414 -41.162986) (xy 338.545678 -42.098722) (xy 338.538282 -42.105573) (xy 338.519683 -42.113312)
			(xy 338.50961 -42.113708) (xy 328.712068 -42.113708) (xy 328.702001 -42.114137) (xy 328.683405 -42.121861)
			(xy 328.676 -42.128694) (xy 328.589386 -42.215308) (xy 328.58202 -42.22242) (xy 328.5744 -42.241216)
			(xy 328.5744 -46.938692) (xy 328.574818 -46.948714) (xy 328.582487 -46.967234) (xy 328.596659 -46.981409)
			(xy 328.615178 -46.98908) (xy 328.6252 -46.989492) (xy 338.71281 -46.989492) (xy 338.72288 -46.989916)
			(xy 338.741482 -46.997633) (xy 338.748878 -47.004478) (xy 339.608414 -47.864014) (xy 339.615268 -47.871409)
			(xy 339.62301 -47.890008) (xy 339.6234 -47.900082) (xy 339.6234 -49.484788) (xy 339.623908 -49.53)
			(xy 339.6234 -49.575212) (xy 339.6234 -51.9176) (xy 342.00999 -51.9176) (xy 342.014007 -51.785917)
			(xy 342.026045 -51.654724) (xy 342.046059 -51.524509) (xy 342.073974 -51.395756) (xy 342.109686 -51.268945)
			(xy 342.153063 -51.144547) (xy 342.203943 -51.023024) (xy 342.262137 -50.904829) (xy 342.327428 -50.790402)
			(xy 342.399574 -50.680168) (xy 342.478306 -50.574538) (xy 342.563331 -50.473904) (xy 342.654333 -50.37864)
			(xy 342.750973 -50.289101) (xy 342.852892 -50.205621) (xy 342.959711 -50.128509) (xy 343.071032 -50.058053)
			(xy 343.186442 -49.994514) (xy 343.30551 -49.93813) (xy 343.427795 -49.889109) (xy 343.55284 -49.847634)
			(xy 343.680181 -49.81386) (xy 343.809345 -49.787911) (xy 343.93985 -49.769886) (xy 344.071211 -49.75985)
			(xy 344.20294 -49.757841) (xy 344.334546 -49.763866) (xy 344.46554 -49.777903) (xy 344.595435 -49.799901)
			(xy 344.723747 -49.829776) (xy 344.849999 -49.867418) (xy 344.973721 -49.912687) (xy 345.094454 -49.965414)
			(xy 345.211747 -50.025404) (xy 345.325166 -50.092432) (xy 345.434286 -50.16625) (xy 345.538704 -50.246584)
			(xy 345.63803 -50.333134) (xy 345.731895 -50.425578) (xy 345.819949 -50.523572) (xy 345.901866 -50.626753)
			(xy 345.97734 -50.734735) (xy 346.04609 -50.847118) (xy 346.084719 -50.919888) (xy 375.283988 -50.919888)
			(xy 375.288017 -50.769861) (xy 375.300094 -50.620267) (xy 375.320183 -50.471537) (xy 375.348226 -50.324099)
			(xy 375.384143 -50.178379) (xy 375.427829 -50.034797) (xy 375.47916 -49.893767) (xy 375.537987 -49.755696)
			(xy 375.60414 -49.620981) (xy 375.677429 -49.490012) (xy 375.757642 -49.363165) (xy 375.844548 -49.240806)
			(xy 375.937897 -49.123289) (xy 376.037419 -49.010952) (xy 376.142827 -48.904119) (xy 376.253818 -48.803097)
			(xy 376.370072 -48.708179) (xy 376.491252 -48.619638) (xy 376.617011 -48.537729) (xy 376.746985 -48.462689)
			(xy 376.880799 -48.394733) (xy 377.018068 -48.334058) (xy 377.158396 -48.280839) (xy 377.301379 -48.235228)
			(xy 377.446603 -48.197359) (xy 377.593651 -48.167339) (xy 377.742099 -48.145255) (xy 377.891517 -48.131171)
			(xy 378.041476 -48.125128) (xy 378.191544 -48.127143) (xy 378.341287 -48.13721) (xy 378.490273 -48.1553)
			(xy 378.638074 -48.181361) (xy 378.784263 -48.215319) (xy 378.928419 -48.257074) (xy 379.070125 -48.306506)
			(xy 379.208974 -48.363474) (xy 379.344564 -48.427813) (xy 379.476506 -48.499337) (xy 379.604418 -48.57784)
			(xy 379.727933 -48.663095) (xy 379.846692 -48.754858) (xy 379.960356 -48.852863) (xy 380.068594 -48.956827)
			(xy 380.171097 -49.066452) (xy 380.267567 -49.181421) (xy 380.357727 -49.301402) (xy 380.441316 -49.42605)
			(xy 380.518095 -49.555004) (xy 380.587841 -49.687894) (xy 380.650354 -49.824337) (xy 380.705452 -49.963938)
			(xy 380.752978 -50.106295) (xy 380.792794 -50.250998) (xy 380.824786 -50.397629) (xy 380.84886 -50.545767)
			(xy 380.864949 -50.694983) (xy 380.873004 -50.844848) (xy 380.873508 -50.919888) (xy 394.841988 -50.919888)
			(xy 394.846017 -50.769861) (xy 394.858094 -50.620267) (xy 394.878183 -50.471537) (xy 394.906226 -50.324099)
			(xy 394.942143 -50.178379) (xy 394.985829 -50.034797) (xy 395.03716 -49.893767) (xy 395.095987 -49.755696)
			(xy 395.16214 -49.620981) (xy 395.235429 -49.490012) (xy 395.315642 -49.363165) (xy 395.402548 -49.240806)
			(xy 395.495897 -49.123289) (xy 395.595419 -49.010952) (xy 395.700827 -48.904119) (xy 395.811818 -48.803097)
			(xy 395.928072 -48.708179) (xy 396.049252 -48.619638) (xy 396.175011 -48.537729) (xy 396.304985 -48.462689)
			(xy 396.438799 -48.394733) (xy 396.576068 -48.334058) (xy 396.716396 -48.280839) (xy 396.859379 -48.235228)
			(xy 397.004603 -48.197359) (xy 397.151651 -48.167339) (xy 397.300099 -48.145255) (xy 397.449517 -48.131171)
			(xy 397.599476 -48.125128) (xy 397.749544 -48.127143) (xy 397.899287 -48.13721) (xy 398.048273 -48.1553)
			(xy 398.196074 -48.181361) (xy 398.342263 -48.215319) (xy 398.486419 -48.257074) (xy 398.628125 -48.306506)
			(xy 398.766974 -48.363474) (xy 398.902564 -48.427813) (xy 399.034506 -48.499337) (xy 399.162418 -48.57784)
			(xy 399.285933 -48.663095) (xy 399.404692 -48.754858) (xy 399.518356 -48.852863) (xy 399.626594 -48.956827)
			(xy 399.729097 -49.066452) (xy 399.825567 -49.181421) (xy 399.915727 -49.301402) (xy 399.999316 -49.42605)
			(xy 400.076095 -49.555004) (xy 400.145841 -49.687894) (xy 400.208354 -49.824337) (xy 400.263452 -49.963938)
			(xy 400.310978 -50.106295) (xy 400.350794 -50.250998) (xy 400.382786 -50.397629) (xy 400.40686 -50.545767)
			(xy 400.422949 -50.694983) (xy 400.431004 -50.844848) (xy 400.431508 -50.919888) (xy 400.431004 -50.994928)
			(xy 400.422949 -51.144793) (xy 400.40686 -51.294009) (xy 400.382786 -51.442147) (xy 400.350794 -51.588778)
			(xy 400.310978 -51.733481) (xy 400.263452 -51.875838) (xy 400.208354 -52.015439) (xy 400.145841 -52.151882)
			(xy 400.076095 -52.284772) (xy 399.999316 -52.413726) (xy 399.915727 -52.538374) (xy 399.825567 -52.658355)
			(xy 399.729097 -52.773324) (xy 399.626594 -52.882949) (xy 399.518356 -52.986913) (xy 399.404692 -53.084918)
			(xy 399.285933 -53.176681) (xy 399.162418 -53.261936) (xy 399.034506 -53.340439) (xy 398.902564 -53.411963)
			(xy 398.766974 -53.476302) (xy 398.628125 -53.53327) (xy 398.486419 -53.582702) (xy 398.342263 -53.624457)
			(xy 398.196074 -53.658415) (xy 398.048273 -53.684476) (xy 397.899287 -53.702566) (xy 397.749544 -53.712633)
			(xy 397.599476 -53.714648) (xy 397.449517 -53.708605) (xy 397.300099 -53.694521) (xy 397.151651 -53.672437)
			(xy 397.004603 -53.642417) (xy 396.859379 -53.604548) (xy 396.716396 -53.558937) (xy 396.576068 -53.505718)
			(xy 396.438799 -53.445043) (xy 396.304985 -53.377087) (xy 396.175011 -53.302047) (xy 396.049252 -53.220138)
			(xy 395.928072 -53.131597) (xy 395.811818 -53.036679) (xy 395.700827 -52.935657) (xy 395.595419 -52.828824)
			(xy 395.495897 -52.716487) (xy 395.402548 -52.59897) (xy 395.315642 -52.476611) (xy 395.235429 -52.349764)
			(xy 395.16214 -52.218795) (xy 395.095987 -52.08408) (xy 395.03716 -51.946009) (xy 394.985829 -51.804979)
			(xy 394.942143 -51.661397) (xy 394.906226 -51.515677) (xy 394.878183 -51.368239) (xy 394.858094 -51.219509)
			(xy 394.846017 -51.069915) (xy 394.841988 -50.919888) (xy 380.873508 -50.919888) (xy 380.873004 -50.994928)
			(xy 380.864949 -51.144793) (xy 380.84886 -51.294009) (xy 380.824786 -51.442147) (xy 380.792794 -51.588778)
			(xy 380.752978 -51.733481) (xy 380.705452 -51.875838) (xy 380.650354 -52.015439) (xy 380.587841 -52.151882)
			(xy 380.518095 -52.284772) (xy 380.441316 -52.413726) (xy 380.357727 -52.538374) (xy 380.267567 -52.658355)
			(xy 380.171097 -52.773324) (xy 380.068594 -52.882949) (xy 379.960356 -52.986913) (xy 379.846692 -53.084918)
			(xy 379.727933 -53.176681) (xy 379.604418 -53.261936) (xy 379.476506 -53.340439) (xy 379.344564 -53.411963)
			(xy 379.208974 -53.476302) (xy 379.070125 -53.53327) (xy 378.928419 -53.582702) (xy 378.784263 -53.624457)
			(xy 378.638074 -53.658415) (xy 378.490273 -53.684476) (xy 378.341287 -53.702566) (xy 378.191544 -53.712633)
			(xy 378.041476 -53.714648) (xy 377.891517 -53.708605) (xy 377.742099 -53.694521) (xy 377.593651 -53.672437)
			(xy 377.446603 -53.642417) (xy 377.301379 -53.604548) (xy 377.158396 -53.558937) (xy 377.018068 -53.505718)
			(xy 376.880799 -53.445043) (xy 376.746985 -53.377087) (xy 376.617011 -53.302047) (xy 376.491252 -53.220138)
			(xy 376.370072 -53.131597) (xy 376.253818 -53.036679) (xy 376.142827 -52.935657) (xy 376.037419 -52.828824)
			(xy 375.937897 -52.716487) (xy 375.844548 -52.59897) (xy 375.757642 -52.476611) (xy 375.677429 -52.349764)
			(xy 375.60414 -52.218795) (xy 375.537987 -52.08408) (xy 375.47916 -51.946009) (xy 375.427829 -51.804979)
			(xy 375.384143 -51.661397) (xy 375.348226 -51.515677) (xy 375.320183 -51.368239) (xy 375.300094 -51.219509)
			(xy 375.288017 -51.069915) (xy 375.283988 -50.919888) (xy 346.084719 -50.919888) (xy 346.107861 -50.963483)
			(xy 346.162423 -51.083397) (xy 346.209574 -51.206415) (xy 346.249137 -51.332078) (xy 346.280965 -51.45992)
			(xy 346.304941 -51.589464) (xy 346.320974 -51.720229) (xy 346.329006 -51.851728) (xy 346.329508 -51.9176)
			(xy 346.329006 -51.983472) (xy 346.320974 -52.114971) (xy 346.304941 -52.245736) (xy 346.280965 -52.37528)
			(xy 346.249137 -52.503122) (xy 346.209574 -52.628785) (xy 346.162423 -52.751803) (xy 346.107861 -52.871717)
			(xy 346.04609 -52.988082) (xy 345.97734 -53.100465) (xy 345.901866 -53.208447) (xy 345.819949 -53.311628)
			(xy 345.731895 -53.409622) (xy 345.63803 -53.502066) (xy 345.538704 -53.588616) (xy 345.434286 -53.66895)
			(xy 345.325166 -53.742768) (xy 345.211747 -53.809796) (xy 345.094454 -53.869786) (xy 344.973721 -53.922513)
			(xy 344.849999 -53.967782) (xy 344.723747 -54.005424) (xy 344.595435 -54.035299) (xy 344.46554 -54.057297)
			(xy 344.334546 -54.071334) (xy 344.20294 -54.077359) (xy 344.071211 -54.07535) (xy 343.93985 -54.065314)
			(xy 343.809345 -54.047289) (xy 343.680181 -54.02134) (xy 343.55284 -53.987566) (xy 343.427795 -53.946091)
			(xy 343.30551 -53.89707) (xy 343.186442 -53.840686) (xy 343.071032 -53.777147) (xy 342.959711 -53.706691)
			(xy 342.852892 -53.629579) (xy 342.750973 -53.546099) (xy 342.654333 -53.45656) (xy 342.563331 -53.361296)
			(xy 342.478306 -53.260662) (xy 342.399574 -53.155032) (xy 342.327428 -53.044798) (xy 342.262137 -52.930371)
			(xy 342.203943 -52.812176) (xy 342.153063 -52.690653) (xy 342.109686 -52.566255) (xy 342.073974 -52.439444)
			(xy 342.046059 -52.310691) (xy 342.026045 -52.180476) (xy 342.014007 -52.049283) (xy 342.00999 -51.9176)
			(xy 339.6234 -51.9176) (xy 339.6234 -52.683918) (xy 339.622973 -52.693987) (xy 339.615254 -52.712586)
			(xy 339.608414 -52.719986) (xy 338.952078 -53.376322) (xy 338.944682 -53.383173) (xy 338.926083 -53.390912)
			(xy 338.91601 -53.391308) (xy 328.712068 -53.391308) (xy 328.702001 -53.391737) (xy 328.683405 -53.399461)
			(xy 328.676 -53.406294) (xy 328.589386 -53.492908) (xy 328.58202 -53.50002) (xy 328.5744 -53.518816)
			(xy 328.5744 -58.216292) (xy 328.574818 -58.226314) (xy 328.582487 -58.244834) (xy 328.596659 -58.259009)
			(xy 328.615178 -58.26668) (xy 328.6252 -58.267092) (xy 338.68741 -58.267092) (xy 338.69748 -58.267516)
			(xy 338.716082 -58.275233) (xy 338.723478 -58.282078) (xy 339.608414 -59.167014) (xy 339.615268 -59.174409)
			(xy 339.62301 -59.193008) (xy 339.6234 -59.203082) (xy 339.6234 -59.309) (xy 377.062492 -59.309)
			(xy 377.062492 -57.531) (xy 377.063038 -57.514285) (xy 377.07169 -57.481994) (xy 377.088405 -57.453043)
			(xy 377.112043 -57.429405) (xy 377.140994 -57.41269) (xy 377.173285 -57.404038) (xy 377.19 -57.403492)
			(xy 378.968 -57.403492) (xy 378.984715 -57.404038) (xy 379.017006 -57.41269) (xy 379.045957 -57.429405)
			(xy 379.069595 -57.453043) (xy 379.08631 -57.481994) (xy 379.094962 -57.514285) (xy 379.095508 -57.531)
			(xy 379.095508 -59.309) (xy 396.620492 -59.309) (xy 396.620492 -57.531) (xy 396.621038 -57.514285)
			(xy 396.62969 -57.481994) (xy 396.646405 -57.453043) (xy 396.670043 -57.429405) (xy 396.698994 -57.41269)
			(xy 396.731285 -57.404038) (xy 396.748 -57.403492) (xy 398.526 -57.403492) (xy 398.542715 -57.404038)
			(xy 398.575006 -57.41269) (xy 398.603957 -57.429405) (xy 398.627595 -57.453043) (xy 398.64431 -57.481994)
			(xy 398.652962 -57.514285) (xy 398.653508 -57.531) (xy 398.653508 -59.309) (xy 398.652962 -59.325715)
			(xy 398.64431 -59.358006) (xy 398.627595 -59.386957) (xy 398.603957 -59.410595) (xy 398.575006 -59.42731)
			(xy 398.542715 -59.435962) (xy 398.526 -59.436508) (xy 396.748 -59.436508) (xy 396.731285 -59.435962)
			(xy 396.698994 -59.42731) (xy 396.670043 -59.410595) (xy 396.646405 -59.386957) (xy 396.62969 -59.358006)
			(xy 396.621038 -59.325715) (xy 396.620492 -59.309) (xy 379.095508 -59.309) (xy 379.094962 -59.325715)
			(xy 379.08631 -59.358006) (xy 379.069595 -59.386957) (xy 379.045957 -59.410595) (xy 379.017006 -59.42731)
			(xy 378.984715 -59.435962) (xy 378.968 -59.436508) (xy 377.19 -59.436508) (xy 377.173285 -59.435962)
			(xy 377.140994 -59.42731) (xy 377.112043 -59.410595) (xy 377.088405 -59.386957) (xy 377.07169 -59.358006)
			(xy 377.063038 -59.325715) (xy 377.062492 -59.309) (xy 339.6234 -59.309) (xy 339.6234 -63.986918)
			(xy 339.622973 -63.996987) (xy 339.615254 -64.015586) (xy 339.608414 -64.022986) (xy 338.977478 -64.653922)
			(xy 338.970082 -64.660773) (xy 338.951483 -64.668512) (xy 338.94141 -64.668908) (xy 328.712068 -64.668908)
			(xy 328.702001 -64.669337) (xy 328.683405 -64.677061) (xy 328.676 -64.683894) (xy 328.589386 -64.770508)
			(xy 328.58202 -64.77762) (xy 328.5744 -64.796416) (xy 328.5744 -69.493892) (xy 328.574818 -69.503914)
			(xy 328.582487 -69.522434) (xy 328.596659 -69.536609) (xy 328.615178 -69.54428) (xy 328.6252 -69.544692)
			(xy 338.91601 -69.544692) (xy 338.92608 -69.545116) (xy 338.944682 -69.552833) (xy 338.952078 -69.559678)
			(xy 339.608414 -70.216014) (xy 339.615268 -70.223409) (xy 339.62301 -70.242008) (xy 339.6234 -70.252082)
			(xy 339.6234 -71.239888) (xy 375.283988 -71.239888) (xy 375.288017 -71.089861) (xy 375.300094 -70.940267)
			(xy 375.320183 -70.791537) (xy 375.348226 -70.644099) (xy 375.384143 -70.498379) (xy 375.427829 -70.354797)
			(xy 375.47916 -70.213767) (xy 375.537987 -70.075696) (xy 375.60414 -69.940981) (xy 375.677429 -69.810012)
			(xy 375.757642 -69.683165) (xy 375.844548 -69.560806) (xy 375.937897 -69.443289) (xy 376.037419 -69.330952)
			(xy 376.142827 -69.224119) (xy 376.253818 -69.123097) (xy 376.370072 -69.028179) (xy 376.491252 -68.939638)
			(xy 376.617011 -68.857729) (xy 376.746985 -68.782689) (xy 376.880799 -68.714733) (xy 377.018068 -68.654058)
			(xy 377.158396 -68.600839) (xy 377.301379 -68.555228) (xy 377.446603 -68.517359) (xy 377.593651 -68.487339)
			(xy 377.742099 -68.465255) (xy 377.891517 -68.451171) (xy 378.041476 -68.445128) (xy 378.191544 -68.447143)
			(xy 378.341287 -68.45721) (xy 378.490273 -68.4753) (xy 378.638074 -68.501361) (xy 378.784263 -68.535319)
			(xy 378.928419 -68.577074) (xy 379.070125 -68.626506) (xy 379.208974 -68.683474) (xy 379.344564 -68.747813)
			(xy 379.476506 -68.819337) (xy 379.604418 -68.89784) (xy 379.727933 -68.983095) (xy 379.846692 -69.074858)
			(xy 379.960356 -69.172863) (xy 380.068594 -69.276827) (xy 380.171097 -69.386452) (xy 380.267567 -69.501421)
			(xy 380.357727 -69.621402) (xy 380.441316 -69.74605) (xy 380.518095 -69.875004) (xy 380.587841 -70.007894)
			(xy 380.650354 -70.144337) (xy 380.705452 -70.283938) (xy 380.752978 -70.426295) (xy 380.792794 -70.570998)
			(xy 380.824786 -70.717629) (xy 380.84886 -70.865767) (xy 380.864949 -71.014983) (xy 380.873004 -71.164848)
			(xy 380.873508 -71.239888) (xy 394.841988 -71.239888) (xy 394.846017 -71.089861) (xy 394.858094 -70.940267)
			(xy 394.878183 -70.791537) (xy 394.906226 -70.644099) (xy 394.942143 -70.498379) (xy 394.985829 -70.354797)
			(xy 395.03716 -70.213767) (xy 395.095987 -70.075696) (xy 395.16214 -69.940981) (xy 395.235429 -69.810012)
			(xy 395.315642 -69.683165) (xy 395.402548 -69.560806) (xy 395.495897 -69.443289) (xy 395.595419 -69.330952)
			(xy 395.700827 -69.224119) (xy 395.811818 -69.123097) (xy 395.928072 -69.028179) (xy 396.049252 -68.939638)
			(xy 396.175011 -68.857729) (xy 396.304985 -68.782689) (xy 396.438799 -68.714733) (xy 396.576068 -68.654058)
			(xy 396.716396 -68.600839) (xy 396.859379 -68.555228) (xy 397.004603 -68.517359) (xy 397.151651 -68.487339)
			(xy 397.300099 -68.465255) (xy 397.449517 -68.451171) (xy 397.599476 -68.445128) (xy 397.749544 -68.447143)
			(xy 397.899287 -68.45721) (xy 398.048273 -68.4753) (xy 398.196074 -68.501361) (xy 398.342263 -68.535319)
			(xy 398.486419 -68.577074) (xy 398.628125 -68.626506) (xy 398.766974 -68.683474) (xy 398.902564 -68.747813)
			(xy 399.034506 -68.819337) (xy 399.162418 -68.89784) (xy 399.285933 -68.983095) (xy 399.404692 -69.074858)
			(xy 399.518356 -69.172863) (xy 399.626594 -69.276827) (xy 399.729097 -69.386452) (xy 399.825567 -69.501421)
			(xy 399.915727 -69.621402) (xy 399.999316 -69.74605) (xy 400.076095 -69.875004) (xy 400.145841 -70.007894)
			(xy 400.208354 -70.144337) (xy 400.263452 -70.283938) (xy 400.310978 -70.426295) (xy 400.350794 -70.570998)
			(xy 400.382786 -70.717629) (xy 400.40686 -70.865767) (xy 400.422949 -71.014983) (xy 400.431004 -71.164848)
			(xy 400.431508 -71.239888) (xy 400.431004 -71.314928) (xy 400.422949 -71.464793) (xy 400.40686 -71.614009)
			(xy 400.382786 -71.762147) (xy 400.350794 -71.908778) (xy 400.310978 -72.053481) (xy 400.263452 -72.195838)
			(xy 400.208354 -72.335439) (xy 400.145841 -72.471882) (xy 400.076095 -72.604772) (xy 399.999316 -72.733726)
			(xy 399.915727 -72.858374) (xy 399.825567 -72.978355) (xy 399.729097 -73.093324) (xy 399.626594 -73.202949)
			(xy 399.518356 -73.306913) (xy 399.404692 -73.404918) (xy 399.285933 -73.496681) (xy 399.162418 -73.581936)
			(xy 399.034506 -73.660439) (xy 398.902564 -73.731963) (xy 398.766974 -73.796302) (xy 398.628125 -73.85327)
			(xy 398.486419 -73.902702) (xy 398.342263 -73.944457) (xy 398.196074 -73.978415) (xy 398.048273 -74.004476)
			(xy 397.899287 -74.022566) (xy 397.749544 -74.032633) (xy 397.599476 -74.034648) (xy 397.449517 -74.028605)
			(xy 397.300099 -74.014521) (xy 397.151651 -73.992437) (xy 397.004603 -73.962417) (xy 396.859379 -73.924548)
			(xy 396.716396 -73.878937) (xy 396.576068 -73.825718) (xy 396.438799 -73.765043) (xy 396.304985 -73.697087)
			(xy 396.175011 -73.622047) (xy 396.049252 -73.540138) (xy 395.928072 -73.451597) (xy 395.811818 -73.356679)
			(xy 395.700827 -73.255657) (xy 395.595419 -73.148824) (xy 395.495897 -73.036487) (xy 395.402548 -72.91897)
			(xy 395.315642 -72.796611) (xy 395.235429 -72.669764) (xy 395.16214 -72.538795) (xy 395.095987 -72.40408)
			(xy 395.03716 -72.266009) (xy 394.985829 -72.124979) (xy 394.942143 -71.981397) (xy 394.906226 -71.835677)
			(xy 394.878183 -71.688239) (xy 394.858094 -71.539509) (xy 394.846017 -71.389915) (xy 394.841988 -71.239888)
			(xy 380.873508 -71.239888) (xy 380.873004 -71.314928) (xy 380.864949 -71.464793) (xy 380.84886 -71.614009)
			(xy 380.824786 -71.762147) (xy 380.792794 -71.908778) (xy 380.752978 -72.053481) (xy 380.705452 -72.195838)
			(xy 380.650354 -72.335439) (xy 380.587841 -72.471882) (xy 380.518095 -72.604772) (xy 380.441316 -72.733726)
			(xy 380.357727 -72.858374) (xy 380.267567 -72.978355) (xy 380.171097 -73.093324) (xy 380.068594 -73.202949)
			(xy 379.960356 -73.306913) (xy 379.846692 -73.404918) (xy 379.727933 -73.496681) (xy 379.604418 -73.581936)
			(xy 379.476506 -73.660439) (xy 379.344564 -73.731963) (xy 379.208974 -73.796302) (xy 379.070125 -73.85327)
			(xy 378.928419 -73.902702) (xy 378.784263 -73.944457) (xy 378.638074 -73.978415) (xy 378.490273 -74.004476)
			(xy 378.341287 -74.022566) (xy 378.191544 -74.032633) (xy 378.041476 -74.034648) (xy 377.891517 -74.028605)
			(xy 377.742099 -74.014521) (xy 377.593651 -73.992437) (xy 377.446603 -73.962417) (xy 377.301379 -73.924548)
			(xy 377.158396 -73.878937) (xy 377.018068 -73.825718) (xy 376.880799 -73.765043) (xy 376.746985 -73.697087)
			(xy 376.617011 -73.622047) (xy 376.491252 -73.540138) (xy 376.370072 -73.451597) (xy 376.253818 -73.356679)
			(xy 376.142827 -73.255657) (xy 376.037419 -73.148824) (xy 375.937897 -73.036487) (xy 375.844548 -72.91897)
			(xy 375.757642 -72.796611) (xy 375.677429 -72.669764) (xy 375.60414 -72.538795) (xy 375.537987 -72.40408)
			(xy 375.47916 -72.266009) (xy 375.427829 -72.124979) (xy 375.384143 -71.981397) (xy 375.348226 -71.835677)
			(xy 375.320183 -71.688239) (xy 375.300094 -71.539509) (xy 375.288017 -71.389915) (xy 375.283988 -71.239888)
			(xy 339.6234 -71.239888) (xy 339.6234 -75.289918) (xy 339.622973 -75.299987) (xy 339.615254 -75.318586)
			(xy 339.608414 -75.325986) (xy 339.003386 -75.931014) (xy 338.995991 -75.937868) (xy 338.977392 -75.94561)
			(xy 338.967318 -75.946) (xy 335.029302 -75.946) (xy 334.986884 -75.946508) (xy 328.712068 -75.946508)
			(xy 328.702001 -75.946937) (xy 328.683405 -75.954661) (xy 328.676 -75.961494) (xy 328.589386 -76.048108)
			(xy 328.58202 -76.05522) (xy 328.5744 -76.074016) (xy 328.5744 -79.607918) (xy 328.57486 -79.617795)
			(xy 328.579418 -79.629) (xy 377.062492 -79.629) (xy 377.062492 -77.851) (xy 377.063038 -77.834285)
			(xy 377.07169 -77.801994) (xy 377.088405 -77.773043) (xy 377.112043 -77.749405) (xy 377.140994 -77.73269)
			(xy 377.173285 -77.724038) (xy 377.19 -77.723492) (xy 378.968 -77.723492) (xy 378.984715 -77.724038)
			(xy 379.017006 -77.73269) (xy 379.045957 -77.749405) (xy 379.069595 -77.773043) (xy 379.08631 -77.801994)
			(xy 379.094962 -77.834285) (xy 379.095508 -77.851) (xy 379.095508 -79.629) (xy 396.620492 -79.629)
			(xy 396.620492 -77.851) (xy 396.621038 -77.834285) (xy 396.62969 -77.801994) (xy 396.646405 -77.773043)
			(xy 396.670043 -77.749405) (xy 396.698994 -77.73269) (xy 396.731285 -77.724038) (xy 396.748 -77.723492)
			(xy 398.526 -77.723492) (xy 398.542715 -77.724038) (xy 398.575006 -77.73269) (xy 398.603957 -77.749405)
			(xy 398.627595 -77.773043) (xy 398.64431 -77.801994) (xy 398.652962 -77.834285) (xy 398.653508 -77.851)
			(xy 398.653508 -79.629) (xy 398.652962 -79.645715) (xy 398.64431 -79.678006) (xy 398.627595 -79.706957)
			(xy 398.603957 -79.730595) (xy 398.575006 -79.74731) (xy 398.542715 -79.755962) (xy 398.526 -79.756508)
			(xy 396.748 -79.756508) (xy 396.731285 -79.755962) (xy 396.698994 -79.74731) (xy 396.670043 -79.730595)
			(xy 396.646405 -79.706957) (xy 396.62969 -79.678006) (xy 396.621038 -79.645715) (xy 396.620492 -79.629)
			(xy 379.095508 -79.629) (xy 379.094962 -79.645715) (xy 379.08631 -79.678006) (xy 379.069595 -79.706957)
			(xy 379.045957 -79.730595) (xy 379.017006 -79.74731) (xy 378.984715 -79.755962) (xy 378.968 -79.756508)
			(xy 377.19 -79.756508) (xy 377.173285 -79.755962) (xy 377.140994 -79.74731) (xy 377.112043 -79.730595)
			(xy 377.088405 -79.706957) (xy 377.07169 -79.678006) (xy 377.063038 -79.645715) (xy 377.062492 -79.629)
			(xy 328.579418 -79.629) (xy 328.582303 -79.636094) (xy 328.588878 -79.643478) (xy 328.813414 -79.868014)
			(xy 328.813922 -79.868522) (xy 328.8213 -79.875112) (xy 328.839599 -79.882579) (xy 328.849482 -79.883)
			(xy 345.444318 -79.883) (xy 345.454387 -79.883427) (xy 345.472986 -79.891146) (xy 345.480386 -79.897986)
			(xy 347.330014 -81.747614) (xy 347.336868 -81.755009) (xy 347.34461 -81.773608) (xy 347.345 -81.783682)
			(xy 347.345 -91.559888) (xy 375.283988 -91.559888) (xy 375.288017 -91.409861) (xy 375.300094 -91.260267)
			(xy 375.320183 -91.111537) (xy 375.348226 -90.964099) (xy 375.384143 -90.818379) (xy 375.427829 -90.674797)
			(xy 375.47916 -90.533767) (xy 375.537987 -90.395696) (xy 375.60414 -90.260981) (xy 375.677429 -90.130012)
			(xy 375.757642 -90.003165) (xy 375.844548 -89.880806) (xy 375.937897 -89.763289) (xy 376.037419 -89.650952)
			(xy 376.142827 -89.544119) (xy 376.253818 -89.443097) (xy 376.370072 -89.348179) (xy 376.491252 -89.259638)
			(xy 376.617011 -89.177729) (xy 376.746985 -89.102689) (xy 376.880799 -89.034733) (xy 377.018068 -88.974058)
			(xy 377.158396 -88.920839) (xy 377.301379 -88.875228) (xy 377.446603 -88.837359) (xy 377.593651 -88.807339)
			(xy 377.742099 -88.785255) (xy 377.891517 -88.771171) (xy 378.041476 -88.765128) (xy 378.191544 -88.767143)
			(xy 378.341287 -88.77721) (xy 378.490273 -88.7953) (xy 378.638074 -88.821361) (xy 378.784263 -88.855319)
			(xy 378.928419 -88.897074) (xy 379.070125 -88.946506) (xy 379.208974 -89.003474) (xy 379.344564 -89.067813)
			(xy 379.476506 -89.139337) (xy 379.604418 -89.21784) (xy 379.727933 -89.303095) (xy 379.846692 -89.394858)
			(xy 379.960356 -89.492863) (xy 380.068594 -89.596827) (xy 380.171097 -89.706452) (xy 380.267567 -89.821421)
			(xy 380.357727 -89.941402) (xy 380.441316 -90.06605) (xy 380.518095 -90.195004) (xy 380.587841 -90.327894)
			(xy 380.650354 -90.464337) (xy 380.705452 -90.603938) (xy 380.752978 -90.746295) (xy 380.792794 -90.890998)
			(xy 380.824786 -91.037629) (xy 380.84886 -91.185767) (xy 380.864949 -91.334983) (xy 380.873004 -91.484848)
			(xy 380.873508 -91.559888) (xy 394.841988 -91.559888) (xy 394.846017 -91.409861) (xy 394.858094 -91.260267)
			(xy 394.878183 -91.111537) (xy 394.906226 -90.964099) (xy 394.942143 -90.818379) (xy 394.985829 -90.674797)
			(xy 395.03716 -90.533767) (xy 395.095987 -90.395696) (xy 395.16214 -90.260981) (xy 395.235429 -90.130012)
			(xy 395.315642 -90.003165) (xy 395.402548 -89.880806) (xy 395.495897 -89.763289) (xy 395.595419 -89.650952)
			(xy 395.700827 -89.544119) (xy 395.811818 -89.443097) (xy 395.928072 -89.348179) (xy 396.049252 -89.259638)
			(xy 396.175011 -89.177729) (xy 396.304985 -89.102689) (xy 396.438799 -89.034733) (xy 396.576068 -88.974058)
			(xy 396.716396 -88.920839) (xy 396.859379 -88.875228) (xy 397.004603 -88.837359) (xy 397.151651 -88.807339)
			(xy 397.300099 -88.785255) (xy 397.449517 -88.771171) (xy 397.599476 -88.765128) (xy 397.749544 -88.767143)
			(xy 397.899287 -88.77721) (xy 398.048273 -88.7953) (xy 398.196074 -88.821361) (xy 398.342263 -88.855319)
			(xy 398.486419 -88.897074) (xy 398.628125 -88.946506) (xy 398.766974 -89.003474) (xy 398.902564 -89.067813)
			(xy 399.034506 -89.139337) (xy 399.162418 -89.21784) (xy 399.285933 -89.303095) (xy 399.404692 -89.394858)
			(xy 399.518356 -89.492863) (xy 399.626594 -89.596827) (xy 399.729097 -89.706452) (xy 399.825567 -89.821421)
			(xy 399.915727 -89.941402) (xy 399.999316 -90.06605) (xy 400.076095 -90.195004) (xy 400.145841 -90.327894)
			(xy 400.208354 -90.464337) (xy 400.263452 -90.603938) (xy 400.310978 -90.746295) (xy 400.350794 -90.890998)
			(xy 400.382786 -91.037629) (xy 400.40686 -91.185767) (xy 400.422949 -91.334983) (xy 400.431004 -91.484848)
			(xy 400.431508 -91.559888) (xy 400.431004 -91.634928) (xy 400.422949 -91.784793) (xy 400.40686 -91.934009)
			(xy 400.382786 -92.082147) (xy 400.350794 -92.228778) (xy 400.310978 -92.373481) (xy 400.263452 -92.515838)
			(xy 400.208354 -92.655439) (xy 400.145841 -92.791882) (xy 400.076095 -92.924772) (xy 399.999316 -93.053726)
			(xy 399.915727 -93.178374) (xy 399.825567 -93.298355) (xy 399.729097 -93.413324) (xy 399.626594 -93.522949)
			(xy 399.518356 -93.626913) (xy 399.404692 -93.724918) (xy 399.285933 -93.816681) (xy 399.162418 -93.901936)
			(xy 399.034506 -93.980439) (xy 398.902564 -94.051963) (xy 398.766974 -94.116302) (xy 398.628125 -94.17327)
			(xy 398.486419 -94.222702) (xy 398.342263 -94.264457) (xy 398.196074 -94.298415) (xy 398.048273 -94.324476)
			(xy 397.899287 -94.342566) (xy 397.749544 -94.352633) (xy 397.599476 -94.354648) (xy 397.449517 -94.348605)
			(xy 397.300099 -94.334521) (xy 397.151651 -94.312437) (xy 397.004603 -94.282417) (xy 396.859379 -94.244548)
			(xy 396.716396 -94.198937) (xy 396.576068 -94.145718) (xy 396.438799 -94.085043) (xy 396.304985 -94.017087)
			(xy 396.175011 -93.942047) (xy 396.049252 -93.860138) (xy 395.928072 -93.771597) (xy 395.811818 -93.676679)
			(xy 395.700827 -93.575657) (xy 395.595419 -93.468824) (xy 395.495897 -93.356487) (xy 395.402548 -93.23897)
			(xy 395.315642 -93.116611) (xy 395.235429 -92.989764) (xy 395.16214 -92.858795) (xy 395.095987 -92.72408)
			(xy 395.03716 -92.586009) (xy 394.985829 -92.444979) (xy 394.942143 -92.301397) (xy 394.906226 -92.155677)
			(xy 394.878183 -92.008239) (xy 394.858094 -91.859509) (xy 394.846017 -91.709915) (xy 394.841988 -91.559888)
			(xy 380.873508 -91.559888) (xy 380.873004 -91.634928) (xy 380.864949 -91.784793) (xy 380.84886 -91.934009)
			(xy 380.824786 -92.082147) (xy 380.792794 -92.228778) (xy 380.752978 -92.373481) (xy 380.705452 -92.515838)
			(xy 380.650354 -92.655439) (xy 380.587841 -92.791882) (xy 380.518095 -92.924772) (xy 380.441316 -93.053726)
			(xy 380.357727 -93.178374) (xy 380.267567 -93.298355) (xy 380.171097 -93.413324) (xy 380.068594 -93.522949)
			(xy 379.960356 -93.626913) (xy 379.846692 -93.724918) (xy 379.727933 -93.816681) (xy 379.604418 -93.901936)
			(xy 379.476506 -93.980439) (xy 379.344564 -94.051963) (xy 379.208974 -94.116302) (xy 379.070125 -94.17327)
			(xy 378.928419 -94.222702) (xy 378.784263 -94.264457) (xy 378.638074 -94.298415) (xy 378.490273 -94.324476)
			(xy 378.341287 -94.342566) (xy 378.191544 -94.352633) (xy 378.041476 -94.354648) (xy 377.891517 -94.348605)
			(xy 377.742099 -94.334521) (xy 377.593651 -94.312437) (xy 377.446603 -94.282417) (xy 377.301379 -94.244548)
			(xy 377.158396 -94.198937) (xy 377.018068 -94.145718) (xy 376.880799 -94.085043) (xy 376.746985 -94.017087)
			(xy 376.617011 -93.942047) (xy 376.491252 -93.860138) (xy 376.370072 -93.771597) (xy 376.253818 -93.676679)
			(xy 376.142827 -93.575657) (xy 376.037419 -93.468824) (xy 375.937897 -93.356487) (xy 375.844548 -93.23897)
			(xy 375.757642 -93.116611) (xy 375.677429 -92.989764) (xy 375.60414 -92.858795) (xy 375.537987 -92.72408)
			(xy 375.47916 -92.586009) (xy 375.427829 -92.444979) (xy 375.384143 -92.301397) (xy 375.348226 -92.155677)
			(xy 375.320183 -92.008239) (xy 375.300094 -91.859509) (xy 375.288017 -91.709915) (xy 375.283988 -91.559888)
			(xy 347.345 -91.559888) (xy 347.345 -99.394518) (xy 347.345427 -99.404587) (xy 347.353146 -99.423186)
			(xy 347.359986 -99.430586) (xy 347.8784 -99.949) (xy 377.062492 -99.949) (xy 377.062492 -98.171)
			(xy 377.063038 -98.154285) (xy 377.07169 -98.121994) (xy 377.088405 -98.093043) (xy 377.112043 -98.069405)
			(xy 377.140994 -98.05269) (xy 377.173285 -98.044038) (xy 377.19 -98.043492) (xy 378.968 -98.043492)
			(xy 378.984715 -98.044038) (xy 379.017006 -98.05269) (xy 379.045957 -98.069405) (xy 379.069595 -98.093043)
			(xy 379.08631 -98.121994) (xy 379.094962 -98.154285) (xy 379.095508 -98.171) (xy 379.095508 -99.949)
			(xy 396.620492 -99.949) (xy 396.620492 -98.171) (xy 396.621038 -98.154285) (xy 396.62969 -98.121994)
			(xy 396.646405 -98.093043) (xy 396.670043 -98.069405) (xy 396.698994 -98.05269) (xy 396.731285 -98.044038)
			(xy 396.748 -98.043492) (xy 398.526 -98.043492) (xy 398.542715 -98.044038) (xy 398.575006 -98.05269)
			(xy 398.603957 -98.069405) (xy 398.627595 -98.093043) (xy 398.64431 -98.121994) (xy 398.652962 -98.154285)
			(xy 398.653508 -98.171) (xy 398.653508 -99.949) (xy 398.652962 -99.965715) (xy 398.64431 -99.998006)
			(xy 398.627595 -100.026957) (xy 398.603957 -100.050595) (xy 398.575006 -100.06731) (xy 398.542715 -100.075962)
			(xy 398.526 -100.076508) (xy 396.748 -100.076508) (xy 396.731285 -100.075962) (xy 396.698994 -100.06731)
			(xy 396.670043 -100.050595) (xy 396.646405 -100.026957) (xy 396.62969 -99.998006) (xy 396.621038 -99.965715)
			(xy 396.620492 -99.949) (xy 379.095508 -99.949) (xy 379.094962 -99.965715) (xy 379.08631 -99.998006)
			(xy 379.069595 -100.026957) (xy 379.045957 -100.050595) (xy 379.017006 -100.06731) (xy 378.984715 -100.075962)
			(xy 378.968 -100.076508) (xy 377.19 -100.076508) (xy 377.173285 -100.075962) (xy 377.140994 -100.06731)
			(xy 377.112043 -100.050595) (xy 377.088405 -100.026957) (xy 377.07169 -99.998006) (xy 377.063038 -99.965715)
			(xy 377.062492 -99.949) (xy 347.8784 -99.949) (xy 355.356414 -107.427014) (xy 355.363268 -107.434409)
			(xy 355.37101 -107.453008) (xy 355.3714 -107.463082) (xy 355.3714 -111.879888) (xy 375.283988 -111.879888)
			(xy 375.288017 -111.729861) (xy 375.300094 -111.580267) (xy 375.320183 -111.431537) (xy 375.348226 -111.284099)
			(xy 375.384143 -111.138379) (xy 375.427829 -110.994797) (xy 375.47916 -110.853767) (xy 375.537987 -110.715696)
			(xy 375.60414 -110.580981) (xy 375.677429 -110.450012) (xy 375.757642 -110.323165) (xy 375.844548 -110.200806)
			(xy 375.937897 -110.083289) (xy 376.037419 -109.970952) (xy 376.142827 -109.864119) (xy 376.253818 -109.763097)
			(xy 376.370072 -109.668179) (xy 376.491252 -109.579638) (xy 376.617011 -109.497729) (xy 376.746985 -109.422689)
			(xy 376.880799 -109.354733) (xy 377.018068 -109.294058) (xy 377.158396 -109.240839) (xy 377.301379 -109.195228)
			(xy 377.446603 -109.157359) (xy 377.593651 -109.127339) (xy 377.742099 -109.105255) (xy 377.891517 -109.091171)
			(xy 378.041476 -109.085128) (xy 378.191544 -109.087143) (xy 378.341287 -109.09721) (xy 378.490273 -109.1153)
			(xy 378.638074 -109.141361) (xy 378.784263 -109.175319) (xy 378.928419 -109.217074) (xy 379.070125 -109.266506)
			(xy 379.208974 -109.323474) (xy 379.344564 -109.387813) (xy 379.476506 -109.459337) (xy 379.604418 -109.53784)
			(xy 379.727933 -109.623095) (xy 379.846692 -109.714858) (xy 379.960356 -109.812863) (xy 380.068594 -109.916827)
			(xy 380.171097 -110.026452) (xy 380.267567 -110.141421) (xy 380.357727 -110.261402) (xy 380.441316 -110.38605)
			(xy 380.518095 -110.515004) (xy 380.587841 -110.647894) (xy 380.650354 -110.784337) (xy 380.705452 -110.923938)
			(xy 380.752978 -111.066295) (xy 380.792794 -111.210998) (xy 380.824786 -111.357629) (xy 380.84886 -111.505767)
			(xy 380.864949 -111.654983) (xy 380.873004 -111.804848) (xy 380.873508 -111.879888) (xy 394.841988 -111.879888)
			(xy 394.846017 -111.729861) (xy 394.858094 -111.580267) (xy 394.878183 -111.431537) (xy 394.906226 -111.284099)
			(xy 394.942143 -111.138379) (xy 394.985829 -110.994797) (xy 395.03716 -110.853767) (xy 395.095987 -110.715696)
			(xy 395.16214 -110.580981) (xy 395.235429 -110.450012) (xy 395.315642 -110.323165) (xy 395.402548 -110.200806)
			(xy 395.495897 -110.083289) (xy 395.595419 -109.970952) (xy 395.700827 -109.864119) (xy 395.811818 -109.763097)
			(xy 395.928072 -109.668179) (xy 396.049252 -109.579638) (xy 396.175011 -109.497729) (xy 396.304985 -109.422689)
			(xy 396.438799 -109.354733) (xy 396.576068 -109.294058) (xy 396.716396 -109.240839) (xy 396.859379 -109.195228)
			(xy 397.004603 -109.157359) (xy 397.151651 -109.127339) (xy 397.300099 -109.105255) (xy 397.449517 -109.091171)
			(xy 397.599476 -109.085128) (xy 397.749544 -109.087143) (xy 397.899287 -109.09721) (xy 398.048273 -109.1153)
			(xy 398.196074 -109.141361) (xy 398.342263 -109.175319) (xy 398.486419 -109.217074) (xy 398.628125 -109.266506)
			(xy 398.766974 -109.323474) (xy 398.902564 -109.387813) (xy 399.034506 -109.459337) (xy 399.162418 -109.53784)
			(xy 399.285933 -109.623095) (xy 399.404692 -109.714858) (xy 399.518356 -109.812863) (xy 399.626594 -109.916827)
			(xy 399.729097 -110.026452) (xy 399.825567 -110.141421) (xy 399.915727 -110.261402) (xy 399.999316 -110.38605)
			(xy 400.076095 -110.515004) (xy 400.145841 -110.647894) (xy 400.208354 -110.784337) (xy 400.263452 -110.923938)
			(xy 400.310978 -111.066295) (xy 400.350794 -111.210998) (xy 400.382786 -111.357629) (xy 400.40686 -111.505767)
			(xy 400.422949 -111.654983) (xy 400.431004 -111.804848) (xy 400.431508 -111.879888) (xy 400.431004 -111.954928)
			(xy 400.422949 -112.104793) (xy 400.40686 -112.254009) (xy 400.382786 -112.402147) (xy 400.350794 -112.548778)
			(xy 400.310978 -112.693481) (xy 400.263452 -112.835838) (xy 400.208354 -112.975439) (xy 400.145841 -113.111882)
			(xy 400.076095 -113.244772) (xy 399.999316 -113.373726) (xy 399.915727 -113.498374) (xy 399.825567 -113.618355)
			(xy 399.729097 -113.733324) (xy 399.626594 -113.842949) (xy 399.518356 -113.946913) (xy 399.404692 -114.044918)
			(xy 399.285933 -114.136681) (xy 399.162418 -114.221936) (xy 399.034506 -114.300439) (xy 398.902564 -114.371963)
			(xy 398.766974 -114.436302) (xy 398.628125 -114.49327) (xy 398.486419 -114.542702) (xy 398.342263 -114.584457)
			(xy 398.196074 -114.618415) (xy 398.048273 -114.644476) (xy 397.899287 -114.662566) (xy 397.749544 -114.672633)
			(xy 397.599476 -114.674648) (xy 397.449517 -114.668605) (xy 397.300099 -114.654521) (xy 397.151651 -114.632437)
			(xy 397.004603 -114.602417) (xy 396.859379 -114.564548) (xy 396.716396 -114.518937) (xy 396.576068 -114.465718)
			(xy 396.438799 -114.405043) (xy 396.304985 -114.337087) (xy 396.175011 -114.262047) (xy 396.049252 -114.180138)
			(xy 395.928072 -114.091597) (xy 395.811818 -113.996679) (xy 395.700827 -113.895657) (xy 395.595419 -113.788824)
			(xy 395.495897 -113.676487) (xy 395.402548 -113.55897) (xy 395.315642 -113.436611) (xy 395.235429 -113.309764)
			(xy 395.16214 -113.178795) (xy 395.095987 -113.04408) (xy 395.03716 -112.906009) (xy 394.985829 -112.764979)
			(xy 394.942143 -112.621397) (xy 394.906226 -112.475677) (xy 394.878183 -112.328239) (xy 394.858094 -112.179509)
			(xy 394.846017 -112.029915) (xy 394.841988 -111.879888) (xy 380.873508 -111.879888) (xy 380.873004 -111.954928)
			(xy 380.864949 -112.104793) (xy 380.84886 -112.254009) (xy 380.824786 -112.402147) (xy 380.792794 -112.548778)
			(xy 380.752978 -112.693481) (xy 380.705452 -112.835838) (xy 380.650354 -112.975439) (xy 380.587841 -113.111882)
			(xy 380.518095 -113.244772) (xy 380.441316 -113.373726) (xy 380.357727 -113.498374) (xy 380.267567 -113.618355)
			(xy 380.171097 -113.733324) (xy 380.068594 -113.842949) (xy 379.960356 -113.946913) (xy 379.846692 -114.044918)
			(xy 379.727933 -114.136681) (xy 379.604418 -114.221936) (xy 379.476506 -114.300439) (xy 379.344564 -114.371963)
			(xy 379.208974 -114.436302) (xy 379.070125 -114.49327) (xy 378.928419 -114.542702) (xy 378.784263 -114.584457)
			(xy 378.638074 -114.618415) (xy 378.490273 -114.644476) (xy 378.341287 -114.662566) (xy 378.191544 -114.672633)
			(xy 378.041476 -114.674648) (xy 377.891517 -114.668605) (xy 377.742099 -114.654521) (xy 377.593651 -114.632437)
			(xy 377.446603 -114.602417) (xy 377.301379 -114.564548) (xy 377.158396 -114.518937) (xy 377.018068 -114.465718)
			(xy 376.880799 -114.405043) (xy 376.746985 -114.337087) (xy 376.617011 -114.262047) (xy 376.491252 -114.180138)
			(xy 376.370072 -114.091597) (xy 376.253818 -113.996679) (xy 376.142827 -113.895657) (xy 376.037419 -113.788824)
			(xy 375.937897 -113.676487) (xy 375.844548 -113.55897) (xy 375.757642 -113.436611) (xy 375.677429 -113.309764)
			(xy 375.60414 -113.178795) (xy 375.537987 -113.04408) (xy 375.47916 -112.906009) (xy 375.427829 -112.764979)
			(xy 375.384143 -112.621397) (xy 375.348226 -112.475677) (xy 375.320183 -112.328239) (xy 375.300094 -112.179509)
			(xy 375.288017 -112.029915) (xy 375.283988 -111.879888) (xy 355.3714 -111.879888) (xy 355.3714 -120.269)
			(xy 377.062492 -120.269) (xy 377.062492 -118.491) (xy 377.063038 -118.474285) (xy 377.07169 -118.441994)
			(xy 377.088405 -118.413043) (xy 377.112043 -118.389405) (xy 377.140994 -118.37269) (xy 377.173285 -118.364038)
			(xy 377.19 -118.363492) (xy 378.968 -118.363492) (xy 378.984715 -118.364038) (xy 379.017006 -118.37269)
			(xy 379.045957 -118.389405) (xy 379.069595 -118.413043) (xy 379.08631 -118.441994) (xy 379.094962 -118.474285)
			(xy 379.095508 -118.491) (xy 379.095508 -120.269) (xy 396.620492 -120.269) (xy 396.620492 -118.491)
			(xy 396.621038 -118.474285) (xy 396.62969 -118.441994) (xy 396.646405 -118.413043) (xy 396.670043 -118.389405)
			(xy 396.698994 -118.37269) (xy 396.731285 -118.364038) (xy 396.748 -118.363492) (xy 398.526 -118.363492)
			(xy 398.542715 -118.364038) (xy 398.575006 -118.37269) (xy 398.603957 -118.389405) (xy 398.627595 -118.413043)
			(xy 398.64431 -118.441994) (xy 398.652962 -118.474285) (xy 398.653508 -118.491) (xy 398.653508 -120.269)
			(xy 398.652962 -120.285715) (xy 398.64431 -120.318006) (xy 398.627595 -120.346957) (xy 398.603957 -120.370595)
			(xy 398.575006 -120.38731) (xy 398.542715 -120.395962) (xy 398.526 -120.396508) (xy 396.748 -120.396508)
			(xy 396.731285 -120.395962) (xy 396.698994 -120.38731) (xy 396.670043 -120.370595) (xy 396.646405 -120.346957)
			(xy 396.62969 -120.318006) (xy 396.621038 -120.285715) (xy 396.620492 -120.269) (xy 379.095508 -120.269)
			(xy 379.094962 -120.285715) (xy 379.08631 -120.318006) (xy 379.069595 -120.346957) (xy 379.045957 -120.370595)
			(xy 379.017006 -120.38731) (xy 378.984715 -120.395962) (xy 378.968 -120.396508) (xy 377.19 -120.396508)
			(xy 377.173285 -120.395962) (xy 377.140994 -120.38731) (xy 377.112043 -120.370595) (xy 377.088405 -120.346957)
			(xy 377.07169 -120.318006) (xy 377.063038 -120.285715) (xy 377.062492 -120.269) (xy 355.3714 -120.269)
			(xy 355.3714 -132.199888) (xy 375.283988 -132.199888) (xy 375.288017 -132.049861) (xy 375.300094 -131.900267)
			(xy 375.320183 -131.751537) (xy 375.348226 -131.604099) (xy 375.384143 -131.458379) (xy 375.427829 -131.314797)
			(xy 375.47916 -131.173767) (xy 375.537987 -131.035696) (xy 375.60414 -130.900981) (xy 375.677429 -130.770012)
			(xy 375.757642 -130.643165) (xy 375.844548 -130.520806) (xy 375.937897 -130.403289) (xy 376.037419 -130.290952)
			(xy 376.142827 -130.184119) (xy 376.253818 -130.083097) (xy 376.370072 -129.988179) (xy 376.491252 -129.899638)
			(xy 376.617011 -129.817729) (xy 376.746985 -129.742689) (xy 376.880799 -129.674733) (xy 377.018068 -129.614058)
			(xy 377.158396 -129.560839) (xy 377.301379 -129.515228) (xy 377.446603 -129.477359) (xy 377.593651 -129.447339)
			(xy 377.742099 -129.425255) (xy 377.891517 -129.411171) (xy 378.041476 -129.405128) (xy 378.191544 -129.407143)
			(xy 378.341287 -129.41721) (xy 378.490273 -129.4353) (xy 378.638074 -129.461361) (xy 378.784263 -129.495319)
			(xy 378.928419 -129.537074) (xy 379.070125 -129.586506) (xy 379.208974 -129.643474) (xy 379.344564 -129.707813)
			(xy 379.476506 -129.779337) (xy 379.604418 -129.85784) (xy 379.727933 -129.943095) (xy 379.846692 -130.034858)
			(xy 379.960356 -130.132863) (xy 380.068594 -130.236827) (xy 380.171097 -130.346452) (xy 380.267567 -130.461421)
			(xy 380.357727 -130.581402) (xy 380.441316 -130.70605) (xy 380.518095 -130.835004) (xy 380.587841 -130.967894)
			(xy 380.650354 -131.104337) (xy 380.705452 -131.243938) (xy 380.752978 -131.386295) (xy 380.792794 -131.530998)
			(xy 380.824786 -131.677629) (xy 380.84886 -131.825767) (xy 380.864949 -131.974983) (xy 380.873004 -132.124848)
			(xy 380.873508 -132.199888) (xy 394.841988 -132.199888) (xy 394.846017 -132.049861) (xy 394.858094 -131.900267)
			(xy 394.878183 -131.751537) (xy 394.906226 -131.604099) (xy 394.942143 -131.458379) (xy 394.985829 -131.314797)
			(xy 395.03716 -131.173767) (xy 395.095987 -131.035696) (xy 395.16214 -130.900981) (xy 395.235429 -130.770012)
			(xy 395.315642 -130.643165) (xy 395.402548 -130.520806) (xy 395.495897 -130.403289) (xy 395.595419 -130.290952)
			(xy 395.700827 -130.184119) (xy 395.811818 -130.083097) (xy 395.928072 -129.988179) (xy 396.049252 -129.899638)
			(xy 396.175011 -129.817729) (xy 396.304985 -129.742689) (xy 396.438799 -129.674733) (xy 396.576068 -129.614058)
			(xy 396.716396 -129.560839) (xy 396.859379 -129.515228) (xy 397.004603 -129.477359) (xy 397.151651 -129.447339)
			(xy 397.300099 -129.425255) (xy 397.449517 -129.411171) (xy 397.599476 -129.405128) (xy 397.749544 -129.407143)
			(xy 397.899287 -129.41721) (xy 398.048273 -129.4353) (xy 398.196074 -129.461361) (xy 398.342263 -129.495319)
			(xy 398.486419 -129.537074) (xy 398.628125 -129.586506) (xy 398.766974 -129.643474) (xy 398.902564 -129.707813)
			(xy 399.034506 -129.779337) (xy 399.162418 -129.85784) (xy 399.285933 -129.943095) (xy 399.404692 -130.034858)
			(xy 399.518356 -130.132863) (xy 399.626594 -130.236827) (xy 399.729097 -130.346452) (xy 399.825567 -130.461421)
			(xy 399.915727 -130.581402) (xy 399.999316 -130.70605) (xy 400.076095 -130.835004) (xy 400.145841 -130.967894)
			(xy 400.208354 -131.104337) (xy 400.263452 -131.243938) (xy 400.310978 -131.386295) (xy 400.350794 -131.530998)
			(xy 400.382786 -131.677629) (xy 400.40686 -131.825767) (xy 400.422949 -131.974983) (xy 400.431004 -132.124848)
			(xy 400.431508 -132.199888) (xy 400.431004 -132.274928) (xy 400.422949 -132.424793) (xy 400.40686 -132.574009)
			(xy 400.382786 -132.722147) (xy 400.350794 -132.868778) (xy 400.310978 -133.013481) (xy 400.263452 -133.155838)
			(xy 400.208354 -133.295439) (xy 400.145841 -133.431882) (xy 400.076095 -133.564772) (xy 399.999316 -133.693726)
			(xy 399.915727 -133.818374) (xy 399.825567 -133.938355) (xy 399.729097 -134.053324) (xy 399.626594 -134.162949)
			(xy 399.518356 -134.266913) (xy 399.404692 -134.364918) (xy 399.285933 -134.456681) (xy 399.162418 -134.541936)
			(xy 399.034506 -134.620439) (xy 398.902564 -134.691963) (xy 398.766974 -134.756302) (xy 398.628125 -134.81327)
			(xy 398.486419 -134.862702) (xy 398.342263 -134.904457) (xy 398.196074 -134.938415) (xy 398.048273 -134.964476)
			(xy 397.899287 -134.982566) (xy 397.749544 -134.992633) (xy 397.599476 -134.994648) (xy 397.449517 -134.988605)
			(xy 397.300099 -134.974521) (xy 397.151651 -134.952437) (xy 397.004603 -134.922417) (xy 396.859379 -134.884548)
			(xy 396.716396 -134.838937) (xy 396.576068 -134.785718) (xy 396.438799 -134.725043) (xy 396.304985 -134.657087)
			(xy 396.175011 -134.582047) (xy 396.049252 -134.500138) (xy 395.928072 -134.411597) (xy 395.811818 -134.316679)
			(xy 395.700827 -134.215657) (xy 395.595419 -134.108824) (xy 395.495897 -133.996487) (xy 395.402548 -133.87897)
			(xy 395.315642 -133.756611) (xy 395.235429 -133.629764) (xy 395.16214 -133.498795) (xy 395.095987 -133.36408)
			(xy 395.03716 -133.226009) (xy 394.985829 -133.084979) (xy 394.942143 -132.941397) (xy 394.906226 -132.795677)
			(xy 394.878183 -132.648239) (xy 394.858094 -132.499509) (xy 394.846017 -132.349915) (xy 394.841988 -132.199888)
			(xy 380.873508 -132.199888) (xy 380.873004 -132.274928) (xy 380.864949 -132.424793) (xy 380.84886 -132.574009)
			(xy 380.824786 -132.722147) (xy 380.792794 -132.868778) (xy 380.752978 -133.013481) (xy 380.705452 -133.155838)
			(xy 380.650354 -133.295439) (xy 380.587841 -133.431882) (xy 380.518095 -133.564772) (xy 380.441316 -133.693726)
			(xy 380.357727 -133.818374) (xy 380.267567 -133.938355) (xy 380.171097 -134.053324) (xy 380.068594 -134.162949)
			(xy 379.960356 -134.266913) (xy 379.846692 -134.364918) (xy 379.727933 -134.456681) (xy 379.604418 -134.541936)
			(xy 379.476506 -134.620439) (xy 379.344564 -134.691963) (xy 379.208974 -134.756302) (xy 379.070125 -134.81327)
			(xy 378.928419 -134.862702) (xy 378.784263 -134.904457) (xy 378.638074 -134.938415) (xy 378.490273 -134.964476)
			(xy 378.341287 -134.982566) (xy 378.191544 -134.992633) (xy 378.041476 -134.994648) (xy 377.891517 -134.988605)
			(xy 377.742099 -134.974521) (xy 377.593651 -134.952437) (xy 377.446603 -134.922417) (xy 377.301379 -134.884548)
			(xy 377.158396 -134.838937) (xy 377.018068 -134.785718) (xy 376.880799 -134.725043) (xy 376.746985 -134.657087)
			(xy 376.617011 -134.582047) (xy 376.491252 -134.500138) (xy 376.370072 -134.411597) (xy 376.253818 -134.316679)
			(xy 376.142827 -134.215657) (xy 376.037419 -134.108824) (xy 375.937897 -133.996487) (xy 375.844548 -133.87897)
			(xy 375.757642 -133.756611) (xy 375.677429 -133.629764) (xy 375.60414 -133.498795) (xy 375.537987 -133.36408)
			(xy 375.47916 -133.226009) (xy 375.427829 -133.084979) (xy 375.384143 -132.941397) (xy 375.348226 -132.795677)
			(xy 375.320183 -132.648239) (xy 375.300094 -132.499509) (xy 375.288017 -132.349915) (xy 375.283988 -132.199888)
			(xy 355.3714 -132.199888) (xy 355.3714 -135.12546) (xy 355.371868 -135.135334) (xy 355.379322 -135.153622)
			(xy 355.385878 -135.16102) (xy 355.870764 -135.645906) (xy 355.871272 -135.646414) (xy 355.878652 -135.652997)
			(xy 355.896952 -135.660447) (xy 355.906832 -135.660892) (xy 362.992416 -135.660892) (xy 363.002485 -135.661318)
			(xy 363.021086 -135.669035) (xy 363.028484 -135.675878) (xy 366.632998 -139.280392) (xy 366.639846 -139.28779)
			(xy 366.647584 -139.306388) (xy 366.647984 -139.31646) (xy 366.647984 -140.589) (xy 377.062492 -140.589)
			(xy 377.062492 -138.811) (xy 377.063038 -138.794285) (xy 377.07169 -138.761994) (xy 377.088405 -138.733043)
			(xy 377.112043 -138.709405) (xy 377.140994 -138.69269) (xy 377.173285 -138.684038) (xy 377.19 -138.683492)
			(xy 378.968 -138.683492) (xy 378.984715 -138.684038) (xy 379.017006 -138.69269) (xy 379.045957 -138.709405)
			(xy 379.069595 -138.733043) (xy 379.08631 -138.761994) (xy 379.094962 -138.794285) (xy 379.095508 -138.811)
			(xy 379.095508 -140.589) (xy 396.620492 -140.589) (xy 396.620492 -138.811) (xy 396.621038 -138.794285)
			(xy 396.62969 -138.761994) (xy 396.646405 -138.733043) (xy 396.670043 -138.709405) (xy 396.698994 -138.69269)
			(xy 396.731285 -138.684038) (xy 396.748 -138.683492) (xy 398.526 -138.683492) (xy 398.542715 -138.684038)
			(xy 398.575006 -138.69269) (xy 398.603957 -138.709405) (xy 398.627595 -138.733043) (xy 398.64431 -138.761994)
			(xy 398.652962 -138.794285) (xy 398.653508 -138.811) (xy 398.653508 -140.589) (xy 398.652962 -140.605715)
			(xy 398.64431 -140.638006) (xy 398.627595 -140.666957) (xy 398.603957 -140.690595) (xy 398.575006 -140.70731)
			(xy 398.542715 -140.715962) (xy 398.526 -140.716508) (xy 396.748 -140.716508) (xy 396.731285 -140.715962)
			(xy 396.698994 -140.70731) (xy 396.670043 -140.690595) (xy 396.646405 -140.666957) (xy 396.62969 -140.638006)
			(xy 396.621038 -140.605715) (xy 396.620492 -140.589) (xy 379.095508 -140.589) (xy 379.094962 -140.605715)
			(xy 379.08631 -140.638006) (xy 379.069595 -140.666957) (xy 379.045957 -140.690595) (xy 379.017006 -140.70731)
			(xy 378.984715 -140.715962) (xy 378.968 -140.716508) (xy 377.19 -140.716508) (xy 377.173285 -140.715962)
			(xy 377.140994 -140.70731) (xy 377.112043 -140.690595) (xy 377.088405 -140.666957) (xy 377.07169 -140.638006)
			(xy 377.063038 -140.605715) (xy 377.062492 -140.589) (xy 366.647984 -140.589) (xy 366.647984 -150.646638)
			(xy 366.647554 -150.656705) (xy 366.639828 -150.675298) (xy 366.632998 -150.682706) (xy 362.56595 -154.749754)
			(xy 362.559107 -154.757153) (xy 362.551384 -154.775752) (xy 362.550964 -154.785822) (xy 362.550964 -159.684424)
			(xy 371.51385 -159.684424) (xy 371.51385 -159.575796) (xy 371.521779 -159.467458) (xy 371.537596 -159.359987)
			(xy 371.561215 -159.253958) (xy 371.592511 -159.149936) (xy 371.631316 -159.048475) (xy 371.677424 -158.950118)
			(xy 371.730588 -158.855389) (xy 371.790526 -158.764794) (xy 371.856916 -158.678815) (xy 371.929406 -158.597912)
			(xy 372.007607 -158.522516) (xy 372.091104 -158.45303) (xy 372.17945 -158.389823) (xy 372.272174 -158.333235)
			(xy 372.368782 -158.283565) (xy 372.468757 -158.24108) (xy 372.571567 -158.206007) (xy 372.676663 -158.178531)
			(xy 372.783484 -158.1588) (xy 372.89146 -158.146919) (xy 373.000016 -158.142952) (xy 373.108572 -158.146919)
			(xy 373.216548 -158.1588) (xy 373.323369 -158.178531) (xy 373.428465 -158.206007) (xy 373.531275 -158.24108)
			(xy 373.63125 -158.283565) (xy 373.727858 -158.333235) (xy 373.820582 -158.389823) (xy 373.908928 -158.45303)
			(xy 373.992425 -158.522516) (xy 374.070626 -158.597912) (xy 374.143116 -158.678815) (xy 374.209506 -158.764794)
			(xy 374.269444 -158.855389) (xy 374.322608 -158.950118) (xy 374.368716 -159.048475) (xy 374.407521 -159.149936)
			(xy 374.438817 -159.253958) (xy 374.462436 -159.359987) (xy 374.478253 -159.467458) (xy 374.486182 -159.575796)
			(xy 374.486678 -159.63011) (xy 374.486182 -159.684424) (xy 374.478253 -159.792762) (xy 374.462436 -159.900233)
			(xy 374.438817 -160.006262) (xy 374.407521 -160.110284) (xy 374.368716 -160.211745) (xy 374.322608 -160.310102)
			(xy 374.269444 -160.404831) (xy 374.209506 -160.495426) (xy 374.143116 -160.581405) (xy 374.070626 -160.662308)
			(xy 373.992425 -160.737704) (xy 373.908928 -160.80719) (xy 373.820582 -160.870397) (xy 373.727858 -160.926985)
			(xy 373.63125 -160.976655) (xy 373.531275 -161.01914) (xy 373.428465 -161.054213) (xy 373.323369 -161.081689)
			(xy 373.216548 -161.10142) (xy 373.108572 -161.113301) (xy 373.000016 -161.117268) (xy 372.89146 -161.113301)
			(xy 372.783484 -161.10142) (xy 372.676663 -161.081689) (xy 372.571567 -161.054213) (xy 372.468757 -161.01914)
			(xy 372.368782 -160.976655) (xy 372.272174 -160.926985) (xy 372.17945 -160.870397) (xy 372.091104 -160.80719)
			(xy 372.007607 -160.737704) (xy 371.929406 -160.662308) (xy 371.856916 -160.581405) (xy 371.790526 -160.495426)
			(xy 371.730588 -160.404831) (xy 371.677424 -160.310102) (xy 371.631316 -160.211745) (xy 371.592511 -160.110284)
			(xy 371.561215 -160.006262) (xy 371.537596 -159.900233) (xy 371.521779 -159.792762) (xy 371.51385 -159.684424)
			(xy 362.550964 -159.684424) (xy 362.550964 -161.489898) (xy 362.551419 -161.499777) (xy 362.558854 -161.518084)
			(xy 362.565442 -161.525458) (xy 362.695998 -161.656014) (xy 362.696506 -161.656522) (xy 362.703883 -161.663115)
			(xy 362.722183 -161.670587) (xy 362.732066 -161.671) (xy 385.865116 -161.671) (xy 385.874275 -161.670568)
			(xy 385.891406 -161.664064) (xy 385.905187 -161.651987) (xy 385.90982 -161.644076) (xy 385.935868 -161.596174)
			(xy 385.994105 -161.503979) (xy 386.059053 -161.416382) (xy 386.130352 -161.333872) (xy 386.207603 -161.256906)
			(xy 386.290378 -161.185914) (xy 386.378214 -161.121291) (xy 386.470625 -161.063397) (xy 386.567094 -161.012553)
			(xy 386.667086 -160.969042) (xy 386.770043 -160.933108) (xy 386.875393 -160.90495) (xy 386.982548 -160.884724)
			(xy 387.090914 -160.872543) (xy 387.199886 -160.868475) (xy 387.308858 -160.872543) (xy 387.417224 -160.884724)
			(xy 387.524379 -160.90495) (xy 387.629729 -160.933108) (xy 387.732686 -160.969042) (xy 387.832678 -161.012553)
			(xy 387.929147 -161.063397) (xy 388.021558 -161.121291) (xy 388.109394 -161.185914) (xy 388.192169 -161.256906)
			(xy 388.26942 -161.333872) (xy 388.340719 -161.416382) (xy 388.405667 -161.503979) (xy 388.463904 -161.596174)
			(xy 388.489952 -161.644076) (xy 388.494582 -161.651999) (xy 388.508332 -161.664131) (xy 388.525487 -161.670606)
			(xy 388.534656 -161.671) (xy 396.345918 -161.671) (xy 396.355987 -161.671427) (xy 396.374586 -161.679146)
			(xy 396.381986 -161.685986) (xy 396.733014 -162.037014) (xy 396.739868 -162.044409) (xy 396.74761 -162.063008)
			(xy 396.748 -162.073082) (xy 396.748 -168.888918) (xy 396.74846 -168.898795) (xy 396.755903 -168.917094)
			(xy 396.762478 -168.924478) (xy 397.368014 -169.530014) (xy 397.368522 -169.530522) (xy 397.3759 -169.537112)
			(xy 397.394199 -169.544579) (xy 397.404082 -169.545)
		)
		(stroke
			(width 0)
			(type solid)
		)
		(fill yes)
		(layer "F.Cu")
		(net "P52V_HS1")
	)
	(gr_poly
		(pts
			(xy 405.953722 -169.418) (xy 405.963599 -169.417539) (xy 405.981896 -169.410095) (xy 405.989282 -169.403522)
			(xy 407.451814 -167.94099) (xy 407.452322 -167.940482) (xy 407.458913 -167.933104) (xy 407.466381 -167.914805)
			(xy 407.4668 -167.904922) (xy 407.4668 -160.853882) (xy 407.467227 -160.843813) (xy 407.474946 -160.825214)
			(xy 407.481786 -160.817814) (xy 411.566614 -156.732986) (xy 411.574009 -156.726132) (xy 411.592608 -156.71839)
			(xy 411.602682 -156.718) (xy 435.842918 -156.718) (xy 435.852795 -156.71754) (xy 435.871094 -156.710097)
			(xy 435.878478 -156.703522) (xy 438.617614 -153.964386) (xy 438.618122 -153.963878) (xy 438.624712 -153.9565)
			(xy 438.632179 -153.938201) (xy 438.6326 -153.928318) (xy 438.6326 -133.777482) (xy 438.633027 -133.767413)
			(xy 438.640746 -133.748814) (xy 438.647586 -133.741414) (xy 442.453014 -129.935986) (xy 442.460409 -129.929132)
			(xy 442.479008 -129.92139) (xy 442.489082 -129.921) (xy 472.418918 -129.921) (xy 472.428795 -129.92054)
			(xy 472.447094 -129.913097) (xy 472.454478 -129.906522) (xy 474.203014 -128.157986) (xy 474.203522 -128.157478)
			(xy 474.210112 -128.1501) (xy 474.217579 -128.131801) (xy 474.218 -128.121918) (xy 474.218 -95.133922)
			(xy 474.205808 -95.10395) (xy 474.204792 -95.100394) (xy 474.203014 -95.087186) (xy 474.203014 -79.635096)
			(xy 474.202591 -79.625026) (xy 474.194877 -79.606421) (xy 474.188028 -79.599028) (xy 473.724986 -79.135986)
			(xy 473.717591 -79.129132) (xy 473.698992 -79.12139) (xy 473.688918 -79.121) (xy 471.318082 -79.121)
			(xy 471.308013 -79.121427) (xy 471.289414 -79.129146) (xy 471.282014 -79.135986) (xy 470.930986 -79.487014)
			(xy 470.924132 -79.494409) (xy 470.91639 -79.513008) (xy 470.916 -79.523082) (xy 470.916 -79.91348)
			(xy 470.916471 -79.923352) (xy 470.92393 -79.941635) (xy 470.930478 -79.94904) (xy 471.18016 -80.198722)
			(xy 471.184365 -80.202752) (xy 471.194248 -80.208911) (xy 471.199718 -80.210914) (xy 471.241154 -80.225496)
			(xy 471.321282 -80.261506) (xy 471.397603 -80.305008) (xy 471.469419 -80.355603) (xy 471.536071 -80.412828)
			(xy 471.596951 -80.47616) (xy 471.651501 -80.545019) (xy 471.699222 -80.618775) (xy 471.739678 -80.696753)
			(xy 471.772497 -80.77824) (xy 471.797381 -80.862491) (xy 471.814101 -80.948733) (xy 471.822504 -81.036178)
			(xy 471.823034 -81.080102) (xy 471.822562 -81.122028) (xy 471.814906 -81.205529) (xy 471.799665 -81.287984)
			(xy 471.776968 -81.368705) (xy 471.747003 -81.447019) (xy 471.71002 -81.522275) (xy 471.666328 -81.593843)
			(xy 471.616291 -81.661129) (xy 471.560326 -81.72357) (xy 471.498899 -81.780647) (xy 471.432522 -81.831884)
			(xy 471.361749 -81.876853) (xy 471.324686 -81.896458) (xy 471.316584 -81.901079) (xy 471.304137 -81.91495)
			(xy 471.297468 -81.932352) (xy 471.297 -81.94167) (xy 471.297 -82.776314) (xy 471.297403 -82.785542)
			(xy 471.303959 -82.802793) (xy 471.316211 -82.816594) (xy 471.324178 -82.821272) (xy 471.36018 -82.840667)
			(xy 471.428876 -82.885045) (xy 471.493271 -82.935461) (xy 471.552836 -82.9915) (xy 471.607083 -83.052702)
			(xy 471.655566 -83.118565) (xy 471.697886 -83.188547) (xy 471.733696 -83.262073) (xy 471.762702 -83.33854)
			(xy 471.784665 -83.417319) (xy 471.799404 -83.497762) (xy 471.8068 -83.57921) (xy 471.807286 -83.620102)
			(xy 471.806649 -83.668575) (xy 471.796249 -83.764962) (xy 471.77556 -83.859675) (xy 471.760804 -83.905852)
			(xy 471.756232 -83.919568) (xy 471.762836 -83.947508) (xy 471.847672 -84.032344) (xy 471.875612 -84.038948)
			(xy 471.889328 -84.034376) (xy 471.935508 -84.019633) (xy 472.030223 -83.998959) (xy 472.126606 -83.988546)
			(xy 472.175078 -83.987894) (xy 472.218032 -83.988388) (xy 472.303553 -83.996552) (xy 472.387909 -84.012809)
			(xy 472.470339 -84.03701) (xy 472.550094 -84.068938) (xy 472.626454 -84.108303) (xy 472.698726 -84.154747)
			(xy 472.766256 -84.207852) (xy 472.828432 -84.267135) (xy 472.884691 -84.33206) (xy 472.934523 -84.402039)
			(xy 472.977478 -84.476438) (xy 473.013167 -84.554583) (xy 473.041265 -84.635767) (xy 473.061519 -84.719254)
			(xy 473.073746 -84.804288) (xy 473.077834 -84.8901) (xy 473.073746 -84.975912) (xy 473.061519 -85.060946)
			(xy 473.041265 -85.144433) (xy 473.013167 -85.225617) (xy 472.977478 -85.303762) (xy 472.934523 -85.378161)
			(xy 472.884691 -85.44814) (xy 472.828432 -85.513065) (xy 472.766256 -85.572348) (xy 472.698726 -85.625453)
			(xy 472.626454 -85.671897) (xy 472.550094 -85.711262) (xy 472.470339 -85.74319) (xy 472.387909 -85.767391)
			(xy 472.303553 -85.783648) (xy 472.218032 -85.791812) (xy 472.175078 -85.79231) (xy 472.126605 -85.791672)
			(xy 472.030219 -85.781271) (xy 471.935506 -85.76058) (xy 471.889328 -85.745828) (xy 471.875612 -85.741256)
			(xy 471.847672 -85.74786) (xy 471.762836 -85.832696) (xy 471.756232 -85.860636) (xy 471.760804 -85.874352)
			(xy 471.775547 -85.920532) (xy 471.796218 -86.015247) (xy 471.806629 -86.11163) (xy 471.807286 -86.160102)
			(xy 471.806649 -86.208575) (xy 471.796249 -86.304962) (xy 471.77556 -86.399675) (xy 471.760804 -86.445852)
			(xy 471.756232 -86.459568) (xy 471.762836 -86.487508) (xy 471.847672 -86.572344) (xy 471.875612 -86.578948)
			(xy 471.889328 -86.574376) (xy 471.935508 -86.559633) (xy 472.030223 -86.538959) (xy 472.126606 -86.528546)
			(xy 472.175078 -86.527894) (xy 472.218032 -86.528388) (xy 472.303553 -86.536552) (xy 472.387909 -86.552809)
			(xy 472.470339 -86.57701) (xy 472.550094 -86.608938) (xy 472.626454 -86.648303) (xy 472.698726 -86.694747)
			(xy 472.766256 -86.747852) (xy 472.828432 -86.807135) (xy 472.884691 -86.87206) (xy 472.934523 -86.942039)
			(xy 472.977478 -87.016438) (xy 473.013167 -87.094583) (xy 473.041265 -87.175767) (xy 473.061519 -87.259254)
			(xy 473.073746 -87.344288) (xy 473.077834 -87.4301) (xy 473.073746 -87.515912) (xy 473.061519 -87.600946)
			(xy 473.041265 -87.684433) (xy 473.013167 -87.765617) (xy 472.977478 -87.843762) (xy 472.934523 -87.918161)
			(xy 472.884691 -87.98814) (xy 472.828432 -88.053065) (xy 472.766256 -88.112348) (xy 472.698726 -88.165453)
			(xy 472.626454 -88.211897) (xy 472.550094 -88.251262) (xy 472.470339 -88.28319) (xy 472.387909 -88.307391)
			(xy 472.303553 -88.323648) (xy 472.218032 -88.331812) (xy 472.175078 -88.33231) (xy 472.126605 -88.331672)
			(xy 472.030219 -88.321271) (xy 471.935506 -88.30058) (xy 471.889328 -88.285828) (xy 471.875612 -88.281256)
			(xy 471.847672 -88.28786) (xy 471.762836 -88.372696) (xy 471.756232 -88.400636) (xy 471.760804 -88.414352)
			(xy 471.775547 -88.460532) (xy 471.796218 -88.555247) (xy 471.806629 -88.65163) (xy 471.807286 -88.700102)
			(xy 471.806819 -88.741792) (xy 471.799126 -88.824815) (xy 471.783804 -88.906774) (xy 471.760986 -88.986971)
			(xy 471.730865 -89.064719) (xy 471.6937 -89.139357) (xy 471.649805 -89.210247) (xy 471.599557 -89.276784)
			(xy 471.543384 -89.338401) (xy 471.481766 -89.394573) (xy 471.415227 -89.444819) (xy 471.344336 -89.488711)
			(xy 471.269697 -89.525875) (xy 471.191948 -89.555994) (xy 471.111751 -89.57881) (xy 471.029791 -89.594129)
			(xy 470.946768 -89.60182) (xy 470.905078 -89.60231) (xy 470.904824 -89.60231) (xy 470.862414 -89.601826)
			(xy 470.777969 -89.593866) (xy 470.694643 -89.578015) (xy 470.613174 -89.554413) (xy 470.534279 -89.523267)
			(xy 470.458657 -89.484854) (xy 470.386974 -89.439512) (xy 470.319863 -89.387641) (xy 470.257918 -89.3297)
			(xy 470.229438 -89.298272) (xy 470.225882 -89.294208) (xy 470.213182 -89.28481) (xy 470.208864 -89.281508)
			(xy 470.194894 -89.274904) (xy 470.187688 -89.271837) (xy 470.172172 -89.269765) (xy 470.164414 -89.27084)
			(xy 470.095834 -89.283032) (xy 470.086436 -89.284556) (xy 470.074752 -89.291414) (xy 470.064592 -89.299288)
			(xy 470.046558 -89.317322) (xy 470.042748 -89.327736) (xy 470.021128 -89.384083) (xy 469.971319 -89.494027)
			(xy 469.914221 -89.600368) (xy 469.850094 -89.702624) (xy 469.779227 -89.80033) (xy 469.701942 -89.893043)
			(xy 469.618591 -89.980343) (xy 469.529551 -90.061832) (xy 469.435227 -90.137142) (xy 469.336046 -90.20593)
			(xy 469.232459 -90.267885) (xy 469.124936 -90.322724) (xy 469.013965 -90.3702) (xy 468.900049 -90.410097)
			(xy 468.783705 -90.442234) (xy 468.665461 -90.466465) (xy 468.545855 -90.482679) (xy 468.425428 -90.490804)
			(xy 468.365078 -90.49131) (xy 468.306456 -90.49083) (xy 468.189463 -90.483161) (xy 468.073223 -90.467856)
			(xy 467.958232 -90.444981) (xy 467.844983 -90.414635) (xy 467.733962 -90.376947) (xy 467.625643 -90.332079)
			(xy 467.52049 -90.280223) (xy 467.418955 -90.2216) (xy 467.32147 -90.156462) (xy 467.228455 -90.085088)
			(xy 467.140307 -90.007783) (xy 467.057403 -89.924879) (xy 466.9801 -89.83673) (xy 466.908726 -89.743713)
			(xy 466.84359 -89.646228) (xy 466.784968 -89.544692) (xy 466.733113 -89.439539) (xy 466.688245 -89.33122)
			(xy 466.650559 -89.220198) (xy 466.620214 -89.106949) (xy 466.597341 -88.991958) (xy 466.582038 -88.875717)
			(xy 466.574369 -88.758724) (xy 466.57387 -88.700102) (xy 466.574376 -88.639752) (xy 466.582502 -88.519326)
			(xy 466.598717 -88.39972) (xy 466.622949 -88.281477) (xy 466.655086 -88.165134) (xy 466.694984 -88.051218)
			(xy 466.74246 -87.940247) (xy 466.7973 -87.832725) (xy 466.859255 -87.729138) (xy 466.928043 -87.629958)
			(xy 467.003353 -87.535634) (xy 467.084842 -87.446595) (xy 467.172141 -87.363244) (xy 467.264854 -87.285959)
			(xy 467.36256 -87.215092) (xy 467.464815 -87.150964) (xy 467.571155 -87.093866) (xy 467.681099 -87.044057)
			(xy 467.737444 -87.022432) (xy 467.747858 -87.018622) (xy 467.767924 -86.998556) (xy 467.773169 -86.992888)
			(xy 467.780274 -86.979183) (xy 467.781894 -86.971632) (xy 467.79434 -86.901274) (xy 467.79434 -86.90102)
			(xy 467.79561 -86.895432) (xy 467.794594 -86.886542) (xy 467.794093 -86.882407) (xy 467.791921 -86.874366)
			(xy 467.790276 -86.87054) (xy 467.783672 -86.856316) (xy 467.78037 -86.851998) (xy 467.770972 -86.839298)
			(xy 467.766908 -86.835742) (xy 467.735464 -86.807254) (xy 467.677493 -86.745288) (xy 467.625595 -86.678155)
			(xy 467.580228 -86.606446) (xy 467.541793 -86.530795) (xy 467.51063 -86.45187) (xy 467.487013 -86.370368)
			(xy 467.471152 -86.287009) (xy 467.463186 -86.202529) (xy 467.463186 -86.117674) (xy 467.471151 -86.033194)
			(xy 467.487012 -85.949835) (xy 467.510629 -85.868333) (xy 467.541792 -85.789407) (xy 467.580226 -85.713756)
			(xy 467.625593 -85.642047) (xy 467.677491 -85.574914) (xy 467.735462 -85.512948) (xy 467.766908 -85.484462)
			(xy 467.770972 -85.480906) (xy 467.78037 -85.468206) (xy 467.783672 -85.463888) (xy 467.790276 -85.449918)
			(xy 467.793348 -85.442712) (xy 467.795428 -85.427195) (xy 467.79434 -85.419438) (xy 467.782148 -85.350858)
			(xy 467.780624 -85.34146) (xy 467.773766 -85.329776) (xy 467.765892 -85.319616) (xy 467.747858 -85.301582)
			(xy 467.737444 -85.297772) (xy 467.68081 -85.276047) (xy 467.570325 -85.225951) (xy 467.463483 -85.168494)
			(xy 467.360775 -85.103938) (xy 467.26267 -85.032579) (xy 467.16962 -84.954746) (xy 467.082049 -84.870793)
			(xy 467.000361 -84.781108) (xy 466.924929 -84.686099) (xy 466.856099 -84.586205) (xy 466.794187 -84.481881)
			(xy 466.739477 -84.373607) (xy 466.692219 -84.261878) (xy 466.652631 -84.147208) (xy 466.620893 -84.030122)
			(xy 466.597151 -83.911156) (xy 466.581514 -83.790856) (xy 466.574054 -83.669774) (xy 466.574804 -83.548465)
			(xy 466.583763 -83.427484) (xy 466.600887 -83.307387) (xy 466.626099 -83.188725) (xy 466.659284 -83.07204)
			(xy 466.700289 -82.957868) (xy 466.748926 -82.846734) (xy 466.804972 -82.739145) (xy 466.86817 -82.635595)
			(xy 466.938231 -82.53656) (xy 467.014833 -82.442492) (xy 467.097625 -82.353825) (xy 467.14156 -82.312002)
			(xy 467.148786 -82.304553) (xy 467.157046 -82.285537) (xy 467.157562 -82.275172) (xy 467.157562 -78.380844)
			(xy 467.157128 -78.370779) (xy 467.149395 -78.352193) (xy 467.142576 -78.344776) (xy 466.181186 -77.383386)
			(xy 466.174332 -77.375991) (xy 466.16659 -77.357392) (xy 466.1662 -77.347318) (xy 466.1662 -66.848482)
			(xy 466.166627 -66.838413) (xy 466.174346 -66.819814) (xy 466.181186 -66.812414) (xy 467.751414 -65.242186)
			(xy 467.758809 -65.235332) (xy 467.777408 -65.22759) (xy 467.787482 -65.2272) (xy 474.019118 -65.2272)
			(xy 474.028995 -65.22674) (xy 474.047294 -65.219297) (xy 474.054678 -65.212722) (xy 474.188028 -65.079372)
			(xy 474.188536 -65.078864) (xy 474.195123 -65.071484) (xy 474.202582 -65.053185) (xy 474.203014 -65.043304)
			(xy 474.203014 -20.591526) (xy 474.202578 -20.581461) (xy 474.194846 -20.562875) (xy 474.188028 -20.555458)
			(xy 472.624404 -18.991834) (xy 472.610942 -18.991834) (xy 471.945462 -18.326354) (xy 471.93835 -18.318988)
			(xy 471.919554 -18.311368) (xy 442.144658 -18.311368) (xy 442.134592 -18.310937) (xy 442.116001 -18.303208)
			(xy 442.10859 -18.296382) (xy 438.172352 -14.360144) (xy 438.165509 -14.352745) (xy 438.157786 -14.334146)
			(xy 438.157366 -14.324076) (xy 438.157366 -4.099052) (xy 438.156933 -4.088986) (xy 438.149203 -4.070398)
			(xy 438.14238 -4.062984) (xy 435.466744 -1.387348) (xy 435.459632 -1.379982) (xy 435.440836 -1.372362)
			(xy 380.253494 -1.372362) (xy 380.243972 -1.372759) (xy 380.226245 -1.379716) (xy 380.212283 -1.392667)
			(xy 380.207774 -1.401064) (xy 380.169928 -1.479042) (xy 380.166077 -1.488015) (xy 380.164774 -1.50748)
			(xy 380.167388 -1.516888) (xy 380.167388 -1.517142) (xy 380.173484 -1.536446) (xy 380.179072 -1.543558)
			(xy 380.214222 -1.59001) (xy 380.278868 -1.686929) (xy 380.336789 -1.788011) (xy 380.387716 -1.89279)
			(xy 380.431415 -2.000784) (xy 380.467686 -2.111495) (xy 380.496359 -2.224412) (xy 380.517304 -2.339014)
			(xy 380.530423 -2.454773) (xy 380.535657 -2.571156) (xy 380.532981 -2.687626) (xy 380.522407 -2.803645)
			(xy 380.503985 -2.91868) (xy 380.477798 -3.032199) (xy 380.443969 -3.143679) (xy 380.402652 -3.252607)
			(xy 380.354038 -3.35848) (xy 380.298352 -3.46081) (xy 380.23585 -3.559125) (xy 380.16682 -3.652972)
			(xy 380.091581 -3.741918) (xy 380.01048 -3.825554) (xy 379.923889 -3.903493) (xy 379.83221 -3.975376)
			(xy 379.735863 -4.040872) (xy 379.635295 -4.099679) (xy 379.530967 -4.151525) (xy 379.423361 -4.196172)
			(xy 379.312974 -4.233415) (xy 379.200314 -4.26308) (xy 379.0859 -4.285032) (xy 378.970261 -4.299168)
			(xy 378.853928 -4.305425) (xy 378.73744 -4.303773) (xy 378.621331 -4.29422) (xy 378.506139 -4.276809)
			(xy 378.392394 -4.251622) (xy 378.280621 -4.218774) (xy 378.171334 -4.178416) (xy 378.065038 -4.130736)
			(xy 377.962222 -4.075951) (xy 377.863361 -4.014316) (xy 377.768911 -3.946114) (xy 377.679307 -3.87166)
			(xy 377.636786 -3.831844) (xy 377.633144 -3.82849) (xy 377.624832 -3.823112) (xy 377.620276 -3.821176)
			(xy 377.609862 -3.817112) (xy 377.60541 -3.815441) (xy 377.596074 -3.813645) (xy 377.59132 -3.813556)
			(xy 377.577096 -3.813556) (xy 377.525026 -3.825494) (xy 377.524518 -3.825494) (xy 377.512072 -3.828542)
			(xy 377.505474 -3.83032) (xy 377.493496 -3.836888) (xy 377.48845 -3.841496) (xy 377.477528 -3.850894)
			(xy 377.474853 -3.853257) (xy 377.470132 -3.858608) (xy 377.46813 -3.861562) (xy 377.459748 -3.874516)
			(xy 377.457716 -3.879342) (xy 377.436951 -3.931783) (xy 377.388996 -4.033885) (xy 377.333946 -4.132341)
			(xy 377.272074 -4.22666) (xy 377.20369 -4.316371) (xy 377.129137 -4.401023) (xy 377.048788 -4.480195)
			(xy 376.963043 -4.55349) (xy 376.872332 -4.620541) (xy 376.77711 -4.681013) (xy 376.677851 -4.734604)
			(xy 376.575053 -4.781045) (xy 376.469229 -4.820104) (xy 376.36091 -4.851586) (xy 376.250636 -4.875334)
			(xy 376.138959 -4.891228) (xy 376.026439 -4.899189) (xy 375.970038 -4.89966) (xy 375.912851 -4.899152)
			(xy 375.798773 -4.890952) (xy 375.685575 -4.874597) (xy 375.57384 -4.850172) (xy 375.464143 -4.817803)
			(xy 375.357048 -4.777657) (xy 375.253105 -4.729938) (xy 375.152848 -4.674894) (xy 375.056795 -4.612806)
			(xy 374.965437 -4.543995) (xy 374.879245 -4.468814) (xy 374.798663 -4.387649) (xy 374.724104 -4.300919)
			(xy 374.655952 -4.209068) (xy 374.594558 -4.11257) (xy 374.540237 -4.01192) (xy 374.493268 -3.907636)
			(xy 374.453893 -3.800254) (xy 374.422315 -3.690327) (xy 374.40997 -3.634486) (xy 374.407505 -3.624935)
			(xy 374.396501 -3.608587) (xy 374.38015 -3.597588) (xy 374.3706 -3.595116) (xy 374.3206 -3.584302)
			(xy 374.221971 -3.557105) (xy 374.173496 -3.54076) (xy 374.169178 -3.539236) (xy 374.163082 -3.537966)
			(xy 374.157768 -3.537115) (xy 374.147012 -3.537367) (xy 374.141746 -3.538474) (xy 374.13565 -3.539998)
			(xy 374.130062 -3.542792) (xy 374.109234 -3.551936) (xy 374.100673 -3.555633) (xy 374.086739 -3.568002)
			(xy 374.082056 -3.576066) (xy 374.079262 -3.5814) (xy 374.0785 -3.583432) (xy 374.063287 -3.617582)
			(xy 374.026667 -3.682762) (xy 373.983364 -3.743707) (xy 373.933862 -3.799735) (xy 373.878718 -3.850219)
			(xy 373.818547 -3.894592) (xy 373.754024 -3.932358) (xy 373.685872 -3.963095) (xy 373.614852 -3.986457)
			(xy 373.541762 -4.002184) (xy 373.467419 -4.010099) (xy 373.430038 -4.01066) (xy 373.393082 -4.010178)
			(xy 373.319573 -4.002456) (xy 373.247275 -3.987093) (xy 373.176978 -3.964257) (xy 373.109454 -3.934198)
			(xy 373.045441 -3.897245) (xy 372.985642 -3.853804) (xy 372.930711 -3.80435) (xy 372.881251 -3.749425)
			(xy 372.837802 -3.689631) (xy 372.800842 -3.625623) (xy 372.770774 -3.558102) (xy 372.747929 -3.487808)
			(xy 372.732557 -3.415512) (xy 372.724826 -3.342004) (xy 372.724426 -3.305048) (xy 372.724913 -3.267662)
			(xy 372.732814 -3.193309) (xy 372.748532 -3.120209) (xy 372.771891 -3.04918) (xy 372.802629 -2.981019)
			(xy 372.840403 -2.91649) (xy 372.884787 -2.856317) (xy 372.935285 -2.801174) (xy 372.99133 -2.751679)
			(xy 373.052294 -2.708388) (xy 373.117494 -2.671785) (xy 373.151654 -2.656586) (xy 373.154194 -2.65557)
			(xy 373.159528 -2.652776) (xy 373.166122 -2.648826) (xy 373.17673 -2.63771) (xy 373.180356 -2.630932)
			(xy 373.180864 -2.629916) (xy 373.196358 -2.59715) (xy 373.197374 -2.589276) (xy 373.198644 -2.581148)
			(xy 373.195342 -2.563876) (xy 373.194072 -2.56032) (xy 373.176929 -2.509745) (xy 373.148643 -2.406761)
			(xy 373.127311 -2.302114) (xy 373.113029 -2.196275) (xy 373.105861 -2.089717) (xy 373.105426 -2.036318)
			(xy 373.105426 -2.034286) (xy 373.105887 -1.981501) (xy 373.112935 -1.876167) (xy 373.126933 -1.771529)
			(xy 373.147819 -1.668046) (xy 373.175503 -1.566171) (xy 373.192294 -1.516126) (xy 373.192548 -1.515618)
			(xy 373.195088 -1.50749) (xy 373.196612 -1.497076) (xy 373.196612 -1.488186) (xy 373.19632 -1.480312)
			(xy 373.191542 -1.465306) (xy 373.187214 -1.458722) (xy 373.140732 -1.393698) (xy 373.13362 -1.383538)
			(xy 373.111776 -1.372362) (xy 372.913148 -1.372362) (xy 372.902741 -1.372852) (xy 372.883633 -1.381101)
			(xy 372.869374 -1.396262) (xy 372.865396 -1.40589) (xy 372.865396 -2.613152) (xy 372.864859 -2.629849)
			(xy 372.856236 -2.662112) (xy 372.839564 -2.691047) (xy 372.815978 -2.714687) (xy 372.787081 -2.731425)
			(xy 372.754838 -2.740121) (xy 372.738142 -2.74066) (xy 371.896132 -2.74066) (xy 371.886117 -2.741142)
			(xy 371.867608 -2.748794) (xy 371.853435 -2.762947) (xy 371.845756 -2.781446) (xy 371.845332 -2.79146)
			(xy 371.845332 -3.796792) (xy 371.845986 -3.80801) (xy 371.855614 -3.828286) (xy 371.863874 -3.835908)
			(xy 371.864636 -3.836416) (xy 371.927374 -3.884168) (xy 371.934157 -3.888918) (xy 371.949834 -3.894224)
			(xy 371.958108 -3.894582) (xy 371.968776 -3.894582) (xy 371.975126 -3.892804) (xy 372.019406 -3.881866)
			(xy 372.109861 -3.870147) (xy 372.155466 -3.869436) (xy 372.160038 -3.869436) (xy 372.198263 -3.869956)
			(xy 372.274265 -3.878225) (xy 372.348927 -3.894663) (xy 372.421375 -3.919077) (xy 372.490758 -3.95118)
			(xy 372.556264 -3.990597) (xy 372.617124 -4.036865) (xy 372.672625 -4.089441) (xy 372.722117 -4.14771)
			(xy 372.765018 -4.210988) (xy 372.800827 -4.278533) (xy 372.829123 -4.349554) (xy 372.849575 -4.423218)
			(xy 372.861943 -4.498662) (xy 372.866082 -4.575) (xy 372.861943 -4.651338) (xy 372.849575 -4.726782)
			(xy 372.829123 -4.800446) (xy 372.800827 -4.871467) (xy 372.765018 -4.939012) (xy 372.722117 -5.00229)
			(xy 372.672625 -5.060559) (xy 372.617124 -5.113135) (xy 372.556264 -5.159403) (xy 372.490758 -5.19882)
			(xy 372.421375 -5.230923) (xy 372.348927 -5.255337) (xy 372.274265 -5.271775) (xy 372.198263 -5.280044)
			(xy 372.160038 -5.28066) (xy 372.128627 -5.280296) (xy 372.066058 -5.27467) (xy 372.004236 -5.263503)
			(xy 371.973856 -5.255514) (xy 371.962172 -5.252212) (xy 371.939058 -5.256784) (xy 371.865398 -5.313172)
			(xy 371.856412 -5.320765) (xy 371.845957 -5.34181) (xy 371.845332 -5.353558) (xy 371.845332 -5.845048)
			(xy 372.723926 -5.845048) (xy 372.727926 -5.769993) (xy 372.739881 -5.695788) (xy 372.759656 -5.623275)
			(xy 372.787027 -5.553274) (xy 372.821684 -5.486579) (xy 372.863233 -5.423946) (xy 372.911205 -5.366084)
			(xy 372.965055 -5.313648) (xy 373.024173 -5.267234) (xy 373.087891 -5.227367) (xy 373.155484 -5.194498)
			(xy 373.226189 -5.169) (xy 373.299203 -5.151162) (xy 373.3737 -5.141187) (xy 373.448835 -5.139186)
			(xy 373.523757 -5.145183) (xy 373.597617 -5.159109) (xy 373.669579 -5.180808) (xy 373.738826 -5.210032)
			(xy 373.804575 -5.246452) (xy 373.86608 -5.289654) (xy 373.922644 -5.339149) (xy 373.973627 -5.394376)
			(xy 374.018451 -5.454709) (xy 374.056608 -5.519465) (xy 374.087666 -5.58791) (xy 374.111273 -5.659268)
			(xy 374.127161 -5.732731) (xy 374.13515 -5.807467) (xy 374.13565 -5.845048) (xy 375.263671 -5.845048)
			(xy 375.267673 -5.769966) (xy 375.279632 -5.695734) (xy 375.299415 -5.623195) (xy 375.326796 -5.553169)
			(xy 375.361465 -5.48645) (xy 375.403029 -5.423794) (xy 375.451018 -5.365911) (xy 375.504887 -5.313457)
			(xy 375.564027 -5.267026) (xy 375.627767 -5.227144) (xy 375.695385 -5.194264) (xy 375.766116 -5.168757)
			(xy 375.839156 -5.150912) (xy 375.91368 -5.140933) (xy 375.988842 -5.138931) (xy 376.063791 -5.14493)
			(xy 376.137678 -5.158862) (xy 376.209665 -5.180568) (xy 376.278937 -5.209804) (xy 376.34471 -5.246236)
			(xy 376.406237 -5.289454) (xy 376.462822 -5.338967) (xy 376.513823 -5.394213) (xy 376.558663 -5.454568)
			(xy 376.596834 -5.519347) (xy 376.627903 -5.587817) (xy 376.651518 -5.659201) (xy 376.667412 -5.732691)
			(xy 376.675404 -5.807454) (xy 376.675904 -5.845048) (xy 376.675404 -5.882642) (xy 376.667412 -5.957405)
			(xy 376.651518 -6.030895) (xy 376.627903 -6.102279) (xy 376.596834 -6.170749) (xy 376.558663 -6.235528)
			(xy 376.513823 -6.295883) (xy 376.462822 -6.351129) (xy 376.406237 -6.400642) (xy 376.34471 -6.44386)
			(xy 376.278937 -6.480292) (xy 376.209665 -6.509528) (xy 376.137678 -6.531234) (xy 376.063791 -6.545166)
			(xy 375.988842 -6.551165) (xy 375.91368 -6.549163) (xy 375.839156 -6.539184) (xy 375.766116 -6.521339)
			(xy 375.695385 -6.495832) (xy 375.627767 -6.462952) (xy 375.564027 -6.42307) (xy 375.504887 -6.376639)
			(xy 375.451018 -6.324185) (xy 375.403029 -6.266302) (xy 375.361465 -6.203646) (xy 375.326796 -6.136927)
			(xy 375.299415 -6.066901) (xy 375.279632 -5.994362) (xy 375.267673 -5.92013) (xy 375.263671 -5.845048)
			(xy 374.13565 -5.845048) (xy 374.13515 -5.882629) (xy 374.127161 -5.957365) (xy 374.111273 -6.030828)
			(xy 374.087666 -6.102186) (xy 374.056608 -6.170631) (xy 374.018451 -6.235387) (xy 373.973627 -6.29572)
			(xy 373.922644 -6.350947) (xy 373.86608 -6.400442) (xy 373.804575 -6.443644) (xy 373.738826 -6.480064)
			(xy 373.669579 -6.509288) (xy 373.597617 -6.530987) (xy 373.523757 -6.544913) (xy 373.448835 -6.55091)
			(xy 373.3737 -6.548909) (xy 373.299203 -6.538934) (xy 373.226189 -6.521096) (xy 373.155484 -6.495598)
			(xy 373.087891 -6.462729) (xy 373.024173 -6.422862) (xy 372.965055 -6.376448) (xy 372.911205 -6.324012)
			(xy 372.863233 -6.26615) (xy 372.821684 -6.203517) (xy 372.787027 -6.136822) (xy 372.759656 -6.066821)
			(xy 372.739881 -5.994308) (xy 372.727926 -5.920103) (xy 372.723926 -5.845048) (xy 371.845332 -5.845048)
			(xy 371.845332 -7.689596) (xy 371.84491 -7.699667) (xy 371.837201 -7.718276) (xy 371.830346 -7.725664)
			(xy 370.340636 -9.215374) (xy 370.333235 -9.222213) (xy 370.314637 -9.229928) (xy 370.304568 -9.23036)
			(xy 61.067442 -9.23036) (xy 61.057377 -9.229925) (xy 61.038792 -9.222191) (xy 61.031374 -9.215374)
			(xy 53.989986 -2.173986) (xy 53.982874 -2.16662) (xy 53.964078 -2.159) (xy 4.466082 -2.159) (xy 4.456013 -2.159427)
			(xy 4.437414 -2.167146) (xy 4.430014 -2.173986) (xy 2.173986 -4.430014) (xy 2.16662 -4.437126) (xy 2.159 -4.455922)
			(xy 2.159 -14.732) (xy 80.135982 -14.732) (xy 80.140053 -14.676378) (xy 80.152179 -14.621941) (xy 80.172102 -14.56985)
			(xy 80.199398 -14.521215) (xy 80.233484 -14.477072) (xy 80.273633 -14.438363) (xy 80.318991 -14.405912)
			(xy 80.368591 -14.380411) (xy 80.421375 -14.362404) (xy 80.476218 -14.352274) (xy 80.531952 -14.350237)
			(xy 80.587389 -14.356337) (xy 80.641346 -14.370443) (xy 80.692675 -14.392255) (xy 80.740281 -14.421309)
			(xy 80.783149 -14.456984) (xy 80.820366 -14.498521) (xy 80.851139 -14.545034) (xy 80.874811 -14.595531)
			(xy 80.890879 -14.648938) (xy 80.898999 -14.704114) (xy 80.899508 -14.732) (xy 80.898999 -14.759886)
			(xy 80.890879 -14.815062) (xy 80.874811 -14.868469) (xy 80.851139 -14.918966) (xy 80.820366 -14.965479)
			(xy 80.783149 -15.007016) (xy 80.740281 -15.042691) (xy 80.692675 -15.071745) (xy 80.641346 -15.093557)
			(xy 80.587389 -15.107663) (xy 80.531952 -15.113763) (xy 80.476218 -15.111726) (xy 80.421375 -15.101596)
			(xy 80.368591 -15.083589) (xy 80.318991 -15.058088) (xy 80.273633 -15.025637) (xy 80.233484 -14.986928)
			(xy 80.199398 -14.942785) (xy 80.172102 -14.89415) (xy 80.152179 -14.842059) (xy 80.140053 -14.787622)
			(xy 80.135982 -14.732) (xy 2.159 -14.732) (xy 2.159 -60.099956) (xy 12.484612 -60.099956) (xy 12.488641 -59.957649)
			(xy 12.500714 -59.815799) (xy 12.520793 -59.674858) (xy 12.548814 -59.53528) (xy 12.584686 -59.39751)
			(xy 12.628296 -59.26199) (xy 12.679502 -59.129155) (xy 12.738142 -58.999429) (xy 12.804027 -58.873229)
			(xy 12.876946 -58.750958) (xy 12.956666 -58.633008) (xy 13.042932 -58.519758) (xy 13.135466 -58.411569)
			(xy 13.233973 -58.308789) (xy 13.338137 -58.211746) (xy 13.447624 -58.120752) (xy 13.562084 -58.036098)
			(xy 13.681149 -57.958055) (xy 13.80444 -57.886874) (xy 13.93156 -57.822781) (xy 14.062102 -57.765983)
			(xy 14.195649 -57.716661) (xy 14.331773 -57.674974) (xy 14.470036 -57.641055) (xy 14.609997 -57.615012)
			(xy 14.751208 -57.596929) (xy 14.893215 -57.586864) (xy 15.035564 -57.58485) (xy 15.1778 -57.590892)
			(xy 15.319465 -57.604971) (xy 15.460107 -57.627043) (xy 15.599276 -57.657036) (xy 15.736524 -57.694854)
			(xy 15.871413 -57.740377) (xy 16.003511 -57.793458) (xy 16.132394 -57.853928) (xy 16.257649 -57.921592)
			(xy 16.378876 -57.996234) (xy 16.495685 -58.077615) (xy 16.607704 -58.165475) (xy 16.714572 -58.259531)
			(xy 16.815948 -58.359482) (xy 16.911507 -58.465009) (xy 17.000942 -58.575773) (xy 17.083968 -58.691419)
			(xy 17.160319 -58.811577) (xy 17.229749 -58.935863) (xy 17.292036 -59.063877) (xy 17.346981 -59.19521)
			(xy 17.394408 -59.329441) (xy 17.434165 -59.466141) (xy 17.466124 -59.604871) (xy 17.490184 -59.745187)
			(xy 17.506266 -59.886639) (xy 17.514321 -60.028774) (xy 17.514824 -60.099956) (xy 17.514321 -60.171138)
			(xy 17.506266 -60.313273) (xy 17.490184 -60.454725) (xy 17.466124 -60.595041) (xy 17.434165 -60.733771)
			(xy 17.394408 -60.870471) (xy 17.346981 -61.004702) (xy 17.292036 -61.136035) (xy 17.229749 -61.264049)
			(xy 17.160319 -61.388335) (xy 17.083968 -61.508493) (xy 17.000942 -61.624139) (xy 16.911507 -61.734903)
			(xy 16.815948 -61.84043) (xy 16.714572 -61.940381) (xy 16.607704 -62.034437) (xy 16.495685 -62.122297)
			(xy 16.378876 -62.203678) (xy 16.257649 -62.27832) (xy 16.132394 -62.345984) (xy 16.003511 -62.406454)
			(xy 15.871413 -62.459535) (xy 15.736524 -62.505058) (xy 15.599276 -62.542876) (xy 15.460107 -62.572869)
			(xy 15.319465 -62.594941) (xy 15.1778 -62.60902) (xy 15.035564 -62.615062) (xy 14.893215 -62.613048)
			(xy 14.751208 -62.602983) (xy 14.609997 -62.5849) (xy 14.470036 -62.558857) (xy 14.331773 -62.524938)
			(xy 14.195649 -62.483251) (xy 14.062102 -62.433929) (xy 13.93156 -62.377131) (xy 13.80444 -62.313038)
			(xy 13.681149 -62.241857) (xy 13.562084 -62.163814) (xy 13.447624 -62.07916) (xy 13.338137 -61.988166)
			(xy 13.233973 -61.891123) (xy 13.135466 -61.788343) (xy 13.042932 -61.680154) (xy 12.956666 -61.566904)
			(xy 12.876946 -61.448954) (xy 12.804027 -61.326683) (xy 12.738142 -61.200483) (xy 12.679502 -61.070757)
			(xy 12.628296 -60.937922) (xy 12.584686 -60.802402) (xy 12.548814 -60.664632) (xy 12.520793 -60.525054)
			(xy 12.500714 -60.384113) (xy 12.488641 -60.242263) (xy 12.484612 -60.099956) (xy 2.159 -60.099956)
			(xy 2.159 -104.544876) (xy 12.484612 -104.544876) (xy 12.488641 -104.402569) (xy 12.500714 -104.260719)
			(xy 12.520793 -104.119778) (xy 12.548814 -103.9802) (xy 12.584686 -103.84243) (xy 12.628296 -103.70691)
			(xy 12.679502 -103.574075) (xy 12.738142 -103.444349) (xy 12.804027 -103.318149) (xy 12.876946 -103.195878)
			(xy 12.956666 -103.077928) (xy 13.042932 -102.964678) (xy 13.135466 -102.856489) (xy 13.233973 -102.753709)
			(xy 13.338137 -102.656666) (xy 13.447624 -102.565672) (xy 13.562084 -102.481018) (xy 13.681149 -102.402975)
			(xy 13.80444 -102.331794) (xy 13.93156 -102.267701) (xy 14.062102 -102.210903) (xy 14.195649 -102.161581)
			(xy 14.331773 -102.119894) (xy 14.470036 -102.085975) (xy 14.609997 -102.059932) (xy 14.751208 -102.041849)
			(xy 14.893215 -102.031784) (xy 15.035564 -102.02977) (xy 15.1778 -102.035812) (xy 15.319465 -102.049891)
			(xy 15.460107 -102.071963) (xy 15.599276 -102.101956) (xy 15.736524 -102.139774) (xy 15.871413 -102.185297)
			(xy 16.003511 -102.238378) (xy 16.132394 -102.298848) (xy 16.257649 -102.366512) (xy 16.378876 -102.441154)
			(xy 16.495685 -102.522535) (xy 16.607704 -102.610395) (xy 16.714572 -102.704451) (xy 16.815948 -102.804402)
			(xy 16.911507 -102.909929) (xy 17.000942 -103.020693) (xy 17.083968 -103.136339) (xy 17.160319 -103.256497)
			(xy 17.229749 -103.380783) (xy 17.292036 -103.508797) (xy 17.346981 -103.64013) (xy 17.394408 -103.774361)
			(xy 17.434165 -103.911061) (xy 17.466124 -104.049791) (xy 17.490184 -104.190107) (xy 17.506266 -104.331559)
			(xy 17.514321 -104.473694) (xy 17.514824 -104.544876) (xy 17.514321 -104.616058) (xy 17.506266 -104.758193)
			(xy 17.490184 -104.899645) (xy 17.466124 -105.039961) (xy 17.434165 -105.178691) (xy 17.394408 -105.315391)
			(xy 17.346981 -105.449622) (xy 17.292036 -105.580955) (xy 17.229749 -105.708969) (xy 17.160319 -105.833255)
			(xy 17.083968 -105.953413) (xy 17.000942 -106.069059) (xy 16.911507 -106.179823) (xy 16.815948 -106.28535)
			(xy 16.714572 -106.385301) (xy 16.607704 -106.479357) (xy 16.495685 -106.567217) (xy 16.378876 -106.648598)
			(xy 16.257649 -106.72324) (xy 16.132394 -106.790904) (xy 16.003511 -106.851374) (xy 15.871413 -106.904455)
			(xy 15.736524 -106.949978) (xy 15.599276 -106.987796) (xy 15.460107 -107.017789) (xy 15.319465 -107.039861)
			(xy 15.1778 -107.05394) (xy 15.035564 -107.059982) (xy 14.893215 -107.057968) (xy 14.751208 -107.047903)
			(xy 14.609997 -107.02982) (xy 14.470036 -107.003777) (xy 14.331773 -106.969858) (xy 14.195649 -106.928171)
			(xy 14.062102 -106.878849) (xy 13.93156 -106.822051) (xy 13.80444 -106.757958) (xy 13.681149 -106.686777)
			(xy 13.562084 -106.608734) (xy 13.447624 -106.52408) (xy 13.338137 -106.433086) (xy 13.233973 -106.336043)
			(xy 13.135466 -106.233263) (xy 13.042932 -106.125074) (xy 12.956666 -106.011824) (xy 12.876946 -105.893874)
			(xy 12.804027 -105.771603) (xy 12.738142 -105.645403) (xy 12.679502 -105.515677) (xy 12.628296 -105.382842)
			(xy 12.584686 -105.247322) (xy 12.548814 -105.109552) (xy 12.520793 -104.969974) (xy 12.500714 -104.829033)
			(xy 12.488641 -104.687183) (xy 12.484612 -104.544876) (xy 2.159 -104.544876) (xy 2.159 -153.497669)
			(xy 23.55798 -153.497669) (xy 23.55798 -153.384115) (xy 23.565901 -153.270839) (xy 23.581704 -153.158391)
			(xy 23.605313 -153.04732) (xy 23.636613 -152.938165) (xy 23.67545 -152.83146) (xy 23.721636 -152.727725)
			(xy 23.774946 -152.627463) (xy 23.83512 -152.531165) (xy 23.901865 -152.439299) (xy 23.974855 -152.352312)
			(xy 24.053736 -152.270629) (xy 24.138122 -152.194647) (xy 24.227603 -152.124737) (xy 24.321743 -152.061239)
			(xy 24.420083 -152.004462) (xy 24.522143 -151.954684) (xy 24.627428 -151.912146) (xy 24.735423 -151.877056)
			(xy 24.845603 -151.849585) (xy 24.957431 -151.829867) (xy 25.070362 -151.817997) (xy 25.183846 -151.814035)
			(xy 25.29733 -151.817997) (xy 25.410261 -151.829867) (xy 25.522089 -151.849585) (xy 25.632269 -151.877056)
			(xy 25.740264 -151.912146) (xy 25.845549 -151.954684) (xy 25.947609 -152.004462) (xy 26.045949 -152.061239)
			(xy 26.140089 -152.124737) (xy 26.22957 -152.194647) (xy 26.313956 -152.270629) (xy 26.392837 -152.352312)
			(xy 26.465827 -152.439299) (xy 26.532572 -152.531165) (xy 26.592746 -152.627463) (xy 26.646056 -152.727725)
			(xy 26.692242 -152.83146) (xy 26.731079 -152.938165) (xy 26.762379 -153.04732) (xy 26.785988 -153.158391)
			(xy 26.801791 -153.270839) (xy 26.809712 -153.384115) (xy 26.810208 -153.440892) (xy 26.809712 -153.497669)
			(xy 26.801791 -153.610945) (xy 26.785988 -153.723393) (xy 26.762379 -153.834464) (xy 26.731079 -153.943619)
			(xy 26.692242 -154.050324) (xy 26.646056 -154.154059) (xy 26.592746 -154.254321) (xy 26.532572 -154.350619)
			(xy 26.465827 -154.442485) (xy 26.392837 -154.529472) (xy 26.313956 -154.611155) (xy 26.22957 -154.687137)
			(xy 26.140089 -154.757047) (xy 26.045949 -154.820545) (xy 25.947609 -154.877322) (xy 25.845549 -154.9271)
			(xy 25.740264 -154.969638) (xy 25.632269 -155.004728) (xy 25.522089 -155.032199) (xy 25.410261 -155.051917)
			(xy 25.29733 -155.063787) (xy 25.183846 -155.06775) (xy 25.070362 -155.063787) (xy 24.957431 -155.051917)
			(xy 24.845603 -155.032199) (xy 24.735423 -155.004728) (xy 24.627428 -154.969638) (xy 24.522143 -154.9271)
			(xy 24.420083 -154.877322) (xy 24.321743 -154.820545) (xy 24.227603 -154.757047) (xy 24.138122 -154.687137)
			(xy 24.053736 -154.611155) (xy 23.974855 -154.529472) (xy 23.901865 -154.442485) (xy 23.83512 -154.350619)
			(xy 23.774946 -154.254321) (xy 23.721636 -154.154059) (xy 23.67545 -154.050324) (xy 23.636613 -153.943619)
			(xy 23.605313 -153.834464) (xy 23.581704 -153.723393) (xy 23.565901 -153.610945) (xy 23.55798 -153.497669)
			(xy 2.159 -153.497669) (xy 2.159 -154.410918) (xy 2.15946 -154.420795) (xy 2.166903 -154.439094)
			(xy 2.173478 -154.446478) (xy 3.287014 -155.560014) (xy 3.287522 -155.560522) (xy 3.2949 -155.567112)
			(xy 3.313199 -155.574579) (xy 3.323082 -155.575) (xy 29.442918 -155.575) (xy 29.452795 -155.57454)
			(xy 29.471094 -155.567097) (xy 29.478478 -155.560522) (xy 30.338014 -154.700986) (xy 30.338522 -154.700478)
			(xy 30.345112 -154.6931) (xy 30.352579 -154.674801) (xy 30.353 -154.664918) (xy 30.353 -41.852596)
			(xy 30.343602 -41.822624) (xy 30.339284 -41.816528) (xy 30.322386 -41.791054) (xy 30.294134 -41.736841)
			(xy 30.272581 -41.679635) (xy 30.258038 -41.620258) (xy 30.250713 -41.559566) (xy 30.250713 -41.498434)
			(xy 30.258038 -41.437742) (xy 30.272581 -41.378365) (xy 30.294134 -41.321159) (xy 30.322386 -41.266946)
			(xy 30.339284 -41.241472) (xy 30.343602 -41.235376) (xy 30.353 -41.205404) (xy 30.353 -37.367464)
			(xy 30.352878 -37.36251) (xy 30.350953 -37.352792) (xy 30.34919 -37.34816) (xy 30.33776 -37.320474)
			(xy 30.330648 -37.313362) (xy 30.307949 -37.289515) (xy 30.268256 -37.236989) (xy 30.235672 -37.17978)
			(xy 30.210742 -37.118846) (xy 30.193882 -37.055204) (xy 30.185374 -36.989919) (xy 30.184852 -36.957)
			(xy 30.185372 -36.924062) (xy 30.19387 -36.858735) (xy 30.210724 -36.795051) (xy 30.235654 -36.734073)
			(xy 30.268241 -36.676821) (xy 30.307941 -36.624251) (xy 30.330648 -36.600384) (xy 30.337252 -36.593526)
			(xy 30.348428 -36.56711) (xy 30.352492 -36.557458) (xy 30.352492 -35.11804) (xy 30.352746 -35.113722)
			(xy 30.353 -35.11169) (xy 30.353 -28.734766) (xy 30.353429 -28.724699) (xy 30.361153 -28.706103)
			(xy 30.367986 -28.698698) (xy 34.412682 -24.654002) (xy 34.420085 -24.647168) (xy 34.438683 -24.639464)
			(xy 34.44875 -24.639016) (xy 41.426892 -24.639016) (xy 41.436763 -24.638543) (xy 41.455044 -24.631083)
			(xy 41.462452 -24.624538) (xy 43.08475 -23.00224) (xy 43.085258 -23.001732) (xy 43.091838 -22.99435)
			(xy 43.099282 -22.976051) (xy 43.099736 -22.966172) (xy 43.099736 -16.27378) (xy 43.100164 -16.263712)
			(xy 43.107887 -16.245116) (xy 43.114722 -16.237712) (xy 43.128184 -16.22425) (xy 43.135584 -16.217411)
			(xy 43.154183 -16.209699) (xy 43.164252 -16.209264) (xy 48.03521 -16.209264) (xy 48.045278 -16.209691)
			(xy 48.063874 -16.217415) (xy 48.071278 -16.22425) (xy 48.49749 -16.650462) (xy 48.504328 -16.657863)
			(xy 48.512041 -16.676462) (xy 48.512476 -16.68653) (xy 48.512476 -20.63857) (xy 56.730635 -20.63857)
			(xy 56.730635 -20.50943) (xy 56.738585 -20.380535) (xy 56.754455 -20.252375) (xy 56.778184 -20.125434)
			(xy 56.809683 -20.000195) (xy 56.848832 -19.877132) (xy 56.895483 -19.756713) (xy 56.949458 -19.639394)
			(xy 57.010553 -19.52562) (xy 57.078536 -19.415823) (xy 57.15315 -19.31042) (xy 57.234111 -19.20981)
			(xy 57.321111 -19.114375) (xy 57.413822 -19.024476) (xy 57.511892 -18.940455) (xy 57.614947 -18.862631)
			(xy 57.722598 -18.791299) (xy 57.834437 -18.726729) (xy 57.950038 -18.669167) (xy 58.068963 -18.61883)
			(xy 58.190762 -18.57591) (xy 58.314972 -18.540569) (xy 58.441121 -18.512942) (xy 58.568733 -18.493133)
			(xy 58.697322 -18.481217) (xy 58.8264 -18.477241) (xy 58.955478 -18.481217) (xy 59.084067 -18.493133)
			(xy 59.211679 -18.512942) (xy 59.337828 -18.540569) (xy 59.462038 -18.57591) (xy 59.583837 -18.61883)
			(xy 59.702762 -18.669167) (xy 59.818363 -18.726729) (xy 59.930202 -18.791299) (xy 60.037853 -18.862631)
			(xy 60.109385 -18.91665) (xy 80.136238 -18.91665) (xy 80.136744 -18.888745) (xy 80.144861 -18.833529)
			(xy 80.160929 -18.780083) (xy 80.172306 -18.754598) (xy 80.177132 -18.744184) (xy 80.177132 -18.588736)
			(xy 80.177049 -18.584931) (xy 80.1759 -18.577407) (xy 80.174846 -18.57375) (xy 80.172814 -18.567146)
			(xy 80.170528 -18.56359) (xy 80.170528 -18.550636) (xy 80.16494 -18.539714) (xy 80.15717 -18.523736)
			(xy 80.146182 -18.489952) (xy 80.140627 -18.454862) (xy 80.140302 -18.437098) (xy 80.140302 -18.169128)
			(xy 80.156812 -18.169128) (xy 80.167922 -18.166923) (xy 80.186798 -18.15446) (xy 80.198506 -18.135107)
			(xy 80.200246 -18.123916) (xy 80.200246 -17.671034) (xy 80.182466 -17.645126) (xy 80.167988 -17.639538)
			(xy 80.1624 -17.637252) (xy 80.155288 -17.63014) (xy 80.148471 -17.622722) (xy 80.140738 -17.604136)
			(xy 80.140302 -17.594072) (xy 80.140302 -17.373346) (xy 80.140707 -17.353663) (xy 80.14749 -17.314886)
			(xy 80.16086 -17.277861) (xy 80.170274 -17.26057) (xy 80.17383 -17.254728) (xy 80.177132 -17.242028)
			(xy 80.177132 -16.555466) (xy 80.172306 -16.545052) (xy 80.160926 -16.519568) (xy 80.144863 -16.46612)
			(xy 80.136746 -16.410905) (xy 80.136238 -16.383) (xy 80.136724 -16.355731) (xy 80.144486 -16.301747)
			(xy 80.159851 -16.249417) (xy 80.182508 -16.199807) (xy 80.211994 -16.153926) (xy 80.247709 -16.112709)
			(xy 80.288926 -16.076994) (xy 80.334807 -16.047508) (xy 80.384417 -16.024851) (xy 80.436747 -16.009486)
			(xy 80.490731 -16.001724) (xy 80.545269 -16.001724) (xy 80.599253 -16.009486) (xy 80.651583 -16.024851)
			(xy 80.701193 -16.047508) (xy 80.747074 -16.076994) (xy 80.788291 -16.112709) (xy 80.824006 -16.153926)
			(xy 80.853492 -16.199807) (xy 80.876149 -16.249417) (xy 80.878082 -16.256) (xy 82.066638 -16.256)
			(xy 82.06714 -16.224023) (xy 82.075155 -16.160573) (xy 82.09106 -16.098628) (xy 82.114603 -16.039166)
			(xy 82.145413 -15.983122) (xy 82.183005 -15.931382) (xy 82.226784 -15.884762) (xy 82.276062 -15.843996)
			(xy 82.33006 -15.809728) (xy 82.387927 -15.782497) (xy 82.448751 -15.762734) (xy 82.511572 -15.750751)
			(xy 82.5754 -15.746735) (xy 82.639228 -15.750751) (xy 82.702049 -15.762734) (xy 82.762873 -15.782497)
			(xy 82.82074 -15.809728) (xy 82.874738 -15.843996) (xy 82.924016 -15.884762) (xy 82.967795 -15.931382)
			(xy 83.005387 -15.983122) (xy 83.036197 -16.039166) (xy 83.05974 -16.098628) (xy 83.075645 -16.160573)
			(xy 83.08366 -16.224023) (xy 83.084162 -16.256) (xy 83.084162 -16.261334) (xy 83.083908 -16.271494)
			(xy 83.091528 -16.290544) (xy 83.129628 -16.328644) (xy 83.136347 -16.336051) (xy 83.144069 -16.354474)
			(xy 83.144614 -16.364458) (xy 83.144614 -16.48206) (xy 83.144868 -16.484346) (xy 83.144868 -17.225264)
			(xy 83.144951 -17.229069) (xy 83.1461 -17.236593) (xy 83.147154 -17.24025) (xy 83.149186 -17.246854)
			(xy 83.151472 -17.25041) (xy 83.151472 -17.263364) (xy 83.15706 -17.274286) (xy 83.16483 -17.290264)
			(xy 83.175818 -17.324048) (xy 83.181373 -17.359138) (xy 83.181698 -17.376902) (xy 83.181698 -17.644872)
			(xy 83.165188 -17.644872) (xy 83.154078 -17.647077) (xy 83.135202 -17.65954) (xy 83.123494 -17.678893)
			(xy 83.121754 -17.690084) (xy 83.121754 -18.142966) (xy 83.139534 -18.168874) (xy 83.154012 -18.174462)
			(xy 83.1596 -18.176748) (xy 83.166712 -18.18386) (xy 83.173529 -18.191278) (xy 83.181262 -18.209864)
			(xy 83.181698 -18.219928) (xy 83.181698 -18.440654) (xy 83.181293 -18.460337) (xy 83.17451 -18.499114)
			(xy 83.16114 -18.536139) (xy 83.151726 -18.55343) (xy 83.14817 -18.559272) (xy 83.144868 -18.571972)
			(xy 83.144868 -18.744438) (xy 83.149694 -18.754852) (xy 83.161075 -18.780335) (xy 83.177137 -18.833783)
			(xy 83.185255 -18.888999) (xy 83.185762 -18.916904) (xy 83.352386 -18.916904) (xy 83.352386 -18.30705)
			(xy 83.352781 -18.275323) (xy 83.35955 -18.212231) (xy 83.373008 -18.150221) (xy 83.392999 -18.089998)
			(xy 83.419297 -18.03225) (xy 83.451601 -17.977634) (xy 83.470242 -17.951958) (xy 83.475322 -17.945354)
			(xy 83.480402 -17.929606) (xy 83.480402 -17.884394) (xy 83.475322 -17.868646) (xy 83.470242 -17.862042)
			(xy 83.451627 -17.836375) (xy 83.419366 -17.781789) (xy 83.393093 -17.724081) (xy 83.373107 -17.663907)
			(xy 83.359633 -17.601948) (xy 83.352826 -17.538907) (xy 83.352386 -17.507204) (xy 83.352386 -16.360902)
			(xy 83.352804 -16.350892) (xy 83.360552 -16.332429) (xy 83.367372 -16.325088) (xy 84.03463 -15.65783)
			(xy 84.058535 -15.634553) (xy 84.110704 -15.592952) (xy 84.1672 -15.557449) (xy 84.227312 -15.528489)
			(xy 84.290288 -15.506436) (xy 84.355335 -15.491568) (xy 84.421638 -15.484069) (xy 84.455 -15.483586)
			(xy 84.488367 -15.484054) (xy 84.55468 -15.491525) (xy 84.61974 -15.506375) (xy 84.682728 -15.528415)
			(xy 84.742853 -15.55737) (xy 84.799357 -15.592874) (xy 84.851531 -15.634481) (xy 84.898719 -15.681669)
			(xy 84.940326 -15.733843) (xy 84.97583 -15.790347) (xy 85.004785 -15.850472) (xy 85.026825 -15.91346)
			(xy 85.041675 -15.97852) (xy 85.049146 -16.044833) (xy 85.049614 -16.0782) (xy 85.04913 -16.111564)
			(xy 85.041655 -16.177872) (xy 85.0268 -16.242925) (xy 85.004752 -16.305905) (xy 84.975787 -16.366019)
			(xy 84.940272 -16.42251) (xy 84.898651 -16.474668) (xy 84.87537 -16.49857) (xy 84.660486 -16.713454)
			(xy 84.660486 -16.713708) (xy 84.5566 -16.817594) (xy 84.54977 -16.825002) (xy 84.542044 -16.843595)
			(xy 84.541614 -16.853662) (xy 84.541614 -17.50695) (xy 84.541219 -17.538677) (xy 84.53445 -17.601769)
			(xy 84.520992 -17.663779) (xy 84.501001 -17.724002) (xy 84.474703 -17.78175) (xy 84.442399 -17.836366)
			(xy 84.423758 -17.862042) (xy 84.418678 -17.868646) (xy 84.413598 -17.884394) (xy 84.413598 -17.929606)
			(xy 84.418678 -17.945354) (xy 84.423758 -17.951958) (xy 84.442373 -17.977625) (xy 84.474634 -18.032211)
			(xy 84.500907 -18.089919) (xy 84.520893 -18.150093) (xy 84.534367 -18.212052) (xy 84.541174 -18.275093)
			(xy 84.541614 -18.306796) (xy 84.541614 -18.916904) (xy 84.541111 -18.951507) (xy 84.533077 -19.020245)
			(xy 84.517117 -19.087586) (xy 84.493447 -19.152618) (xy 84.462387 -19.214463) (xy 84.424358 -19.272284)
			(xy 84.379873 -19.325299) (xy 84.329534 -19.372791) (xy 84.274023 -19.414118) (xy 84.214088 -19.448721)
			(xy 84.150542 -19.476132) (xy 84.084244 -19.495981) (xy 84.016089 -19.507998) (xy 83.947 -19.512022)
			(xy 83.877911 -19.507998) (xy 83.809756 -19.495981) (xy 83.743458 -19.476132) (xy 83.679912 -19.448721)
			(xy 83.619977 -19.414118) (xy 83.564466 -19.372791) (xy 83.514127 -19.325299) (xy 83.469642 -19.272284)
			(xy 83.431613 -19.214463) (xy 83.400553 -19.152618) (xy 83.376883 -19.087586) (xy 83.360923 -19.020245)
			(xy 83.352889 -18.951507) (xy 83.352386 -18.916904) (xy 83.185762 -18.916904) (xy 83.185276 -18.944173)
			(xy 83.177514 -18.998157) (xy 83.162149 -19.050487) (xy 83.139492 -19.100097) (xy 83.110006 -19.145978)
			(xy 83.074291 -19.187195) (xy 83.033074 -19.22291) (xy 82.987193 -19.252396) (xy 82.937583 -19.275053)
			(xy 82.885253 -19.290418) (xy 82.831269 -19.29818) (xy 82.776731 -19.29818) (xy 82.722747 -19.290418)
			(xy 82.670417 -19.275053) (xy 82.620807 -19.252396) (xy 82.574926 -19.22291) (xy 82.533709 -19.187195)
			(xy 82.497994 -19.145978) (xy 82.468508 -19.100097) (xy 82.445851 -19.050487) (xy 82.430486 -18.998157)
			(xy 82.422724 -18.944173) (xy 82.422238 -18.916904) (xy 82.422728 -18.888999) (xy 82.430851 -18.833782)
			(xy 82.446926 -18.780336) (xy 82.458306 -18.754852) (xy 82.463132 -18.744438) (xy 82.463132 -18.588736)
			(xy 82.463049 -18.584931) (xy 82.4619 -18.577407) (xy 82.460846 -18.57375) (xy 82.458814 -18.567146)
			(xy 82.456528 -18.56359) (xy 82.456528 -18.550636) (xy 82.45094 -18.539714) (xy 82.44317 -18.523736)
			(xy 82.432182 -18.489952) (xy 82.426627 -18.454862) (xy 82.426302 -18.437098) (xy 82.426302 -18.169128)
			(xy 82.442812 -18.169128) (xy 82.453922 -18.166923) (xy 82.472798 -18.15446) (xy 82.484506 -18.135107)
			(xy 82.486246 -18.123916) (xy 82.486246 -17.671034) (xy 82.468466 -17.645126) (xy 82.453988 -17.639538)
			(xy 82.4484 -17.637252) (xy 82.441288 -17.63014) (xy 82.434471 -17.622722) (xy 82.426738 -17.604136)
			(xy 82.426302 -17.594072) (xy 82.426302 -17.373346) (xy 82.426707 -17.353663) (xy 82.43349 -17.314886)
			(xy 82.44686 -17.277861) (xy 82.456274 -17.26057) (xy 82.45983 -17.254728) (xy 82.463132 -17.242028)
			(xy 82.463132 -16.774414) (xy 82.44332 -16.74749) (xy 82.427064 -16.742664) (xy 82.396181 -16.73271)
			(xy 82.337022 -16.706053) (xy 82.281733 -16.672091) (xy 82.231211 -16.631374) (xy 82.186277 -16.584565)
			(xy 82.147658 -16.532421) (xy 82.115983 -16.475791) (xy 82.091766 -16.415593) (xy 82.075399 -16.352804)
			(xy 82.067149 -16.288443) (xy 82.066638 -16.256) (xy 80.878082 -16.256) (xy 80.891514 -16.301747)
			(xy 80.899276 -16.355731) (xy 80.899762 -16.383) (xy 80.899274 -16.410905) (xy 80.89115 -16.466122)
			(xy 80.875075 -16.519568) (xy 80.863694 -16.545052) (xy 80.858868 -16.555466) (xy 80.858868 -17.225264)
			(xy 80.858951 -17.229069) (xy 80.8601 -17.236593) (xy 80.861154 -17.24025) (xy 80.863186 -17.246854)
			(xy 80.865472 -17.25041) (xy 80.865472 -17.263364) (xy 80.87106 -17.274286) (xy 80.87883 -17.290264)
			(xy 80.889818 -17.324048) (xy 80.895373 -17.359138) (xy 80.895698 -17.376902) (xy 80.895698 -17.644872)
			(xy 80.879188 -17.644872) (xy 80.868078 -17.647077) (xy 80.849202 -17.65954) (xy 80.837494 -17.678893)
			(xy 80.835754 -17.690084) (xy 80.835754 -18.142966) (xy 80.853534 -18.168874) (xy 80.868012 -18.174462)
			(xy 80.8736 -18.176748) (xy 80.880712 -18.18386) (xy 80.887529 -18.191278) (xy 80.895262 -18.209864)
			(xy 80.895698 -18.219928) (xy 80.895698 -18.440654) (xy 80.895293 -18.460337) (xy 80.88851 -18.499114)
			(xy 80.87514 -18.536139) (xy 80.865726 -18.55343) (xy 80.86217 -18.559272) (xy 80.858868 -18.571972)
			(xy 80.858868 -18.744184) (xy 80.863694 -18.754598) (xy 80.875058 -18.780089) (xy 80.891126 -18.833533)
			(xy 80.899251 -18.888746) (xy 80.899762 -18.91665) (xy 81.279238 -18.91665) (xy 81.279744 -18.888745)
			(xy 81.287861 -18.833529) (xy 81.303929 -18.780083) (xy 81.315306 -18.754598) (xy 81.320132 -18.744184)
			(xy 81.320132 -18.588736) (xy 81.320049 -18.584931) (xy 81.3189 -18.577407) (xy 81.317846 -18.57375)
			(xy 81.315814 -18.567146) (xy 81.313528 -18.56359) (xy 81.313528 -18.550636) (xy 81.30794 -18.539714)
			(xy 81.30017 -18.523736) (xy 81.289182 -18.489952) (xy 81.283627 -18.454862) (xy 81.283302 -18.437098)
			(xy 81.283302 -18.169128) (xy 81.299812 -18.169128) (xy 81.310922 -18.166923) (xy 81.329798 -18.15446)
			(xy 81.341506 -18.135107) (xy 81.343246 -18.123916) (xy 81.343246 -17.671034) (xy 81.325466 -17.645126)
			(xy 81.310988 -17.639538) (xy 81.3054 -17.637252) (xy 81.298288 -17.63014) (xy 81.291471 -17.622722)
			(xy 81.283738 -17.604136) (xy 81.283302 -17.594072) (xy 81.283302 -17.373346) (xy 81.283707 -17.353663)
			(xy 81.29049 -17.314886) (xy 81.30386 -17.277861) (xy 81.313274 -17.26057) (xy 81.31683 -17.254728)
			(xy 81.320132 -17.242028) (xy 81.320132 -17.063466) (xy 81.315306 -17.053052) (xy 81.303926 -17.027568)
			(xy 81.287863 -16.97412) (xy 81.279746 -16.918905) (xy 81.279238 -16.891) (xy 81.279724 -16.863731)
			(xy 81.287486 -16.809747) (xy 81.302851 -16.757417) (xy 81.325508 -16.707807) (xy 81.354994 -16.661926)
			(xy 81.390709 -16.620709) (xy 81.431926 -16.584994) (xy 81.477807 -16.555508) (xy 81.527417 -16.532851)
			(xy 81.579747 -16.517486) (xy 81.633731 -16.509724) (xy 81.688269 -16.509724) (xy 81.742253 -16.517486)
			(xy 81.794583 -16.532851) (xy 81.844193 -16.555508) (xy 81.890074 -16.584994) (xy 81.931291 -16.620709)
			(xy 81.967006 -16.661926) (xy 81.996492 -16.707807) (xy 82.019149 -16.757417) (xy 82.034514 -16.809747)
			(xy 82.042276 -16.863731) (xy 82.042762 -16.891) (xy 82.042274 -16.918905) (xy 82.03415 -16.974122)
			(xy 82.018075 -17.027568) (xy 82.006694 -17.053052) (xy 82.001868 -17.063466) (xy 82.001868 -17.225264)
			(xy 82.001951 -17.229069) (xy 82.0031 -17.236593) (xy 82.004154 -17.24025) (xy 82.006186 -17.246854)
			(xy 82.008472 -17.25041) (xy 82.008472 -17.263364) (xy 82.01406 -17.274286) (xy 82.02183 -17.290264)
			(xy 82.032818 -17.324048) (xy 82.038373 -17.359138) (xy 82.038698 -17.376902) (xy 82.038698 -17.644872)
			(xy 82.022188 -17.644872) (xy 82.011078 -17.647077) (xy 81.992202 -17.65954) (xy 81.980494 -17.678893)
			(xy 81.978754 -17.690084) (xy 81.978754 -18.142966) (xy 81.996534 -18.168874) (xy 82.011012 -18.174462)
			(xy 82.0166 -18.176748) (xy 82.023712 -18.18386) (xy 82.030529 -18.191278) (xy 82.038262 -18.209864)
			(xy 82.038698 -18.219928) (xy 82.038698 -18.440654) (xy 82.038293 -18.460337) (xy 82.03151 -18.499114)
			(xy 82.01814 -18.536139) (xy 82.008726 -18.55343) (xy 82.00517 -18.559272) (xy 82.001868 -18.571972)
			(xy 82.001868 -18.744184) (xy 82.006694 -18.754598) (xy 82.018058 -18.780089) (xy 82.034126 -18.833533)
			(xy 82.042251 -18.888746) (xy 82.042762 -18.91665) (xy 82.042276 -18.943919) (xy 82.034514 -18.997903)
			(xy 82.019149 -19.050233) (xy 81.996492 -19.099843) (xy 81.967006 -19.145724) (xy 81.931291 -19.186941)
			(xy 81.890074 -19.222656) (xy 81.844193 -19.252142) (xy 81.794583 -19.274799) (xy 81.742253 -19.290164)
			(xy 81.688269 -19.297926) (xy 81.633731 -19.297926) (xy 81.579747 -19.290164) (xy 81.527417 -19.274799)
			(xy 81.477807 -19.252142) (xy 81.431926 -19.222656) (xy 81.390709 -19.186941) (xy 81.354994 -19.145724)
			(xy 81.325508 -19.099843) (xy 81.302851 -19.050233) (xy 81.287486 -18.997903) (xy 81.279724 -18.943919)
			(xy 81.279238 -18.91665) (xy 80.899762 -18.91665) (xy 80.899276 -18.943919) (xy 80.891514 -18.997903)
			(xy 80.876149 -19.050233) (xy 80.853492 -19.099843) (xy 80.824006 -19.145724) (xy 80.788291 -19.186941)
			(xy 80.747074 -19.222656) (xy 80.701193 -19.252142) (xy 80.651583 -19.274799) (xy 80.599253 -19.290164)
			(xy 80.545269 -19.297926) (xy 80.490731 -19.297926) (xy 80.436747 -19.290164) (xy 80.384417 -19.274799)
			(xy 80.334807 -19.252142) (xy 80.288926 -19.222656) (xy 80.247709 -19.186941) (xy 80.211994 -19.145724)
			(xy 80.182508 -19.099843) (xy 80.159851 -19.050233) (xy 80.144486 -18.997903) (xy 80.136724 -18.943919)
			(xy 80.136238 -18.91665) (xy 60.109385 -18.91665) (xy 60.140908 -18.940455) (xy 60.238978 -19.024476)
			(xy 60.331689 -19.114375) (xy 60.418689 -19.20981) (xy 60.49965 -19.31042) (xy 60.574264 -19.415823)
			(xy 60.642247 -19.52562) (xy 60.703342 -19.639394) (xy 60.757317 -19.756713) (xy 60.803968 -19.877132)
			(xy 60.843117 -20.000195) (xy 60.874616 -20.125434) (xy 60.898345 -20.252375) (xy 60.914215 -20.380535)
			(xy 60.922165 -20.50943) (xy 60.922662 -20.574) (xy 60.922165 -20.63857) (xy 60.914215 -20.767465)
			(xy 60.898345 -20.895625) (xy 60.874616 -21.022566) (xy 60.843117 -21.147805) (xy 60.803968 -21.270868)
			(xy 60.757317 -21.391287) (xy 60.703342 -21.508606) (xy 60.642247 -21.62238) (xy 60.574264 -21.732177)
			(xy 60.49965 -21.83758) (xy 60.418689 -21.93819) (xy 60.331689 -22.033625) (xy 60.238978 -22.123524)
			(xy 60.140908 -22.207545) (xy 60.037853 -22.285369) (xy 59.930202 -22.356701) (xy 59.818363 -22.421271)
			(xy 59.702762 -22.478833) (xy 59.583837 -22.52917) (xy 59.462038 -22.57209) (xy 59.337828 -22.607431)
			(xy 59.211679 -22.635058) (xy 59.084067 -22.654867) (xy 58.955478 -22.666783) (xy 58.8264 -22.67076)
			(xy 58.697322 -22.666783) (xy 58.568733 -22.654867) (xy 58.441121 -22.635058) (xy 58.314972 -22.607431)
			(xy 58.190762 -22.57209) (xy 58.068963 -22.52917) (xy 57.950038 -22.478833) (xy 57.834437 -22.421271)
			(xy 57.722598 -22.356701) (xy 57.614947 -22.285369) (xy 57.511892 -22.207545) (xy 57.413822 -22.123524)
			(xy 57.321111 -22.033625) (xy 57.234111 -21.93819) (xy 57.15315 -21.83758) (xy 57.078536 -21.732177)
			(xy 57.010553 -21.62238) (xy 56.949458 -21.508606) (xy 56.895483 -21.391287) (xy 56.848832 -21.270868)
			(xy 56.809683 -21.147805) (xy 56.778184 -21.022566) (xy 56.754455 -20.895625) (xy 56.738585 -20.767465)
			(xy 56.730635 -20.63857) (xy 48.512476 -20.63857) (xy 48.512476 -25.23998) (xy 48.512946 -25.249853)
			(xy 48.520403 -25.268138) (xy 48.526954 -25.27554) (xy 48.636428 -25.385014) (xy 48.636936 -25.385522)
			(xy 48.644315 -25.39211) (xy 48.662614 -25.399572) (xy 48.672496 -25.4) (xy 56.011318 -25.4) (xy 56.021387 -25.400427)
			(xy 56.039986 -25.408146) (xy 56.047386 -25.414986) (xy 56.525414 -25.893014) (xy 56.532268 -25.900409)
			(xy 56.54001 -25.919008) (xy 56.5404 -25.929082) (xy 56.5404 -30.458918) (xy 56.54086 -30.468795)
			(xy 56.548303 -30.487094) (xy 56.554878 -30.494478) (xy 56.779414 -30.719014) (xy 56.779922 -30.719522)
			(xy 56.7873 -30.726112) (xy 56.805599 -30.733579) (xy 56.815482 -30.734) (xy 68.945252 -30.734) (xy 68.955126 -30.733534)
			(xy 68.973416 -30.726082) (xy 68.980812 -30.719522) (xy 73.465182 -26.235152) (xy 73.46569 -26.234644)
			(xy 74.335894 -25.385522) (xy 74.336402 -25.385014) (xy 78.23073 -21.490686) (xy 78.238126 -21.483835)
			(xy 78.256725 -21.476098) (xy 78.266798 -21.4757) (xy 88.545416 -21.4757) (xy 98.60153 -11.419586)
			(xy 98.975926 -11.419586) (xy 98.983322 -11.412734) (xy 99.001921 -11.404996) (xy 99.011994 -11.4046)
			(xy 121.012966 -11.4046) (xy 121.022839 -11.404131) (xy 121.041125 -11.396676) (xy 121.048526 -11.390122)
			(xy 122.568716 -9.869932) (xy 122.576114 -9.863085) (xy 122.594712 -9.855351) (xy 122.604784 -9.854946)
			(xy 143.426688 -9.854946) (xy 143.436758 -9.855368) (xy 143.455361 -9.863085) (xy 143.462756 -9.869932)
			(xy 145.261838 -11.669014) (xy 145.262346 -11.669522) (xy 145.269725 -11.676109) (xy 145.288025 -11.683567)
			(xy 145.297906 -11.684) (xy 160.101534 -11.684) (xy 160.111601 -11.684429) (xy 160.130197 -11.692153)
			(xy 160.137602 -11.698986) (xy 162.960304 -14.521688) (xy 162.967152 -14.529086) (xy 162.97489 -14.547684)
			(xy 162.97529 -14.557756) (xy 162.97529 -25.34793) (xy 162.975752 -25.357806) (xy 162.983197 -25.376103)
			(xy 162.989768 -25.38349) (xy 163.332922 -25.726644) (xy 163.33343 -25.727152) (xy 163.34081 -25.733738)
			(xy 163.359109 -25.741197) (xy 163.36899 -25.74163) (xy 206.004668 -25.74163) (xy 206.018306 -25.741156)
			(xy 206.044592 -25.733865) (xy 206.068009 -25.719874) (xy 206.086887 -25.700182) (xy 206.099877 -25.676195)
			(xy 206.106053 -25.649625) (xy 206.104974 -25.622368) (xy 206.096717 -25.596369) (xy 206.08187 -25.573484)
			(xy 206.071978 -25.564084) (xy 206.003575 -25.502771) (xy 205.871651 -25.374913) (xy 205.745545 -25.241313)
			(xy 205.625508 -25.102235) (xy 205.511776 -24.957954) (xy 205.404576 -24.808757) (xy 205.304118 -24.654939)
			(xy 205.210603 -24.496804) (xy 205.124216 -24.334665) (xy 205.045127 -24.168844) (xy 204.973493 -23.999669)
			(xy 204.909456 -23.827474) (xy 204.853142 -23.652601) (xy 204.804664 -23.475397) (xy 204.764117 -23.29621)
			(xy 204.731581 -23.115398) (xy 204.707121 -22.933317) (xy 204.690786 -22.750328) (xy 204.682607 -22.566794)
			(xy 204.68209 -22.474936) (xy 204.682595 -22.383605) (xy 204.690675 -22.201121) (xy 204.706819 -22.019173)
			(xy 204.730995 -21.838117) (xy 204.763156 -21.658308) (xy 204.803239 -21.480098) (xy 204.851166 -21.303835)
			(xy 204.906843 -21.129864) (xy 204.97016 -20.958527) (xy 205.040995 -20.790158) (xy 205.119207 -20.625086)
			(xy 205.204645 -20.463637) (xy 205.29714 -20.306124) (xy 205.396512 -20.152857) (xy 205.502567 -20.004135)
			(xy 205.615096 -19.86025) (xy 205.733879 -19.721484) (xy 205.858685 -19.588108) (xy 205.989267 -19.460382)
			(xy 206.125372 -19.338558) (xy 206.266732 -19.222873) (xy 206.413071 -19.113555) (xy 206.564103 -19.010816)
			(xy 206.719531 -18.914859) (xy 206.879051 -18.825871) (xy 207.042351 -18.744026) (xy 207.209112 -18.669484)
			(xy 207.379007 -18.602392) (xy 207.551703 -18.54288) (xy 207.726863 -18.491066) (xy 207.904143 -18.44705)
			(xy 208.083197 -18.410919) (xy 208.263673 -18.382743) (xy 208.44522 -18.362579) (xy 208.62748 -18.350464)
			(xy 208.810098 -18.346423) (xy 208.992716 -18.350464) (xy 209.174976 -18.362579) (xy 209.356523 -18.382743)
			(xy 209.536999 -18.410919) (xy 209.716053 -18.44705) (xy 209.893333 -18.491066) (xy 210.068493 -18.54288)
			(xy 210.241189 -18.602392) (xy 210.411084 -18.669484) (xy 210.577845 -18.744026) (xy 210.741145 -18.825871)
			(xy 210.900665 -18.914859) (xy 211.056093 -19.010816) (xy 211.207125 -19.113555) (xy 211.353464 -19.222873)
			(xy 211.494824 -19.338558) (xy 211.630929 -19.460382) (xy 211.761511 -19.588108) (xy 211.886317 -19.721484)
			(xy 212.0051 -19.86025) (xy 212.117629 -20.004135) (xy 212.223684 -20.152857) (xy 212.323056 -20.306124)
			(xy 212.415551 -20.463637) (xy 212.500989 -20.625086) (xy 212.579201 -20.790158) (xy 212.650036 -20.958527)
			(xy 212.713353 -21.129864) (xy 212.76903 -21.303835) (xy 212.816957 -21.480098) (xy 212.85704 -21.658308)
			(xy 212.889201 -21.838117) (xy 212.913377 -22.019173) (xy 212.929521 -22.201121) (xy 212.937601 -22.383605)
			(xy 212.938106 -22.474936) (xy 212.937612 -22.565122) (xy 212.92972 -22.745323) (xy 212.913965 -22.925007)
			(xy 212.890378 -23.103831) (xy 212.859003 -23.281454) (xy 212.819901 -23.457538) (xy 212.773145 -23.631746)
			(xy 212.718826 -23.803745) (xy 212.657047 -23.973209) (xy 212.587926 -24.139812) (xy 212.511594 -24.303238)
			(xy 212.428198 -24.463174) (xy 212.337897 -24.619315) (xy 212.240862 -24.771363) (xy 212.137279 -24.919028)
			(xy 212.027346 -25.062029) (xy 211.911272 -25.200092) (xy 211.78928 -25.332954) (xy 211.661601 -25.460361)
			(xy 211.52848 -25.58207) (xy 211.39017 -25.69785) (xy 211.318856 -25.75306) (xy 211.316062 -25.755092)
			(xy 211.304378 -25.766776) (xy 211.300314 -25.774396) (xy 211.296504 -25.78227) (xy 211.293032 -25.790428)
			(xy 211.291321 -25.80806) (xy 211.29574 -25.825215) (xy 211.305758 -25.839826) (xy 211.31276 -25.845262)
			(xy 211.319872 -25.850342) (xy 211.326984 -25.853898) (xy 211.329778 -25.855676) (xy 211.33943 -25.863042)
			(xy 213.405466 -27.929078) (xy 213.412304 -27.936479) (xy 213.420015 -27.955078) (xy 213.420452 -27.965146)
			(xy 213.420452 -53.369464) (xy 213.420016 -53.379528) (xy 213.41228 -53.398111) (xy 213.405466 -53.405532)
			(xy 211.707984 -55.103014) (xy 211.700589 -55.109867) (xy 211.68199 -55.117609) (xy 211.671916 -55.118)
			(xy 183.080406 -55.118) (xy 183.06161 -55.12562) (xy 183.054498 -55.132986) (xy 182.459122 -55.728362)
			(xy 182.452283 -55.735763) (xy 182.444568 -55.754361) (xy 182.444136 -55.76443) (xy 182.444136 -59.233054)
			(xy 182.444601 -59.24293) (xy 182.452046 -59.261225) (xy 182.458614 -59.268614) (xy 184.706514 -61.516514)
			(xy 184.707022 -61.517022) (xy 184.7144 -61.523612) (xy 184.732699 -61.531079) (xy 184.742582 -61.5315)
			(xy 188.790072 -61.5315) (xy 189.712092 -62.45352) (xy 189.712092 -79.624936) (xy 204.681592 -79.624936)
			(xy 204.685577 -79.443595) (xy 204.697523 -79.262603) (xy 204.717407 -79.082311) (xy 204.745191 -78.903067)
			(xy 204.780822 -78.725215) (xy 204.82423 -78.549101) (xy 204.875332 -78.375063) (xy 204.93403 -78.203438)
			(xy 205.000209 -78.034557) (xy 205.073742 -77.868745) (xy 205.154487 -77.706324) (xy 205.242289 -77.547605)
			(xy 205.336978 -77.392897) (xy 205.43837 -77.242497) (xy 205.546271 -77.096696) (xy 205.660472 -76.955775)
			(xy 205.780753 -76.820006) (xy 205.906881 -76.689652) (xy 206.038613 -76.564963) (xy 206.175695 -76.446181)
			(xy 206.317862 -76.333535) (xy 206.464839 -76.227242) (xy 206.616344 -76.127508) (xy 206.772083 -76.034524)
			(xy 206.931756 -75.948471) (xy 207.095055 -75.869515) (xy 207.261664 -75.797807) (xy 207.431262 -75.733487)
			(xy 207.603522 -75.676679) (xy 207.77811 -75.627491) (xy 207.954691 -75.58602) (xy 208.132923 -75.552345)
			(xy 208.312462 -75.526531) (xy 208.492961 -75.508629) (xy 208.674073 -75.498671) (xy 208.855447 -75.496679)
			(xy 209.036734 -75.502655) (xy 209.217583 -75.516589) (xy 209.397646 -75.538452) (xy 209.576574 -75.568204)
			(xy 209.754023 -75.605786) (xy 209.92965 -75.651126) (xy 210.103116 -75.704137) (xy 210.274086 -75.764716)
			(xy 210.442231 -75.832746) (xy 210.607224 -75.908096) (xy 210.768749 -75.990621) (xy 210.926493 -76.080161)
			(xy 211.080152 -76.176543) (xy 211.229429 -76.279581) (xy 211.374036 -76.389077) (xy 211.513694 -76.504819)
			(xy 211.648134 -76.626584) (xy 211.777095 -76.754136) (xy 211.900329 -76.88723) (xy 212.017598 -77.025608)
			(xy 212.128676 -77.169004) (xy 212.233348 -77.31714) (xy 212.331412 -77.469731) (xy 212.422679 -77.626482)
			(xy 212.506973 -77.787091) (xy 212.584131 -77.951247) (xy 212.654004 -78.118634) (xy 212.716458 -78.288928)
			(xy 212.77137 -78.461801) (xy 212.818637 -78.63692) (xy 212.858166 -78.813945) (xy 212.889881 -78.992536)
			(xy 212.913722 -79.172348) (xy 212.929641 -79.353033) (xy 212.937608 -79.534243) (xy 212.938106 -79.624936)
			(xy 234.681532 -79.624936) (xy 234.685517 -79.443595) (xy 234.697463 -79.262603) (xy 234.717347 -79.082311)
			(xy 234.745131 -78.903067) (xy 234.780762 -78.725215) (xy 234.82417 -78.549101) (xy 234.875272 -78.375063)
			(xy 234.93397 -78.203438) (xy 235.000149 -78.034557) (xy 235.073682 -77.868745) (xy 235.154427 -77.706324)
			(xy 235.242229 -77.547605) (xy 235.336918 -77.392897) (xy 235.43831 -77.242497) (xy 235.546211 -77.096696)
			(xy 235.660412 -76.955775) (xy 235.780693 -76.820006) (xy 235.906821 -76.689652) (xy 236.038553 -76.564963)
			(xy 236.175635 -76.446181) (xy 236.317802 -76.333535) (xy 236.464779 -76.227242) (xy 236.616284 -76.127508)
			(xy 236.772023 -76.034524) (xy 236.931696 -75.948471) (xy 237.094995 -75.869515) (xy 237.261604 -75.797807)
			(xy 237.431202 -75.733487) (xy 237.603462 -75.676679) (xy 237.77805 -75.627491) (xy 237.954631 -75.58602)
			(xy 238.132863 -75.552345) (xy 238.312402 -75.526531) (xy 238.492901 -75.508629) (xy 238.674013 -75.498671)
			(xy 238.855387 -75.496679) (xy 239.036674 -75.502655) (xy 239.217523 -75.516589) (xy 239.397586 -75.538452)
			(xy 239.576514 -75.568204) (xy 239.753963 -75.605786) (xy 239.92959 -75.651126) (xy 240.103056 -75.704137)
			(xy 240.274026 -75.764716) (xy 240.442171 -75.832746) (xy 240.607164 -75.908096) (xy 240.768689 -75.990621)
			(xy 240.926433 -76.080161) (xy 241.080092 -76.176543) (xy 241.229369 -76.279581) (xy 241.373976 -76.389077)
			(xy 241.513634 -76.504819) (xy 241.648074 -76.626584) (xy 241.777035 -76.754136) (xy 241.900269 -76.88723)
			(xy 242.017538 -77.025608) (xy 242.128616 -77.169004) (xy 242.233288 -77.31714) (xy 242.331352 -77.469731)
			(xy 242.422619 -77.626482) (xy 242.506913 -77.787091) (xy 242.584071 -77.951247) (xy 242.653944 -78.118634)
			(xy 242.716398 -78.288928) (xy 242.77131 -78.461801) (xy 242.818577 -78.63692) (xy 242.858106 -78.813945)
			(xy 242.888051 -78.98257) (xy 248.182128 -78.98257) (xy 248.186201 -78.926911) (xy 248.198336 -78.872438)
			(xy 248.218272 -78.820312) (xy 248.245586 -78.771644) (xy 248.279694 -78.727472) (xy 248.319871 -78.688737)
			(xy 248.365259 -78.656265) (xy 248.414891 -78.630747) (xy 248.467711 -78.612728) (xy 248.52259 -78.602591)
			(xy 248.578361 -78.600553) (xy 248.633835 -78.606656) (xy 248.687828 -78.620772) (xy 248.739191 -78.642599)
			(xy 248.786829 -78.671672) (xy 248.829725 -78.707371) (xy 248.866967 -78.748935) (xy 248.897761 -78.795479)
			(xy 248.921449 -78.84601) (xy 248.937527 -78.899452) (xy 248.945653 -78.954666) (xy 248.946162 -78.98257)
			(xy 248.945653 -79.010474) (xy 248.937527 -79.065688) (xy 248.921449 -79.11913) (xy 248.897761 -79.169661)
			(xy 248.866967 -79.216205) (xy 248.829725 -79.257769) (xy 248.786829 -79.293468) (xy 248.739191 -79.322541)
			(xy 248.687828 -79.344368) (xy 248.633835 -79.358484) (xy 248.578361 -79.364587) (xy 248.52259 -79.362549)
			(xy 248.467711 -79.352412) (xy 248.414891 -79.334393) (xy 248.365259 -79.308875) (xy 248.319871 -79.276403)
			(xy 248.279694 -79.237668) (xy 248.245586 -79.193496) (xy 248.218272 -79.144828) (xy 248.198336 -79.092702)
			(xy 248.186201 -79.038229) (xy 248.182128 -78.98257) (xy 242.888051 -78.98257) (xy 242.889821 -78.992536)
			(xy 242.913662 -79.172348) (xy 242.929581 -79.353033) (xy 242.937548 -79.534243) (xy 242.938046 -79.624936)
			(xy 242.937548 -79.715629) (xy 242.929581 -79.896839) (xy 242.913662 -80.077524) (xy 242.889821 -80.257336)
			(xy 242.858106 -80.435927) (xy 242.818577 -80.612952) (xy 242.77131 -80.788071) (xy 242.716398 -80.960944)
			(xy 242.653944 -81.131238) (xy 242.584071 -81.298625) (xy 242.506913 -81.462781) (xy 242.422619 -81.62339)
			(xy 242.331352 -81.780141) (xy 242.244684 -81.915) (xy 258.012182 -81.915) (xy 258.016253 -81.859378)
			(xy 258.028379 -81.804941) (xy 258.048302 -81.75285) (xy 258.075598 -81.704215) (xy 258.109684 -81.660072)
			(xy 258.149833 -81.621363) (xy 258.195191 -81.588912) (xy 258.244791 -81.563411) (xy 258.297575 -81.545404)
			(xy 258.352418 -81.535274) (xy 258.408152 -81.533237) (xy 258.463589 -81.539337) (xy 258.517546 -81.553443)
			(xy 258.568875 -81.575255) (xy 258.616481 -81.604309) (xy 258.659349 -81.639984) (xy 258.696566 -81.681521)
			(xy 258.727339 -81.728034) (xy 258.751011 -81.778531) (xy 258.767079 -81.831938) (xy 258.775199 -81.887114)
			(xy 258.775708 -81.915) (xy 258.775199 -81.942886) (xy 258.767079 -81.998062) (xy 258.751011 -82.051469)
			(xy 258.727339 -82.101966) (xy 258.696566 -82.148479) (xy 258.659349 -82.190016) (xy 258.616481 -82.225691)
			(xy 258.568875 -82.254745) (xy 258.517546 -82.276557) (xy 258.463589 -82.290663) (xy 258.408152 -82.296763)
			(xy 258.352418 -82.294726) (xy 258.297575 -82.284596) (xy 258.244791 -82.266589) (xy 258.195191 -82.241088)
			(xy 258.149833 -82.208637) (xy 258.109684 -82.169928) (xy 258.075598 -82.125785) (xy 258.048302 -82.07715)
			(xy 258.028379 -82.025059) (xy 258.016253 -81.970622) (xy 258.012182 -81.915) (xy 242.244684 -81.915)
			(xy 242.233288 -81.932732) (xy 242.128616 -82.080868) (xy 242.017538 -82.224264) (xy 241.900269 -82.362642)
			(xy 241.777035 -82.495736) (xy 241.648074 -82.623288) (xy 241.513634 -82.745053) (xy 241.373976 -82.860795)
			(xy 241.229369 -82.970291) (xy 241.080092 -83.073329) (xy 240.926433 -83.169711) (xy 240.768689 -83.259251)
			(xy 240.607164 -83.341776) (xy 240.442171 -83.417126) (xy 240.274026 -83.485156) (xy 240.103056 -83.545735)
			(xy 239.92959 -83.598746) (xy 239.753963 -83.644086) (xy 239.576514 -83.681668) (xy 239.397586 -83.71142)
			(xy 239.217523 -83.733283) (xy 239.036674 -83.747217) (xy 238.855387 -83.753193) (xy 238.674013 -83.751201)
			(xy 238.492901 -83.741243) (xy 238.312402 -83.723341) (xy 238.132863 -83.697527) (xy 237.954631 -83.663852)
			(xy 237.77805 -83.622381) (xy 237.603462 -83.573193) (xy 237.431202 -83.516385) (xy 237.261604 -83.452065)
			(xy 237.094995 -83.380357) (xy 236.931696 -83.301401) (xy 236.772023 -83.215348) (xy 236.616284 -83.122364)
			(xy 236.464779 -83.02263) (xy 236.317802 -82.916337) (xy 236.175635 -82.803691) (xy 236.038553 -82.684909)
			(xy 235.906821 -82.56022) (xy 235.780693 -82.429866) (xy 235.660412 -82.294097) (xy 235.546211 -82.153176)
			(xy 235.43831 -82.007375) (xy 235.336918 -81.856975) (xy 235.242229 -81.702267) (xy 235.154427 -81.543548)
			(xy 235.073682 -81.381127) (xy 235.000149 -81.215315) (xy 234.93397 -81.046434) (xy 234.875272 -80.874809)
			(xy 234.82417 -80.700771) (xy 234.780762 -80.524657) (xy 234.745131 -80.346805) (xy 234.717347 -80.167561)
			(xy 234.697463 -79.987269) (xy 234.685517 -79.806277) (xy 234.681532 -79.624936) (xy 212.938106 -79.624936)
			(xy 212.937608 -79.715629) (xy 212.929641 -79.896839) (xy 212.913722 -80.077524) (xy 212.889881 -80.257336)
			(xy 212.858166 -80.435927) (xy 212.818637 -80.612952) (xy 212.77137 -80.788071) (xy 212.716458 -80.960944)
			(xy 212.654004 -81.131238) (xy 212.584131 -81.298625) (xy 212.506973 -81.462781) (xy 212.422679 -81.62339)
			(xy 212.331412 -81.780141) (xy 212.233348 -81.932732) (xy 212.128676 -82.080868) (xy 212.017598 -82.224264)
			(xy 211.900329 -82.362642) (xy 211.777095 -82.495736) (xy 211.648134 -82.623288) (xy 211.513694 -82.745053)
			(xy 211.374036 -82.860795) (xy 211.229429 -82.970291) (xy 211.080152 -83.073329) (xy 210.926493 -83.169711)
			(xy 210.768749 -83.259251) (xy 210.607224 -83.341776) (xy 210.442231 -83.417126) (xy 210.274086 -83.485156)
			(xy 210.103116 -83.545735) (xy 209.92965 -83.598746) (xy 209.754023 -83.644086) (xy 209.576574 -83.681668)
			(xy 209.397646 -83.71142) (xy 209.217583 -83.733283) (xy 209.036734 -83.747217) (xy 208.855447 -83.753193)
			(xy 208.674073 -83.751201) (xy 208.492961 -83.741243) (xy 208.312462 -83.723341) (xy 208.132923 -83.697527)
			(xy 207.954691 -83.663852) (xy 207.77811 -83.622381) (xy 207.603522 -83.573193) (xy 207.431262 -83.516385)
			(xy 207.261664 -83.452065) (xy 207.095055 -83.380357) (xy 206.931756 -83.301401) (xy 206.772083 -83.215348)
			(xy 206.616344 -83.122364) (xy 206.464839 -83.02263) (xy 206.317862 -82.916337) (xy 206.175695 -82.803691)
			(xy 206.038613 -82.684909) (xy 205.906881 -82.56022) (xy 205.780753 -82.429866) (xy 205.660472 -82.294097)
			(xy 205.546271 -82.153176) (xy 205.43837 -82.007375) (xy 205.336978 -81.856975) (xy 205.242289 -81.702267)
			(xy 205.154487 -81.543548) (xy 205.073742 -81.381127) (xy 205.000209 -81.215315) (xy 204.93403 -81.046434)
			(xy 204.875332 -80.874809) (xy 204.82423 -80.700771) (xy 204.780822 -80.524657) (xy 204.745191 -80.346805)
			(xy 204.717407 -80.167561) (xy 204.697523 -79.987269) (xy 204.685577 -79.806277) (xy 204.681592 -79.624936)
			(xy 189.712092 -79.624936) (xy 189.712092 -80.83169) (xy 185.17489 -85.368892) (xy 182.894224 -85.368892)
			(xy 182.886822 -85.375727) (xy 182.868223 -85.383435) (xy 182.858156 -85.383878) (xy 173.66996 -85.383878)
			(xy 173.659893 -85.383447) (xy 173.641302 -85.37572) (xy 173.633892 -85.368892) (xy 173.115986 -84.850986)
			(xy 173.108591 -84.844132) (xy 173.089992 -84.83639) (xy 173.079918 -84.836) (xy 171.3738 -84.836)
			(xy 171.355004 -84.84362) (xy 171.347892 -84.850986) (xy 171.158154 -85.040724) (xy 171.158154 -88.034622)
			(xy 259.58495 -88.034622) (xy 259.589021 -87.979) (xy 259.601147 -87.924563) (xy 259.62107 -87.872472)
			(xy 259.648366 -87.823837) (xy 259.682452 -87.779694) (xy 259.722601 -87.740985) (xy 259.767959 -87.708534)
			(xy 259.817559 -87.683033) (xy 259.870343 -87.665026) (xy 259.925186 -87.654896) (xy 259.98092 -87.652859)
			(xy 260.036357 -87.658959) (xy 260.090314 -87.673065) (xy 260.141643 -87.694877) (xy 260.189249 -87.723931)
			(xy 260.232117 -87.759606) (xy 260.269334 -87.801143) (xy 260.300107 -87.847656) (xy 260.323779 -87.898153)
			(xy 260.339847 -87.95156) (xy 260.347967 -88.006736) (xy 260.348476 -88.034622) (xy 260.347967 -88.062508)
			(xy 260.339847 -88.117684) (xy 260.323779 -88.171091) (xy 260.300107 -88.221588) (xy 260.269334 -88.268101)
			(xy 260.232117 -88.309638) (xy 260.189249 -88.345313) (xy 260.141643 -88.374367) (xy 260.090314 -88.396179)
			(xy 260.036357 -88.410285) (xy 259.98092 -88.416385) (xy 259.925186 -88.414348) (xy 259.870343 -88.404218)
			(xy 259.817559 -88.386211) (xy 259.767959 -88.36071) (xy 259.722601 -88.328259) (xy 259.682452 -88.28955)
			(xy 259.648366 -88.245407) (xy 259.62107 -88.196772) (xy 259.601147 -88.144681) (xy 259.589021 -88.090244)
			(xy 259.58495 -88.034622) (xy 171.158154 -88.034622) (xy 171.158154 -90.002868) (xy 170.818302 -90.34272)
			(xy 225.042728 -90.34272) (xy 225.046801 -90.287061) (xy 225.058936 -90.232588) (xy 225.078872 -90.180462)
			(xy 225.106186 -90.131794) (xy 225.140294 -90.087622) (xy 225.180471 -90.048887) (xy 225.225859 -90.016415)
			(xy 225.275491 -89.990897) (xy 225.328311 -89.972878) (xy 225.38319 -89.962741) (xy 225.438961 -89.960703)
			(xy 225.494435 -89.966806) (xy 225.548428 -89.980922) (xy 225.599791 -90.002749) (xy 225.647429 -90.031822)
			(xy 225.690325 -90.067521) (xy 225.727567 -90.109085) (xy 225.758361 -90.155629) (xy 225.782049 -90.20616)
			(xy 225.798127 -90.259602) (xy 225.806253 -90.314816) (xy 225.806762 -90.34272) (xy 225.806253 -90.370624)
			(xy 225.799183 -90.418666) (xy 259.057138 -90.418666) (xy 259.061209 -90.363044) (xy 259.073335 -90.308607)
			(xy 259.093258 -90.256516) (xy 259.120554 -90.207881) (xy 259.15464 -90.163738) (xy 259.194789 -90.125029)
			(xy 259.240147 -90.092578) (xy 259.289747 -90.067077) (xy 259.342531 -90.04907) (xy 259.397374 -90.03894)
			(xy 259.453108 -90.036903) (xy 259.508545 -90.043003) (xy 259.562502 -90.057109) (xy 259.613831 -90.078921)
			(xy 259.661437 -90.107975) (xy 259.704305 -90.14365) (xy 259.741522 -90.185187) (xy 259.772295 -90.2317)
			(xy 259.795967 -90.282197) (xy 259.812035 -90.335604) (xy 259.820155 -90.39078) (xy 259.820664 -90.418666)
			(xy 259.820155 -90.446552) (xy 259.812035 -90.501728) (xy 259.795967 -90.555135) (xy 259.772295 -90.605632)
			(xy 259.741522 -90.652145) (xy 259.704305 -90.693682) (xy 259.661437 -90.729357) (xy 259.613831 -90.758411)
			(xy 259.562502 -90.780223) (xy 259.508545 -90.794329) (xy 259.453108 -90.800429) (xy 259.397374 -90.798392)
			(xy 259.342531 -90.788262) (xy 259.289747 -90.770255) (xy 259.240147 -90.744754) (xy 259.194789 -90.712303)
			(xy 259.15464 -90.673594) (xy 259.120554 -90.629451) (xy 259.093258 -90.580816) (xy 259.073335 -90.528725)
			(xy 259.061209 -90.474288) (xy 259.057138 -90.418666) (xy 225.799183 -90.418666) (xy 225.798127 -90.425838)
			(xy 225.782049 -90.47928) (xy 225.758361 -90.529811) (xy 225.727567 -90.576355) (xy 225.690325 -90.617919)
			(xy 225.647429 -90.653618) (xy 225.599791 -90.682691) (xy 225.548428 -90.704518) (xy 225.494435 -90.718634)
			(xy 225.438961 -90.724737) (xy 225.38319 -90.722699) (xy 225.328311 -90.712562) (xy 225.275491 -90.694543)
			(xy 225.225859 -90.669025) (xy 225.180471 -90.636553) (xy 225.140294 -90.597818) (xy 225.106186 -90.553646)
			(xy 225.078872 -90.504978) (xy 225.058936 -90.452852) (xy 225.046801 -90.398379) (xy 225.042728 -90.34272)
			(xy 170.818302 -90.34272) (xy 170.631104 -90.529918) (xy 159.117538 -90.529918) (xy 155.45562 -86.868)
			(xy 150.008082 -86.868) (xy 149.998013 -86.867573) (xy 149.979414 -86.859854) (xy 149.972014 -86.853014)
			(xy 148.517864 -85.398864) (xy 148.510752 -85.391498) (xy 148.491956 -85.383878) (xy 122.819414 -85.383878)
			(xy 122.805698 -85.387688) (xy 122.799856 -85.391498) (xy 122.793852 -85.39489) (xy 122.780586 -85.398633)
			(xy 122.773694 -85.398864) (xy 105.216198 -85.398864) (xy 105.206129 -85.39844) (xy 105.187528 -85.390721)
			(xy 105.18013 -85.383878) (xy 102.55885 -82.762598) (xy 102.551738 -82.755232) (xy 102.532942 -82.747612)
			(xy 97.756726 -82.747612) (xy 97.746662 -82.748049) (xy 97.728078 -82.755784) (xy 97.720658 -82.762598)
			(xy 88.484456 -91.9988) (xy 205.07859 -91.9988) (xy 205.082603 -91.935004) (xy 205.094581 -91.872214)
			(xy 205.114334 -91.811421) (xy 205.141551 -91.753582) (xy 205.175802 -91.699611) (xy 205.216547 -91.650358)
			(xy 205.263144 -91.606601) (xy 205.314859 -91.569028) (xy 205.370874 -91.538234) (xy 205.430307 -91.514702)
			(xy 205.492221 -91.498805) (xy 205.555639 -91.490794) (xy 205.5876 -91.490292) (xy 205.621318 -91.49083)
			(xy 205.688163 -91.499735) (xy 205.753247 -91.517388) (xy 205.81543 -91.54348) (xy 205.873623 -91.577555)
			(xy 205.926807 -91.619015) (xy 205.95082 -91.642692) (xy 205.958258 -91.649621) (xy 205.976987 -91.657481)
			(xy 205.987142 -91.657932) (xy 208.762092 -91.657932) (xy 208.772095 -91.657406) (xy 208.790581 -91.649755)
			(xy 208.804733 -91.635614) (xy 208.812398 -91.617135) (xy 208.812892 -91.607132) (xy 208.812892 -91.1606)
			(xy 208.813438 -91.143885) (xy 208.82209 -91.111594) (xy 208.838805 -91.082643) (xy 208.862443 -91.059005)
			(xy 208.891394 -91.04229) (xy 208.923685 -91.033638) (xy 208.9404 -91.033092) (xy 210.6168 -91.033092)
			(xy 210.633515 -91.033638) (xy 210.665806 -91.04229) (xy 210.694757 -91.059005) (xy 210.718395 -91.082643)
			(xy 210.73511 -91.111594) (xy 210.743762 -91.143885) (xy 210.744308 -91.1606) (xy 210.744308 -91.9988)
			(xy 219.099406 -91.9988) (xy 219.103295 -91.912191) (xy 219.114933 -91.826279) (xy 219.134224 -91.741757)
			(xy 219.161015 -91.659304) (xy 219.195089 -91.579584) (xy 219.236171 -91.50324) (xy 219.283932 -91.430885)
			(xy 219.337986 -91.363103) (xy 219.397899 -91.30044) (xy 219.463188 -91.243399) (xy 219.533326 -91.19244)
			(xy 219.607751 -91.147973) (xy 219.685861 -91.110357) (xy 219.767029 -91.079894) (xy 219.850601 -91.05683)
			(xy 219.935905 -91.04135) (xy 220.022252 -91.033578) (xy 220.0656 -91.033092) (xy 220.109259 -91.033518)
			(xy 220.19622 -91.041395) (xy 220.282114 -91.057093) (xy 220.36624 -91.080484) (xy 220.44791 -91.111377)
			(xy 220.526456 -91.149519) (xy 220.601236 -91.194599) (xy 220.67164 -91.246248) (xy 220.737091 -91.304045)
			(xy 220.797055 -91.367516) (xy 220.851042 -91.436143) (xy 220.898611 -91.509366) (xy 220.939372 -91.586585)
			(xy 220.956632 -91.62669) (xy 220.960908 -91.635694) (xy 220.975027 -91.649741) (xy 220.993413 -91.657399)
			(xy 221.003368 -91.657932) (xy 221.92488 -91.657932) (xy 221.935247 -91.657429) (xy 221.954263 -91.649161)
			(xy 221.96171 -91.64193) (xy 221.977931 -91.625499) (xy 222.01568 -91.598927) (xy 222.058028 -91.580554)
			(xy 222.103221 -91.571142) (xy 222.126302 -91.570556) (xy 222.393764 -91.570556) (xy 222.393764 -91.5797)
			(xy 222.394287 -91.589703) (xy 222.40194 -91.608188) (xy 222.416082 -91.62234) (xy 222.434561 -91.630006)
			(xy 222.444564 -91.6305) (xy 222.892112 -91.6305) (xy 222.917258 -91.614244) (xy 222.923608 -91.600528)
			(xy 222.927991 -91.591817) (xy 222.942028 -91.578303) (xy 222.960094 -91.571006) (xy 222.969836 -91.570556)
			(xy 223.186498 -91.570556) (xy 223.208779 -91.571037) (xy 223.252468 -91.579812) (xy 223.293597 -91.596964)
			(xy 223.330576 -91.621831) (xy 223.361976 -91.653452) (xy 223.386583 -91.690604) (xy 223.403447 -91.731852)
			(xy 223.411916 -91.775602) (xy 223.412304 -91.797886) (xy 223.412304 -91.821) (xy 224.433128 -91.821)
			(xy 224.437201 -91.765341) (xy 224.449336 -91.710868) (xy 224.469272 -91.658742) (xy 224.496586 -91.610074)
			(xy 224.530694 -91.565902) (xy 224.570871 -91.527167) (xy 224.616259 -91.494695) (xy 224.665891 -91.469177)
			(xy 224.718711 -91.451158) (xy 224.77359 -91.441021) (xy 224.829361 -91.438983) (xy 224.884835 -91.445086)
			(xy 224.938828 -91.459202) (xy 224.990191 -91.481029) (xy 225.037829 -91.510102) (xy 225.080725 -91.545801)
			(xy 225.117967 -91.587365) (xy 225.148761 -91.633909) (xy 225.172449 -91.68444) (xy 225.188527 -91.737882)
			(xy 225.196653 -91.793096) (xy 225.197162 -91.821) (xy 225.196653 -91.848904) (xy 225.188527 -91.904118)
			(xy 225.172449 -91.95756) (xy 225.148761 -92.008091) (xy 225.117967 -92.054635) (xy 225.080725 -92.096199)
			(xy 225.037829 -92.131898) (xy 224.990191 -92.160971) (xy 224.938828 -92.182798) (xy 224.884835 -92.196914)
			(xy 224.829361 -92.203017) (xy 224.77359 -92.200979) (xy 224.718711 -92.190842) (xy 224.665891 -92.172823)
			(xy 224.616259 -92.147305) (xy 224.570871 -92.114833) (xy 224.530694 -92.076098) (xy 224.496586 -92.031926)
			(xy 224.469272 -91.983258) (xy 224.449336 -91.931132) (xy 224.437201 -91.876659) (xy 224.433128 -91.821)
			(xy 223.412304 -91.821) (xy 223.412304 -92.098622) (xy 223.411991 -92.117778) (xy 223.405737 -92.155572)
			(xy 223.399858 -92.173806) (xy 223.398542 -92.177805) (xy 223.397138 -92.186106) (xy 223.397064 -92.190316)
			(xy 223.397064 -92.463874) (xy 223.40189 -92.474288) (xy 223.413279 -92.499725) (xy 223.429357 -92.553085)
			(xy 223.437477 -92.608221) (xy 223.437958 -92.636086) (xy 223.437472 -92.663337) (xy 223.429716 -92.717285)
			(xy 223.414361 -92.76958) (xy 223.391719 -92.819157) (xy 223.380252 -92.837) (xy 229.386892 -92.837)
			(xy 229.386892 -91.1606) (xy 229.387438 -91.143885) (xy 229.39609 -91.111594) (xy 229.412805 -91.082643)
			(xy 229.436443 -91.059005) (xy 229.465394 -91.04229) (xy 229.497685 -91.033638) (xy 229.5144 -91.033092)
			(xy 231.1908 -91.033092) (xy 231.207515 -91.033638) (xy 231.239806 -91.04229) (xy 231.268757 -91.059005)
			(xy 231.292395 -91.082643) (xy 231.30911 -91.111594) (xy 231.317762 -91.143885) (xy 231.318308 -91.1606)
			(xy 231.318308 -91.607132) (xy 231.318762 -91.617143) (xy 231.326434 -91.635637) (xy 231.340597 -91.649789)
			(xy 231.359097 -91.657446) (xy 231.369108 -91.657932) (xy 234.067858 -91.657932) (xy 234.078017 -91.657488)
			(xy 234.096753 -91.649637) (xy 234.10418 -91.642692) (xy 234.128198 -91.619022) (xy 234.181382 -91.577562)
			(xy 234.239574 -91.543488) (xy 234.301756 -91.517396) (xy 234.366839 -91.499743) (xy 234.433683 -91.490839)
			(xy 234.4674 -91.490292) (xy 234.499361 -91.490794) (xy 234.562779 -91.498805) (xy 234.624693 -91.514702)
			(xy 234.684126 -91.538234) (xy 234.740141 -91.569028) (xy 234.791856 -91.606601) (xy 234.838453 -91.650358)
			(xy 234.879198 -91.699611) (xy 234.913449 -91.753582) (xy 234.940666 -91.811421) (xy 234.960419 -91.872214)
			(xy 234.972397 -91.935004) (xy 234.976411 -91.9988) (xy 234.972397 -92.062596) (xy 234.960419 -92.125386)
			(xy 234.940666 -92.186179) (xy 234.913449 -92.244018) (xy 234.879198 -92.297989) (xy 234.838453 -92.347242)
			(xy 234.791856 -92.390999) (xy 234.740141 -92.428572) (xy 234.684126 -92.459366) (xy 234.624693 -92.482898)
			(xy 234.562779 -92.498795) (xy 234.499361 -92.506806) (xy 234.4674 -92.507308) (xy 234.433682 -92.50677)
			(xy 234.366837 -92.497865) (xy 234.301753 -92.480212) (xy 234.23957 -92.45412) (xy 234.181377 -92.420045)
			(xy 234.128193 -92.378585) (xy 234.10418 -92.354908) (xy 234.096742 -92.347979) (xy 234.078013 -92.340119)
			(xy 234.067858 -92.339668) (xy 231.369108 -92.339668) (xy 231.359105 -92.340194) (xy 231.340619 -92.347845)
			(xy 231.326467 -92.361986) (xy 231.318802 -92.380465) (xy 231.318308 -92.390468) (xy 231.318308 -92.837)
			(xy 231.317762 -92.853715) (xy 231.30911 -92.886006) (xy 231.292395 -92.914957) (xy 231.268757 -92.938595)
			(xy 231.239806 -92.95531) (xy 231.207515 -92.963962) (xy 231.1908 -92.964508) (xy 229.5144 -92.964508)
			(xy 229.497685 -92.963962) (xy 229.465394 -92.95531) (xy 229.436443 -92.938595) (xy 229.412805 -92.914957)
			(xy 229.39609 -92.886006) (xy 229.387438 -92.853715) (xy 229.386892 -92.837) (xy 223.380252 -92.837)
			(xy 223.362253 -92.865007) (xy 223.326562 -92.906198) (xy 223.285371 -92.941889) (xy 223.239521 -92.971355)
			(xy 223.189944 -92.993997) (xy 223.137649 -93.009352) (xy 223.083701 -93.017108) (xy 223.029199 -93.017108)
			(xy 222.975251 -93.009352) (xy 222.922956 -92.993997) (xy 222.873379 -92.971355) (xy 222.827529 -92.941889)
			(xy 222.786338 -92.906198) (xy 222.750647 -92.865007) (xy 222.721181 -92.819157) (xy 222.698539 -92.76958)
			(xy 222.683184 -92.717285) (xy 222.675428 -92.663337) (xy 222.674942 -92.636086) (xy 222.675453 -92.608224)
			(xy 222.683597 -92.553097) (xy 222.699652 -92.499735) (xy 222.71101 -92.474288) (xy 222.715836 -92.463874)
			(xy 222.715836 -92.3163) (xy 222.715313 -92.306297) (xy 222.70766 -92.287812) (xy 222.693518 -92.27366)
			(xy 222.675039 -92.265994) (xy 222.665036 -92.2655) (xy 222.419926 -92.2655) (xy 222.394018 -92.28328)
			(xy 222.38843 -92.297758) (xy 222.386144 -92.303346) (xy 222.379032 -92.310458) (xy 222.37161 -92.317271)
			(xy 222.353028 -92.325008) (xy 222.342964 -92.325444) (xy 222.30334 -92.325444) (xy 222.296482 -92.327222)
			(xy 222.274199 -92.333033) (xy 222.228575 -92.339274) (xy 222.20555 -92.339668) (xy 221.003368 -92.339668)
			(xy 220.993403 -92.340163) (xy 220.97499 -92.347796) (xy 220.960897 -92.36189) (xy 220.956632 -92.37091)
			(xy 220.939314 -92.410986) (xy 220.898543 -92.48819) (xy 220.850969 -92.561399) (xy 220.79698 -92.630013)
			(xy 220.737016 -92.693473) (xy 220.671569 -92.751261) (xy 220.601172 -92.802904) (xy 220.526399 -92.847981)
			(xy 220.447863 -92.886123) (xy 220.366204 -92.91702) (xy 220.282089 -92.940418) (xy 220.196205 -92.956127)
			(xy 220.109254 -92.964018) (xy 220.0656 -92.964508) (xy 220.022252 -92.964022) (xy 219.935905 -92.95625)
			(xy 219.850601 -92.94077) (xy 219.767029 -92.917706) (xy 219.685861 -92.887243) (xy 219.607751 -92.849627)
			(xy 219.533326 -92.80516) (xy 219.463188 -92.754201) (xy 219.397899 -92.69716) (xy 219.337986 -92.634497)
			(xy 219.283932 -92.566715) (xy 219.236171 -92.49436) (xy 219.195089 -92.418016) (xy 219.161015 -92.338296)
			(xy 219.134224 -92.255843) (xy 219.114933 -92.171321) (xy 219.103295 -92.085409) (xy 219.099406 -91.9988)
			(xy 210.744308 -91.9988) (xy 210.744308 -92.837) (xy 210.743762 -92.853715) (xy 210.73511 -92.886006)
			(xy 210.718395 -92.914957) (xy 210.694757 -92.938595) (xy 210.665806 -92.95531) (xy 210.633515 -92.963962)
			(xy 210.6168 -92.964508) (xy 208.9404 -92.964508) (xy 208.923685 -92.963962) (xy 208.891394 -92.95531)
			(xy 208.862443 -92.938595) (xy 208.838805 -92.914957) (xy 208.82209 -92.886006) (xy 208.813438 -92.853715)
			(xy 208.812892 -92.837) (xy 208.812892 -92.390468) (xy 208.812438 -92.380457) (xy 208.804766 -92.361963)
			(xy 208.790603 -92.347811) (xy 208.772103 -92.340154) (xy 208.762092 -92.339668) (xy 205.987142 -92.339668)
			(xy 205.976983 -92.340112) (xy 205.958247 -92.347963) (xy 205.95082 -92.354908) (xy 205.926802 -92.378578)
			(xy 205.873618 -92.420038) (xy 205.815426 -92.454112) (xy 205.753244 -92.480204) (xy 205.688161 -92.497857)
			(xy 205.621317 -92.506761) (xy 205.5876 -92.507308) (xy 205.555639 -92.506806) (xy 205.492221 -92.498795)
			(xy 205.430307 -92.482898) (xy 205.370874 -92.459366) (xy 205.314859 -92.428572) (xy 205.263144 -92.390999)
			(xy 205.216547 -92.347242) (xy 205.175802 -92.297989) (xy 205.141551 -92.244018) (xy 205.114334 -92.186179)
			(xy 205.094581 -92.125386) (xy 205.082603 -92.062596) (xy 205.07859 -91.9988) (xy 88.484456 -91.9988)
			(xy 88.305386 -92.17787) (xy 88.29802 -92.184982) (xy 88.2904 -92.203778) (xy 88.2904 -96.347066)
			(xy 155.066735 -96.347066) (xy 155.066735 -96.184934) (xy 155.074691 -96.022997) (xy 155.090583 -95.861646)
			(xy 155.114372 -95.701269) (xy 155.146003 -95.542252) (xy 155.185398 -95.384979) (xy 155.232462 -95.229828)
			(xy 155.287083 -95.077173) (xy 155.349128 -94.927383) (xy 155.418448 -94.780817) (xy 155.494877 -94.637829)
			(xy 155.578229 -94.498764) (xy 155.668305 -94.363956) (xy 155.764887 -94.23373) (xy 155.867743 -94.108401)
			(xy 155.976624 -93.988269) (xy 156.091269 -93.873624) (xy 156.211401 -93.764743) (xy 156.33673 -93.661887)
			(xy 156.466956 -93.565305) (xy 156.601764 -93.475229) (xy 156.740829 -93.391877) (xy 156.883817 -93.315448)
			(xy 157.030383 -93.246128) (xy 157.180173 -93.184083) (xy 157.332828 -93.129462) (xy 157.487979 -93.082398)
			(xy 157.645252 -93.043003) (xy 157.804269 -93.011372) (xy 157.964646 -92.987583) (xy 158.125997 -92.971691)
			(xy 158.287934 -92.963735) (xy 158.450066 -92.963735) (xy 158.612003 -92.971691) (xy 158.773354 -92.987583)
			(xy 158.933731 -93.011372) (xy 159.092748 -93.043003) (xy 159.250021 -93.082398) (xy 159.405172 -93.129462)
			(xy 159.557827 -93.184083) (xy 159.707617 -93.246128) (xy 159.854183 -93.315448) (xy 159.997171 -93.391877)
			(xy 160.136236 -93.475229) (xy 160.271044 -93.565305) (xy 160.40127 -93.661887) (xy 160.526599 -93.764743)
			(xy 160.646731 -93.873624) (xy 160.761376 -93.988269) (xy 160.870257 -94.108401) (xy 160.973113 -94.23373)
			(xy 161.069695 -94.363956) (xy 161.159771 -94.498764) (xy 161.183768 -94.5388) (xy 208.812391 -94.5388)
			(xy 208.816394 -94.450938) (xy 208.82837 -94.363804) (xy 208.848221 -94.27812) (xy 208.87578 -94.194596)
			(xy 208.910821 -94.113924) (xy 208.953052 -94.036773) (xy 209.002124 -93.963782) (xy 209.057631 -93.895556)
			(xy 209.119111 -93.83266) (xy 209.186056 -93.775615) (xy 209.257911 -93.724894) (xy 209.334081 -93.680917)
			(xy 209.413934 -93.644049) (xy 209.496809 -93.614596) (xy 209.582019 -93.5928) (xy 209.668858 -93.578844)
			(xy 209.756606 -93.572841) (xy 209.844536 -93.574843) (xy 209.931921 -93.584833) (xy 210.018034 -93.602728)
			(xy 210.102164 -93.628379) (xy 210.183612 -93.661574) (xy 210.261705 -93.702038) (xy 210.335794 -93.749436)
			(xy 210.405266 -93.803375) (xy 210.469545 -93.863408) (xy 210.528099 -93.929037) (xy 210.580443 -93.999719)
			(xy 210.626142 -94.074868) (xy 210.664818 -94.153861) (xy 210.69615 -94.236044) (xy 210.71988 -94.320736)
			(xy 210.73581 -94.407235) (xy 210.743808 -94.494823) (xy 210.744308 -94.5388) (xy 229.386391 -94.5388)
			(xy 229.390394 -94.450938) (xy 229.40237 -94.363804) (xy 229.422221 -94.27812) (xy 229.44978 -94.194596)
			(xy 229.484821 -94.113924) (xy 229.527052 -94.036773) (xy 229.576124 -93.963782) (xy 229.631631 -93.895556)
			(xy 229.693111 -93.83266) (xy 229.760056 -93.775615) (xy 229.831911 -93.724894) (xy 229.908081 -93.680917)
			(xy 229.987934 -93.644049) (xy 230.070809 -93.614596) (xy 230.156019 -93.5928) (xy 230.242858 -93.578844)
			(xy 230.330606 -93.572841) (xy 230.418536 -93.574843) (xy 230.505921 -93.584833) (xy 230.592034 -93.602728)
			(xy 230.676164 -93.628379) (xy 230.757612 -93.661574) (xy 230.835705 -93.702038) (xy 230.909794 -93.749436)
			(xy 230.979266 -93.803375) (xy 231.043545 -93.863408) (xy 231.102099 -93.929037) (xy 231.154443 -93.999719)
			(xy 231.200142 -94.074868) (xy 231.238818 -94.153861) (xy 231.27015 -94.236044) (xy 231.29388 -94.320736)
			(xy 231.30981 -94.407235) (xy 231.317808 -94.494823) (xy 231.318308 -94.5388) (xy 231.317808 -94.582777)
			(xy 231.30981 -94.670365) (xy 231.29388 -94.756864) (xy 231.27015 -94.841556) (xy 231.238818 -94.923739)
			(xy 231.200142 -95.002732) (xy 231.154443 -95.077881) (xy 231.102099 -95.148563) (xy 231.043545 -95.214192)
			(xy 230.979266 -95.274225) (xy 230.909794 -95.328164) (xy 230.835705 -95.375562) (xy 230.757612 -95.416026)
			(xy 230.676164 -95.449221) (xy 230.592034 -95.474872) (xy 230.505921 -95.492767) (xy 230.418536 -95.502757)
			(xy 230.330606 -95.504759) (xy 230.242858 -95.498756) (xy 230.156019 -95.4848) (xy 230.070809 -95.463004)
			(xy 229.987934 -95.433551) (xy 229.908081 -95.396683) (xy 229.831911 -95.352706) (xy 229.760056 -95.301985)
			(xy 229.693111 -95.24494) (xy 229.631631 -95.182044) (xy 229.576124 -95.113818) (xy 229.527052 -95.040827)
			(xy 229.484821 -94.963676) (xy 229.44978 -94.883004) (xy 229.422221 -94.79948) (xy 229.40237 -94.713796)
			(xy 229.390394 -94.626662) (xy 229.386391 -94.5388) (xy 210.744308 -94.5388) (xy 210.743808 -94.582777)
			(xy 210.73581 -94.670365) (xy 210.71988 -94.756864) (xy 210.69615 -94.841556) (xy 210.664818 -94.923739)
			(xy 210.626142 -95.002732) (xy 210.580443 -95.077881) (xy 210.528099 -95.148563) (xy 210.469545 -95.214192)
			(xy 210.405266 -95.274225) (xy 210.335794 -95.328164) (xy 210.261705 -95.375562) (xy 210.183612 -95.416026)
			(xy 210.102164 -95.449221) (xy 210.018034 -95.474872) (xy 209.931921 -95.492767) (xy 209.844536 -95.502757)
			(xy 209.756606 -95.504759) (xy 209.668858 -95.498756) (xy 209.582019 -95.4848) (xy 209.496809 -95.463004)
			(xy 209.413934 -95.433551) (xy 209.334081 -95.396683) (xy 209.257911 -95.352706) (xy 209.186056 -95.301985)
			(xy 209.119111 -95.24494) (xy 209.057631 -95.182044) (xy 209.002124 -95.113818) (xy 208.953052 -95.040827)
			(xy 208.910821 -94.963676) (xy 208.87578 -94.883004) (xy 208.848221 -94.79948) (xy 208.82837 -94.713796)
			(xy 208.816394 -94.626662) (xy 208.812391 -94.5388) (xy 161.183768 -94.5388) (xy 161.243123 -94.637829)
			(xy 161.319552 -94.780817) (xy 161.388872 -94.927383) (xy 161.450917 -95.077173) (xy 161.505538 -95.229828)
			(xy 161.552602 -95.384979) (xy 161.591997 -95.542252) (xy 161.623628 -95.701269) (xy 161.647417 -95.861646)
			(xy 161.663309 -96.022997) (xy 161.671265 -96.184934) (xy 161.671762 -96.266) (xy 161.671265 -96.347066)
			(xy 161.663309 -96.509003) (xy 161.647417 -96.670354) (xy 161.623628 -96.830731) (xy 161.591997 -96.989748)
			(xy 161.552602 -97.147021) (xy 161.505538 -97.302172) (xy 161.450917 -97.454827) (xy 161.388872 -97.604617)
			(xy 161.319552 -97.751183) (xy 161.243123 -97.894171) (xy 161.22944 -97.917) (xy 219.099892 -97.917)
			(xy 219.099892 -96.2406) (xy 219.100438 -96.223885) (xy 219.10909 -96.191594) (xy 219.125805 -96.162643)
			(xy 219.149443 -96.139005) (xy 219.178394 -96.12229) (xy 219.210685 -96.113638) (xy 219.2274 -96.113092)
			(xy 220.9038 -96.113092) (xy 220.920515 -96.113638) (xy 220.952806 -96.12229) (xy 220.981757 -96.139005)
			(xy 221.005395 -96.162643) (xy 221.02211 -96.191594) (xy 221.030762 -96.223885) (xy 221.031308 -96.2406)
			(xy 221.031308 -96.687132) (xy 221.031762 -96.697143) (xy 221.039434 -96.715637) (xy 221.053597 -96.729789)
			(xy 221.072097 -96.737446) (xy 221.082108 -96.737932) (xy 221.92488 -96.737932) (xy 221.935247 -96.737429)
			(xy 221.954263 -96.729161) (xy 221.96171 -96.72193) (xy 221.977931 -96.705499) (xy 222.01568 -96.678927)
			(xy 222.058028 -96.660554) (xy 222.103221 -96.651142) (xy 222.126302 -96.650556) (xy 222.393764 -96.650556)
			(xy 222.393764 -96.6597) (xy 222.394287 -96.669703) (xy 222.40194 -96.688188) (xy 222.416082 -96.70234)
			(xy 222.434561 -96.710006) (xy 222.444564 -96.7105) (xy 222.665036 -96.7105) (xy 222.675046 -96.710041)
			(xy 222.693539 -96.70237) (xy 222.70769 -96.688208) (xy 222.715349 -96.66971) (xy 222.715836 -96.6597)
			(xy 222.715836 -95.193612) (xy 222.71101 -95.183198) (xy 222.699617 -95.157763) (xy 222.68354 -95.104402)
			(xy 222.675422 -95.049266) (xy 222.674942 -95.0214) (xy 222.675428 -94.994149) (xy 222.683184 -94.940201)
			(xy 222.698539 -94.887906) (xy 222.721181 -94.838329) (xy 222.750647 -94.792479) (xy 222.786338 -94.751288)
			(xy 222.827529 -94.715597) (xy 222.873379 -94.686131) (xy 222.922956 -94.663489) (xy 222.975251 -94.648134)
			(xy 223.029199 -94.640378) (xy 223.083701 -94.640378) (xy 223.137649 -94.648134) (xy 223.189944 -94.663489)
			(xy 223.239521 -94.686131) (xy 223.285371 -94.715597) (xy 223.326562 -94.751288) (xy 223.362253 -94.792479)
			(xy 223.391719 -94.838329) (xy 223.414361 -94.887906) (xy 223.429716 -94.940201) (xy 223.437472 -94.994149)
			(xy 223.437958 -95.0214) (xy 223.437442 -95.049262) (xy 223.4293 -95.104388) (xy 223.413247 -95.15775)
			(xy 223.40189 -95.183198) (xy 223.397064 -95.193612) (xy 223.397064 -96.774) (xy 224.475292 -96.774)
			(xy 224.479363 -96.718378) (xy 224.491489 -96.663941) (xy 224.511412 -96.61185) (xy 224.538708 -96.563215)
			(xy 224.572794 -96.519072) (xy 224.612943 -96.480363) (xy 224.658301 -96.447912) (xy 224.707901 -96.422411)
			(xy 224.760685 -96.404404) (xy 224.815528 -96.394274) (xy 224.871262 -96.392237) (xy 224.926699 -96.398337)
			(xy 224.980656 -96.412443) (xy 225.031985 -96.434255) (xy 225.079591 -96.463309) (xy 225.122459 -96.498984)
			(xy 225.159676 -96.540521) (xy 225.190449 -96.587034) (xy 225.214121 -96.637531) (xy 225.230189 -96.690938)
			(xy 225.238309 -96.746114) (xy 225.238818 -96.774) (xy 225.238309 -96.801886) (xy 225.230189 -96.857062)
			(xy 225.214121 -96.910469) (xy 225.190449 -96.960966) (xy 225.159676 -97.007479) (xy 225.122459 -97.049016)
			(xy 225.079591 -97.084691) (xy 225.031985 -97.113745) (xy 224.980656 -97.135557) (xy 224.926699 -97.149663)
			(xy 224.871262 -97.155763) (xy 224.815528 -97.153726) (xy 224.760685 -97.143596) (xy 224.707901 -97.125589)
			(xy 224.658301 -97.100088) (xy 224.612943 -97.067637) (xy 224.572794 -97.028928) (xy 224.538708 -96.984785)
			(xy 224.511412 -96.93615) (xy 224.491489 -96.884059) (xy 224.479363 -96.829622) (xy 224.475292 -96.774)
			(xy 223.397064 -96.774) (xy 223.397064 -96.785684) (xy 223.397178 -96.78989) (xy 223.398577 -96.798186)
			(xy 223.399858 -96.802194) (xy 223.405788 -96.820415) (xy 223.412037 -96.858218) (xy 223.412304 -96.877378)
			(xy 223.412304 -97.178114) (xy 223.411853 -97.200392) (xy 223.403386 -97.24413) (xy 223.386527 -97.285366)
			(xy 223.361927 -97.322508) (xy 223.330536 -97.35412) (xy 223.293567 -97.37898) (xy 223.25245 -97.396128)
			(xy 223.208772 -97.4049) (xy 223.186498 -97.405444) (xy 222.919036 -97.405444) (xy 222.919036 -97.3963)
			(xy 222.918513 -97.386297) (xy 222.91086 -97.367812) (xy 222.896718 -97.35366) (xy 222.878239 -97.345994)
			(xy 222.868236 -97.3455) (xy 222.419926 -97.3455) (xy 222.394018 -97.36328) (xy 222.38843 -97.377758)
			(xy 222.386144 -97.383346) (xy 222.379032 -97.390458) (xy 222.37161 -97.397271) (xy 222.353028 -97.405008)
			(xy 222.342964 -97.405444) (xy 222.30334 -97.405444) (xy 222.296482 -97.407222) (xy 222.274199 -97.413033)
			(xy 222.228575 -97.419274) (xy 222.20555 -97.419668) (xy 221.082108 -97.419668) (xy 221.072105 -97.420194)
			(xy 221.053619 -97.427845) (xy 221.039467 -97.441986) (xy 221.031802 -97.460465) (xy 221.031308 -97.470468)
			(xy 221.031308 -97.917) (xy 221.030762 -97.933715) (xy 221.028435 -97.9424) (xy 258.012182 -97.9424)
			(xy 258.016253 -97.886778) (xy 258.028379 -97.832341) (xy 258.048302 -97.78025) (xy 258.075598 -97.731615)
			(xy 258.109684 -97.687472) (xy 258.149833 -97.648763) (xy 258.195191 -97.616312) (xy 258.244791 -97.590811)
			(xy 258.297575 -97.572804) (xy 258.352418 -97.562674) (xy 258.408152 -97.560637) (xy 258.463589 -97.566737)
			(xy 258.517546 -97.580843) (xy 258.568875 -97.602655) (xy 258.616481 -97.631709) (xy 258.659349 -97.667384)
			(xy 258.696566 -97.708921) (xy 258.727339 -97.755434) (xy 258.751011 -97.805931) (xy 258.767079 -97.859338)
			(xy 258.775199 -97.914514) (xy 258.775708 -97.9424) (xy 258.775199 -97.970286) (xy 258.767079 -98.025462)
			(xy 258.751011 -98.078869) (xy 258.727339 -98.129366) (xy 258.696566 -98.175879) (xy 258.659349 -98.217416)
			(xy 258.616481 -98.253091) (xy 258.568875 -98.282145) (xy 258.517546 -98.303957) (xy 258.463589 -98.318063)
			(xy 258.408152 -98.324163) (xy 258.352418 -98.322126) (xy 258.297575 -98.311996) (xy 258.244791 -98.293989)
			(xy 258.195191 -98.268488) (xy 258.149833 -98.236037) (xy 258.109684 -98.197328) (xy 258.075598 -98.153185)
			(xy 258.048302 -98.10455) (xy 258.028379 -98.052459) (xy 258.016253 -97.998022) (xy 258.012182 -97.9424)
			(xy 221.028435 -97.9424) (xy 221.02211 -97.966006) (xy 221.005395 -97.994957) (xy 220.981757 -98.018595)
			(xy 220.952806 -98.03531) (xy 220.920515 -98.043962) (xy 220.9038 -98.044508) (xy 219.2274 -98.044508)
			(xy 219.210685 -98.043962) (xy 219.178394 -98.03531) (xy 219.149443 -98.018595) (xy 219.125805 -97.994957)
			(xy 219.10909 -97.966006) (xy 219.100438 -97.933715) (xy 219.099892 -97.917) (xy 161.22944 -97.917)
			(xy 161.159771 -98.033236) (xy 161.069695 -98.168044) (xy 160.973113 -98.29827) (xy 160.870257 -98.423599)
			(xy 160.761376 -98.543731) (xy 160.646731 -98.658376) (xy 160.526599 -98.767257) (xy 160.40127 -98.870113)
			(xy 160.271044 -98.966695) (xy 160.136236 -99.056771) (xy 159.997171 -99.140123) (xy 159.854183 -99.216552)
			(xy 159.707617 -99.285872) (xy 159.557827 -99.347917) (xy 159.405172 -99.402538) (xy 159.401467 -99.403662)
			(xy 292.595044 -99.403662) (xy 292.599115 -99.34804) (xy 292.611241 -99.293603) (xy 292.631164 -99.241512)
			(xy 292.65846 -99.192877) (xy 292.692546 -99.148734) (xy 292.732695 -99.110025) (xy 292.778053 -99.077574)
			(xy 292.827653 -99.052073) (xy 292.880437 -99.034066) (xy 292.93528 -99.023936) (xy 292.991014 -99.021899)
			(xy 293.046451 -99.027999) (xy 293.100408 -99.042105) (xy 293.151737 -99.063917) (xy 293.199343 -99.092971)
			(xy 293.242211 -99.128646) (xy 293.279428 -99.170183) (xy 293.310201 -99.216696) (xy 293.333873 -99.267193)
			(xy 293.349941 -99.3206) (xy 293.358061 -99.375776) (xy 293.35857 -99.403662) (xy 293.358061 -99.431548)
			(xy 293.349941 -99.486724) (xy 293.333873 -99.540131) (xy 293.310201 -99.590628) (xy 293.279428 -99.637141)
			(xy 293.242211 -99.678678) (xy 293.199343 -99.714353) (xy 293.151737 -99.743407) (xy 293.100408 -99.765219)
			(xy 293.046451 -99.779325) (xy 292.991014 -99.785425) (xy 292.93528 -99.783388) (xy 292.880437 -99.773258)
			(xy 292.827653 -99.755251) (xy 292.778053 -99.72975) (xy 292.732695 -99.697299) (xy 292.692546 -99.65859)
			(xy 292.65846 -99.614447) (xy 292.631164 -99.565812) (xy 292.611241 -99.513721) (xy 292.599115 -99.459284)
			(xy 292.595044 -99.403662) (xy 159.401467 -99.403662) (xy 159.250021 -99.449602) (xy 159.092748 -99.488997)
			(xy 158.933731 -99.520628) (xy 158.773354 -99.544417) (xy 158.612003 -99.560309) (xy 158.450066 -99.568265)
			(xy 158.287934 -99.568265) (xy 158.125997 -99.560309) (xy 157.964646 -99.544417) (xy 157.804269 -99.520628)
			(xy 157.645252 -99.488997) (xy 157.487979 -99.449602) (xy 157.332828 -99.402538) (xy 157.180173 -99.347917)
			(xy 157.030383 -99.285872) (xy 156.883817 -99.216552) (xy 156.740829 -99.140123) (xy 156.601764 -99.056771)
			(xy 156.466956 -98.966695) (xy 156.33673 -98.870113) (xy 156.211401 -98.767257) (xy 156.091269 -98.658376)
			(xy 155.976624 -98.543731) (xy 155.867743 -98.423599) (xy 155.764887 -98.29827) (xy 155.668305 -98.168044)
			(xy 155.578229 -98.033236) (xy 155.494877 -97.894171) (xy 155.418448 -97.751183) (xy 155.349128 -97.604617)
			(xy 155.287083 -97.454827) (xy 155.232462 -97.302172) (xy 155.185398 -97.147021) (xy 155.146003 -96.989748)
			(xy 155.114372 -96.830731) (xy 155.090583 -96.670354) (xy 155.074691 -96.509003) (xy 155.066735 -96.347066)
			(xy 88.2904 -96.347066) (xy 88.2904 -100.689918) (xy 88.29086 -100.699795) (xy 88.295418 -100.711)
			(xy 226.820982 -100.711) (xy 226.825053 -100.655378) (xy 226.837179 -100.600941) (xy 226.857102 -100.54885)
			(xy 226.884398 -100.500215) (xy 226.918484 -100.456072) (xy 226.958633 -100.417363) (xy 227.003991 -100.384912)
			(xy 227.053591 -100.359411) (xy 227.106375 -100.341404) (xy 227.161218 -100.331274) (xy 227.216952 -100.329237)
			(xy 227.272389 -100.335337) (xy 227.326346 -100.349443) (xy 227.377675 -100.371255) (xy 227.425281 -100.400309)
			(xy 227.468149 -100.435984) (xy 227.505366 -100.477521) (xy 227.536139 -100.524034) (xy 227.559811 -100.574531)
			(xy 227.575879 -100.627938) (xy 227.583999 -100.683114) (xy 227.584508 -100.711) (xy 227.583999 -100.738886)
			(xy 227.575879 -100.794062) (xy 227.559811 -100.847469) (xy 227.536139 -100.897966) (xy 227.505366 -100.944479)
			(xy 227.468149 -100.986016) (xy 227.425281 -101.021691) (xy 227.377675 -101.050745) (xy 227.326346 -101.072557)
			(xy 227.272389 -101.086663) (xy 227.216952 -101.092763) (xy 227.161218 -101.090726) (xy 227.106375 -101.080596)
			(xy 227.053591 -101.062589) (xy 227.003991 -101.037088) (xy 226.958633 -101.004637) (xy 226.918484 -100.965928)
			(xy 226.884398 -100.921785) (xy 226.857102 -100.87315) (xy 226.837179 -100.821059) (xy 226.825053 -100.766622)
			(xy 226.820982 -100.711) (xy 88.295418 -100.711) (xy 88.298303 -100.718094) (xy 88.304878 -100.725478)
			(xy 88.910414 -101.331014) (xy 88.910922 -101.331522) (xy 88.9183 -101.338112) (xy 88.936599 -101.345579)
			(xy 88.946482 -101.346) (xy 194.616324 -101.346) (xy 194.646296 -101.333808) (xy 194.649852 -101.332792)
			(xy 194.66306 -101.331014) (xy 333.034386 -101.331014) (xy 333.036672 -101.328728) (xy 343.658698 -101.328728)
			(xy 343.668577 -101.328272) (xy 343.686883 -101.320837) (xy 343.694258 -101.31425) (xy 344.452956 -100.555552)
			(xy 344.453464 -100.555044) (xy 344.460045 -100.547662) (xy 344.467492 -100.529363) (xy 344.467942 -100.519484)
			(xy 344.467942 -85.627464) (xy 344.460322 -85.608668) (xy 344.452956 -85.601556) (xy 341.924386 -83.072986)
			(xy 341.916991 -83.066132) (xy 341.898392 -83.05839) (xy 341.888318 -83.058) (xy 329.093322 -83.058)
			(xy 329.074526 -83.06562) (xy 329.067414 -83.072986) (xy 322.345812 -89.794588) (xy 322.338415 -89.801438)
			(xy 322.319817 -89.809178) (xy 322.309744 -89.809574) (xy 302.768508 -89.809574) (xy 302.758437 -89.809995)
			(xy 302.739828 -89.817704) (xy 302.73244 -89.82456) (xy 300.355 -92.202) (xy 288.737802 -92.202)
			(xy 288.356802 -92.583) (xy 288.338006 -92.59062) (xy 288.330894 -92.597986) (xy 287.923986 -93.004894)
			(xy 287.917129 -93.012288) (xy 287.909379 -93.030887) (xy 287.909 -93.040962) (xy 287.909 -93.198442)
			(xy 287.909762 -93.218) (xy 287.909762 -93.218254) (xy 287.909258 -93.245512) (xy 287.901467 -93.299468)
			(xy 287.88608 -93.351767) (xy 287.863409 -93.401345) (xy 287.833916 -93.447194) (xy 287.798201 -93.488381)
			(xy 287.75699 -93.524069) (xy 287.711122 -93.553531) (xy 287.661528 -93.576169) (xy 287.609219 -93.591521)
			(xy 287.555258 -93.599276) (xy 287.500742 -93.599276) (xy 287.446781 -93.591521) (xy 287.394472 -93.576169)
			(xy 287.344878 -93.553531) (xy 287.29901 -93.524069) (xy 287.257799 -93.488381) (xy 287.222084 -93.447194)
			(xy 287.192591 -93.401345) (xy 287.16992 -93.351767) (xy 287.154533 -93.299468) (xy 287.146742 -93.245512)
			(xy 287.146238 -93.218254) (xy 287.146238 -93.218) (xy 287.147 -93.198442) (xy 287.147 -92.974922)
			(xy 287.13938 -92.956126) (xy 287.132014 -92.949014) (xy 286.283146 -92.100146) (xy 286.275747 -92.093303)
			(xy 286.257148 -92.085581) (xy 286.247078 -92.08516) (xy 277.221442 -92.08516) (xy 277.211377 -92.084725)
			(xy 277.192792 -92.076991) (xy 277.185374 -92.070174) (xy 274.93976 -89.82456) (xy 274.932362 -89.817713)
			(xy 274.913763 -89.809984) (xy 274.903692 -89.809574) (xy 270.505936 -89.809574) (xy 270.495872 -89.809139)
			(xy 270.477286 -89.801405) (xy 270.469868 -89.794588) (xy 270.208502 -89.533222) (xy 270.176321 -89.534407)
			(xy 270.111927 -89.535677) (xy 270.079724 -89.535762) (xy 270.0782 -89.535762) (xy 269.997134 -89.535265)
			(xy 269.835197 -89.527309) (xy 269.673846 -89.511417) (xy 269.513469 -89.487628) (xy 269.354452 -89.455997)
			(xy 269.197179 -89.416602) (xy 269.042028 -89.369538) (xy 268.889373 -89.314917) (xy 268.739583 -89.252872)
			(xy 268.593017 -89.183552) (xy 268.450029 -89.107123) (xy 268.310964 -89.023771) (xy 268.176156 -88.933695)
			(xy 268.04593 -88.837113) (xy 267.920601 -88.734257) (xy 267.800469 -88.625376) (xy 267.685824 -88.510731)
			(xy 267.576943 -88.390599) (xy 267.474087 -88.26527) (xy 267.377505 -88.135044) (xy 267.287429 -88.000236)
			(xy 267.204077 -87.861171) (xy 267.127648 -87.718183) (xy 267.058328 -87.571617) (xy 266.996283 -87.421827)
			(xy 266.941662 -87.269172) (xy 266.894598 -87.114021) (xy 266.855203 -86.956748) (xy 266.823572 -86.797731)
			(xy 266.799783 -86.637354) (xy 266.783891 -86.476003) (xy 266.775935 -86.314066) (xy 266.775438 -86.233)
			(xy 266.775438 -86.231476) (xy 266.775524 -86.199273) (xy 266.776795 -86.134879) (xy 266.777978 -86.102698)
			(xy 260.668008 -79.992728) (xy 260.657594 -79.9846) (xy 260.649212 -79.979774) (xy 260.64083 -79.977996)
			(xy 260.633406 -79.976226) (xy 260.619971 -79.969002) (xy 260.614414 -79.963772) (xy 257.570986 -76.920344)
			(xy 257.564139 -76.912947) (xy 257.556412 -76.894347) (xy 257.556 -76.884276) (xy 257.556 -55.357522)
			(xy 257.54838 -55.338726) (xy 257.541014 -55.331614) (xy 257.357372 -55.147972) (xy 257.349975 -55.141122)
			(xy 257.331377 -55.133387) (xy 257.321304 -55.132986) (xy 239.939068 -55.132986) (xy 239.932115 -55.132751)
			(xy 239.918718 -55.129025) (xy 239.912652 -55.12562) (xy 239.912398 -55.125366) (xy 239.906343 -55.121932)
			(xy 239.89294 -55.118197) (xy 239.885982 -55.118) (xy 228.68255 -55.118) (xy 228.672484 -55.117568)
			(xy 228.653893 -55.10984) (xy 228.646482 -55.103014) (xy 226.775264 -53.231796) (xy 226.768411 -53.2244)
			(xy 226.760668 -53.205802) (xy 226.760278 -53.195728) (xy 226.760278 -27.325574) (xy 226.760705 -27.315505)
			(xy 226.768424 -27.296906) (xy 226.775264 -27.289506) (xy 228.056948 -26.007822) (xy 228.064348 -26.000981)
			(xy 228.082946 -25.99326) (xy 228.093016 -25.992836) (xy 236.31652 -25.992836) (xy 236.330719 -25.992364)
			(xy 236.358019 -25.984541) (xy 236.382111 -25.969504) (xy 236.401132 -25.948417) (xy 236.413613 -25.922907)
			(xy 236.41859 -25.894948) (xy 236.415677 -25.866699) (xy 236.4051 -25.840343) (xy 236.387676 -25.817917)
			(xy 236.376464 -25.809194) (xy 236.302112 -25.754295) (xy 236.157829 -25.638755) (xy 236.018862 -25.516872)
			(xy 235.885491 -25.388891) (xy 235.757982 -25.255068) (xy 235.636591 -25.115671) (xy 235.521562 -24.970981)
			(xy 235.413125 -24.821286) (xy 235.311497 -24.666887) (xy 235.216883 -24.508093) (xy 235.129472 -24.345224)
			(xy 235.049439 -24.178605) (xy 234.976944 -24.008571) (xy 234.912134 -23.835461) (xy 234.855137 -23.659625)
			(xy 234.806069 -23.481413) (xy 234.765027 -23.301183) (xy 234.732094 -23.119297) (xy 234.707336 -22.936119)
			(xy 234.690803 -22.752016) (xy 234.682527 -22.567358) (xy 234.68203 -22.474936) (xy 234.682535 -22.383605)
			(xy 234.690615 -22.201121) (xy 234.706759 -22.019173) (xy 234.730935 -21.838117) (xy 234.763096 -21.658308)
			(xy 234.803179 -21.480098) (xy 234.851106 -21.303835) (xy 234.906783 -21.129864) (xy 234.9701 -20.958527)
			(xy 235.040935 -20.790158) (xy 235.119147 -20.625086) (xy 235.204585 -20.463637) (xy 235.29708 -20.306124)
			(xy 235.396452 -20.152857) (xy 235.502507 -20.004135) (xy 235.615036 -19.86025) (xy 235.733819 -19.721484)
			(xy 235.858625 -19.588108) (xy 235.989207 -19.460382) (xy 236.125312 -19.338558) (xy 236.266672 -19.222873)
			(xy 236.413011 -19.113555) (xy 236.564043 -19.010816) (xy 236.719471 -18.914859) (xy 236.878991 -18.825871)
			(xy 237.042291 -18.744026) (xy 237.209052 -18.669484) (xy 237.378947 -18.602392) (xy 237.551643 -18.54288)
			(xy 237.726803 -18.491066) (xy 237.904083 -18.44705) (xy 238.083137 -18.410919) (xy 238.263613 -18.382743)
			(xy 238.44516 -18.362579) (xy 238.62742 -18.350464) (xy 238.810038 -18.346423) (xy 238.992656 -18.350464)
			(xy 239.174916 -18.362579) (xy 239.356463 -18.382743) (xy 239.536939 -18.410919) (xy 239.715993 -18.44705)
			(xy 239.893273 -18.491066) (xy 240.068433 -18.54288) (xy 240.241129 -18.602392) (xy 240.411024 -18.669484)
			(xy 240.577785 -18.744026) (xy 240.741085 -18.825871) (xy 240.900605 -18.914859) (xy 241.056033 -19.010816)
			(xy 241.207065 -19.113555) (xy 241.353404 -19.222873) (xy 241.494764 -19.338558) (xy 241.630869 -19.460382)
			(xy 241.761451 -19.588108) (xy 241.886257 -19.721484) (xy 242.00504 -19.86025) (xy 242.117569 -20.004135)
			(xy 242.223624 -20.152857) (xy 242.322996 -20.306124) (xy 242.415491 -20.463637) (xy 242.500929 -20.625086)
			(xy 242.579141 -20.790158) (xy 242.649976 -20.958527) (xy 242.713293 -21.129864) (xy 242.76897 -21.303835)
			(xy 242.816897 -21.480098) (xy 242.85698 -21.658308) (xy 242.889141 -21.838117) (xy 242.913317 -22.019173)
			(xy 242.929461 -22.201121) (xy 242.937541 -22.383605) (xy 242.938046 -22.474936) (xy 242.93753 -22.567357)
			(xy 242.929254 -22.752015) (xy 242.912721 -22.936116) (xy 242.887963 -23.119293) (xy 242.85503 -23.301179)
			(xy 242.813988 -23.481407) (xy 242.76492 -23.659618) (xy 242.707924 -23.835454) (xy 242.643113 -24.008562)
			(xy 242.570619 -24.178595) (xy 242.490586 -24.345213) (xy 242.403175 -24.508082) (xy 242.308561 -24.666874)
			(xy 242.206933 -24.821272) (xy 242.098496 -24.970965) (xy 241.983467 -25.115655) (xy 241.862076 -25.25505)
			(xy 241.734568 -25.388872) (xy 241.601196 -25.516852) (xy 241.46223 -25.638734) (xy 241.317947 -25.754273)
			(xy 241.243612 -25.809194) (xy 241.232426 -25.817945) (xy 241.214998 -25.840355) (xy 241.204417 -25.866698)
			(xy 241.201501 -25.894937) (xy 241.206475 -25.922886) (xy 241.218956 -25.948385) (xy 241.237976 -25.969459)
			(xy 241.262066 -25.98448) (xy 241.289361 -25.992284) (xy 241.303556 -25.992836) (xy 276.000718 -25.992836)
			(xy 276.010596 -25.992377) (xy 276.028898 -25.984938) (xy 276.036278 -25.978358) (xy 276.379432 -25.635204)
			(xy 276.37994 -25.634696) (xy 276.386516 -25.627313) (xy 276.39395 -25.609013) (xy 276.394418 -25.599136)
			(xy 276.394418 -13.593064) (xy 276.394848 -13.582997) (xy 276.402574 -13.564404) (xy 276.409404 -13.556996)
			(xy 278.521414 -11.444986) (xy 278.528809 -11.438132) (xy 278.547408 -11.43039) (xy 278.557482 -11.43)
			(xy 302.543718 -11.43) (xy 302.553595 -11.42954) (xy 302.571894 -11.422097) (xy 302.579278 -11.415522)
			(xy 303.692814 -10.301986) (xy 303.700209 -10.295132) (xy 303.718808 -10.28739) (xy 303.728882 -10.287)
			(xy 325.708518 -10.287) (xy 325.718587 -10.287427) (xy 325.737186 -10.295146) (xy 325.744586 -10.301986)
			(xy 326.857614 -11.415014) (xy 326.858122 -11.415522) (xy 326.8655 -11.422112) (xy 326.883799 -11.429579)
			(xy 326.893682 -11.43) (xy 335.487518 -11.43) (xy 335.497587 -11.430427) (xy 335.516186 -11.438146)
			(xy 335.523586 -11.444986) (xy 339.33384 -15.25524) (xy 355.002592 -15.25524) (xy 355.876352 -16.129)
			(xy 379.942852 -16.129) (xy 379.943283 -16.095618) (xy 379.950758 -16.029272) (xy 379.965615 -15.964181)
			(xy 379.987667 -15.901163) (xy 380.016635 -15.84101) (xy 380.052157 -15.784479) (xy 380.093785 -15.732281)
			(xy 380.140996 -15.685072) (xy 380.193196 -15.643446) (xy 380.249728 -15.607926) (xy 380.309882 -15.578959)
			(xy 380.372901 -15.556909) (xy 380.437992 -15.542055) (xy 380.504338 -15.534582) (xy 380.53772 -15.534132)
			(xy 380.571099 -15.534632) (xy 380.637438 -15.542108) (xy 380.702522 -15.556962) (xy 380.765535 -15.57901)
			(xy 380.825683 -15.607973) (xy 380.882211 -15.643487) (xy 380.934408 -15.685106) (xy 380.958344 -15.708376)
			(xy 381.224536 -15.974568) (xy 381.235712 -15.986252) (xy 381.38354 -16.13408) (xy 381.390276 -16.141473)
			(xy 381.397988 -16.159906) (xy 381.398526 -16.169894) (xy 381.398526 -16.378428) (xy 381.39878 -16.395192)
			(xy 381.39878 -17.507204) (xy 381.398332 -17.540339) (xy 381.390954 -17.606198) (xy 381.376301 -17.670828)
			(xy 381.354555 -17.733428) (xy 381.325985 -17.793224) (xy 381.290945 -17.849473) (xy 381.270764 -17.875758)
			(xy 381.264238 -17.885092) (xy 381.259193 -17.907263) (xy 381.264206 -17.929442) (xy 381.270764 -17.93875)
			(xy 381.290942 -17.965037) (xy 381.325988 -18.021283) (xy 381.354561 -18.081077) (xy 381.376307 -18.143678)
			(xy 381.390955 -18.208309) (xy 381.398325 -18.274169) (xy 381.39878 -18.307304) (xy 381.39878 -18.917158)
			(xy 381.56515 -18.917158) (xy 381.565658 -18.889253) (xy 381.573774 -18.834037) (xy 381.589841 -18.780591)
			(xy 381.601218 -18.755106) (xy 381.606044 -18.744946) (xy 381.606044 -18.56867) (xy 381.602742 -18.555716)
			(xy 381.599186 -18.549874) (xy 381.589789 -18.532621) (xy 381.576417 -18.495685) (xy 381.569632 -18.456993)
			(xy 381.569214 -18.437352) (xy 381.569214 -18.169382) (xy 381.583692 -18.169382) (xy 381.595245 -18.167617)
			(xy 381.615061 -18.15528) (xy 381.627408 -18.13547) (xy 381.629158 -18.123916) (xy 381.629158 -17.645126)
			(xy 381.620014 -17.645126) (xy 381.61001 -17.644601) (xy 381.591524 -17.636951) (xy 381.577371 -17.62281)
			(xy 381.569707 -17.604329) (xy 381.569214 -17.594326) (xy 381.569214 -17.377156) (xy 381.569779 -17.354814)
			(xy 381.578574 -17.311002) (xy 381.595777 -17.26976) (xy 381.62072 -17.232683) (xy 381.65244 -17.201208)
			(xy 381.689708 -17.176551) (xy 381.731082 -17.159668) (xy 381.77496 -17.151211) (xy 381.797306 -17.150842)
			(xy 381.800354 -17.150842) (xy 381.810423 -17.150408) (xy 381.829021 -17.142695) (xy 381.836422 -17.135856)
			(xy 381.940054 -17.032224) (xy 381.946613 -17.024828) (xy 381.954065 -17.006538) (xy 381.954532 -16.996664)
			(xy 381.954532 -16.555212) (xy 381.949706 -16.545052) (xy 381.938326 -16.519568) (xy 381.922263 -16.46612)
			(xy 381.914146 -16.410905) (xy 381.913638 -16.383) (xy 381.914124 -16.355731) (xy 381.921886 -16.301747)
			(xy 381.937251 -16.249417) (xy 381.959908 -16.199807) (xy 381.989394 -16.153926) (xy 382.025109 -16.112709)
			(xy 382.066326 -16.076994) (xy 382.112207 -16.047508) (xy 382.161817 -16.024851) (xy 382.214147 -16.009486)
			(xy 382.268131 -16.001724) (xy 382.322669 -16.001724) (xy 382.376653 -16.009486) (xy 382.428983 -16.024851)
			(xy 382.478593 -16.047508) (xy 382.524474 -16.076994) (xy 382.565691 -16.112709) (xy 382.601406 -16.153926)
			(xy 382.630892 -16.199807) (xy 382.653549 -16.249417) (xy 382.668914 -16.301747) (xy 382.676676 -16.355731)
			(xy 382.677162 -16.383) (xy 382.676674 -16.410905) (xy 382.66855 -16.466122) (xy 382.652475 -16.519568)
			(xy 382.641094 -16.545052) (xy 382.636268 -16.555212) (xy 382.636268 -17.158716) (xy 382.636014 -17.170908)
			(xy 382.636014 -17.278858) (xy 382.635576 -17.288865) (xy 382.627842 -17.307329) (xy 382.621028 -17.314672)
			(xy 382.545844 -17.389856) (xy 382.545336 -17.390618) (xy 382.536446 -17.399762) (xy 382.339596 -17.596358)
			(xy 382.332781 -17.603778) (xy 382.325047 -17.622362) (xy 382.32461 -17.632426) (xy 382.32461 -17.645126)
			(xy 382.315466 -17.645126) (xy 382.305453 -17.645561) (xy 382.286955 -17.653236) (xy 382.272803 -17.667406)
			(xy 382.265149 -17.685912) (xy 382.264666 -17.695926) (xy 382.264666 -18.169382) (xy 382.27381 -18.169382)
			(xy 382.283816 -18.16988) (xy 382.302305 -18.177539) (xy 382.316456 -18.191689) (xy 382.324119 -18.210176)
			(xy 382.32461 -18.220182) (xy 382.32461 -18.437352) (xy 382.324165 -18.456991) (xy 382.31737 -18.495677)
			(xy 382.304026 -18.532619) (xy 382.294638 -18.549874) (xy 382.291082 -18.555716) (xy 382.28778 -18.56867)
			(xy 382.28778 -18.744946) (xy 382.292606 -18.755106) (xy 382.303973 -18.780595) (xy 382.32004 -18.83404)
			(xy 382.328163 -18.889254) (xy 382.328674 -18.917158) (xy 382.328188 -18.944427) (xy 382.320426 -18.998411)
			(xy 382.305061 -19.050741) (xy 382.282404 -19.100351) (xy 382.252918 -19.146232) (xy 382.217203 -19.187449)
			(xy 382.175986 -19.223164) (xy 382.130105 -19.25265) (xy 382.080495 -19.275307) (xy 382.028165 -19.290672)
			(xy 381.974181 -19.298434) (xy 381.919643 -19.298434) (xy 381.865659 -19.290672) (xy 381.813329 -19.275307)
			(xy 381.763719 -19.25265) (xy 381.717838 -19.223164) (xy 381.676621 -19.187449) (xy 381.640906 -19.146232)
			(xy 381.61142 -19.100351) (xy 381.588763 -19.050741) (xy 381.573398 -18.998411) (xy 381.565636 -18.944427)
			(xy 381.56515 -18.917158) (xy 381.39878 -18.917158) (xy 381.39878 -18.923) (xy 381.398277 -18.957618)
			(xy 381.390239 -19.026385) (xy 381.374272 -19.093755) (xy 381.350592 -19.158815) (xy 381.319519 -19.220686)
			(xy 381.281474 -19.278532) (xy 381.23697 -19.331569) (xy 381.18661 -19.379081) (xy 381.131074 -19.420426)
			(xy 381.071114 -19.455044) (xy 381.007541 -19.482467) (xy 380.941214 -19.502324) (xy 380.87303 -19.514346)
			(xy 380.803912 -19.518372) (xy 380.734794 -19.514346) (xy 380.66661 -19.502324) (xy 380.600283 -19.482467)
			(xy 380.53671 -19.455044) (xy 380.47675 -19.420426) (xy 380.421214 -19.379081) (xy 380.370854 -19.331569)
			(xy 380.32635 -19.278532) (xy 380.288305 -19.220686) (xy 380.257232 -19.158815) (xy 380.233552 -19.093755)
			(xy 380.217585 -19.026385) (xy 380.209547 -18.957618) (xy 380.209044 -18.923) (xy 380.209044 -18.307304)
			(xy 380.209492 -18.274169) (xy 380.216869 -18.20831) (xy 380.231522 -18.14368) (xy 380.253268 -18.081079)
			(xy 380.281838 -18.021283) (xy 380.316879 -17.965034) (xy 380.33706 -17.93875) (xy 380.343668 -17.929466)
			(xy 380.348684 -17.907263) (xy 380.343636 -17.885068) (xy 380.33706 -17.875758) (xy 380.31689 -17.849465)
			(xy 380.281842 -17.793221) (xy 380.253267 -17.733428) (xy 380.23152 -17.670828) (xy 380.21687 -17.606198)
			(xy 380.209499 -17.540339) (xy 380.209044 -17.507204) (xy 380.209044 -16.6624) (xy 380.208633 -16.652329)
			(xy 380.200904 -16.63373) (xy 380.194058 -16.626332) (xy 380.117096 -16.549624) (xy 380.093821 -16.525691)
			(xy 380.052189 -16.473499) (xy 380.016664 -16.416974) (xy 379.987692 -16.356825) (xy 379.965638 -16.293811)
			(xy 379.950779 -16.228723) (xy 379.943303 -16.162381) (xy 379.942852 -16.129) (xy 355.876352 -16.129)
			(xy 357.146352 -17.399) (xy 357.156418 -17.399433) (xy 357.175009 -17.40716) (xy 357.18242 -17.413986)
			(xy 360.215434 -20.447) (xy 378.078238 -20.447) (xy 378.078646 -20.420672) (xy 378.08589 -20.368518)
			(xy 378.100226 -20.317852) (xy 378.121384 -20.269634) (xy 378.148962 -20.224778) (xy 378.16536 -20.204176)
			(xy 378.170672 -20.197187) (xy 378.176637 -20.180688) (xy 378.177044 -20.171918) (xy 378.177044 -18.56867)
			(xy 378.173742 -18.555716) (xy 378.170186 -18.549874) (xy 378.160789 -18.532621) (xy 378.147417 -18.495685)
			(xy 378.140632 -18.456993) (xy 378.140214 -18.437352) (xy 378.140214 -18.169382) (xy 378.154692 -18.169382)
			(xy 378.166245 -18.167617) (xy 378.186061 -18.15528) (xy 378.198408 -18.13547) (xy 378.200158 -18.123916)
			(xy 378.200158 -17.645126) (xy 378.191014 -17.645126) (xy 378.18101 -17.644601) (xy 378.162524 -17.636951)
			(xy 378.148371 -17.62281) (xy 378.140707 -17.604329) (xy 378.140214 -17.594326) (xy 378.140214 -17.377156)
			(xy 378.140672 -17.357518) (xy 378.147463 -17.318833) (xy 378.160801 -17.28189) (xy 378.170186 -17.264634)
			(xy 378.173742 -17.258792) (xy 378.177044 -17.245838) (xy 378.177044 -17.063212) (xy 378.172218 -17.053052)
			(xy 378.160839 -17.027568) (xy 378.144776 -16.97412) (xy 378.136658 -16.918905) (xy 378.13615 -16.891)
			(xy 378.136636 -16.863731) (xy 378.144398 -16.809747) (xy 378.159763 -16.757417) (xy 378.18242 -16.707807)
			(xy 378.211906 -16.661926) (xy 378.247621 -16.620709) (xy 378.288838 -16.584994) (xy 378.334719 -16.555508)
			(xy 378.384329 -16.532851) (xy 378.436659 -16.517486) (xy 378.490643 -16.509724) (xy 378.545181 -16.509724)
			(xy 378.599165 -16.517486) (xy 378.651495 -16.532851) (xy 378.701105 -16.555508) (xy 378.746986 -16.584994)
			(xy 378.788203 -16.620709) (xy 378.823918 -16.661926) (xy 378.853404 -16.707807) (xy 378.876061 -16.757417)
			(xy 378.891426 -16.809747) (xy 378.899188 -16.863731) (xy 378.899674 -16.891) (xy 379.27915 -16.891)
			(xy 379.279636 -16.863731) (xy 379.287398 -16.809747) (xy 379.302763 -16.757417) (xy 379.32542 -16.707807)
			(xy 379.354906 -16.661926) (xy 379.390621 -16.620709) (xy 379.431838 -16.584994) (xy 379.477719 -16.555508)
			(xy 379.527329 -16.532851) (xy 379.579659 -16.517486) (xy 379.633643 -16.509724) (xy 379.688181 -16.509724)
			(xy 379.742165 -16.517486) (xy 379.794495 -16.532851) (xy 379.844105 -16.555508) (xy 379.889986 -16.584994)
			(xy 379.931203 -16.620709) (xy 379.966918 -16.661926) (xy 379.996404 -16.707807) (xy 380.019061 -16.757417)
			(xy 380.034426 -16.809747) (xy 380.042188 -16.863731) (xy 380.042674 -16.891) (xy 380.042185 -16.918905)
			(xy 380.034061 -16.974122) (xy 380.017987 -17.027568) (xy 380.006606 -17.053052) (xy 380.00178 -17.063212)
			(xy 380.00178 -17.245838) (xy 380.005082 -17.258792) (xy 380.008638 -17.264634) (xy 380.018032 -17.281889)
			(xy 380.031407 -17.318823) (xy 380.038192 -17.357515) (xy 380.03861 -17.377156) (xy 380.03861 -17.645126)
			(xy 380.024132 -17.645126) (xy 380.012581 -17.646901) (xy 379.992763 -17.659232) (xy 379.980415 -17.679039)
			(xy 379.978666 -17.690592) (xy 379.978666 -18.169382) (xy 379.98781 -18.169382) (xy 379.997816 -18.16988)
			(xy 380.016305 -18.177539) (xy 380.030456 -18.191689) (xy 380.038119 -18.210176) (xy 380.03861 -18.220182)
			(xy 380.03861 -18.437352) (xy 380.038165 -18.456991) (xy 380.03137 -18.495677) (xy 380.018026 -18.532619)
			(xy 380.008638 -18.549874) (xy 380.005082 -18.555716) (xy 380.00178 -18.56867) (xy 380.00178 -20.00357)
			(xy 386.295635 -20.00357) (xy 386.295635 -19.87443) (xy 386.303585 -19.745535) (xy 386.319455 -19.617375)
			(xy 386.343184 -19.490434) (xy 386.374683 -19.365195) (xy 386.413832 -19.242132) (xy 386.460483 -19.121713)
			(xy 386.514458 -19.004394) (xy 386.575553 -18.89062) (xy 386.643536 -18.780823) (xy 386.71815 -18.67542)
			(xy 386.799111 -18.57481) (xy 386.886111 -18.479375) (xy 386.978822 -18.389476) (xy 387.076892 -18.305455)
			(xy 387.179947 -18.227631) (xy 387.287598 -18.156299) (xy 387.399437 -18.091729) (xy 387.515038 -18.034167)
			(xy 387.633963 -17.98383) (xy 387.755762 -17.94091) (xy 387.879972 -17.905569) (xy 388.006121 -17.877942)
			(xy 388.133733 -17.858133) (xy 388.262322 -17.846217) (xy 388.3914 -17.842241) (xy 388.520478 -17.846217)
			(xy 388.649067 -17.858133) (xy 388.776679 -17.877942) (xy 388.902828 -17.905569) (xy 389.027038 -17.94091)
			(xy 389.148837 -17.98383) (xy 389.267762 -18.034167) (xy 389.383363 -18.091729) (xy 389.495202 -18.156299)
			(xy 389.602853 -18.227631) (xy 389.705908 -18.305455) (xy 389.803978 -18.389476) (xy 389.896689 -18.479375)
			(xy 389.983689 -18.57481) (xy 390.06465 -18.67542) (xy 390.139264 -18.780823) (xy 390.207247 -18.89062)
			(xy 390.268342 -19.004394) (xy 390.322317 -19.121713) (xy 390.368968 -19.242132) (xy 390.408117 -19.365195)
			(xy 390.439616 -19.490434) (xy 390.463345 -19.617375) (xy 390.479215 -19.745535) (xy 390.487165 -19.87443)
			(xy 390.487662 -19.939) (xy 390.487165 -20.00357) (xy 390.479215 -20.132465) (xy 390.463345 -20.260625)
			(xy 390.439616 -20.387566) (xy 390.408117 -20.512805) (xy 390.368968 -20.635868) (xy 390.322317 -20.756287)
			(xy 390.268342 -20.873606) (xy 390.207247 -20.98738) (xy 390.139264 -21.097177) (xy 390.06465 -21.20258)
			(xy 389.983689 -21.30319) (xy 389.896689 -21.398625) (xy 389.803978 -21.488524) (xy 389.705908 -21.572545)
			(xy 389.602853 -21.650369) (xy 389.495202 -21.721701) (xy 389.383363 -21.786271) (xy 389.267762 -21.843833)
			(xy 389.148837 -21.89417) (xy 389.027038 -21.93709) (xy 388.902828 -21.972431) (xy 388.776679 -22.000058)
			(xy 388.649067 -22.019867) (xy 388.520478 -22.031783) (xy 388.3914 -22.03576) (xy 388.262322 -22.031783)
			(xy 388.133733 -22.019867) (xy 388.006121 -22.000058) (xy 387.879972 -21.972431) (xy 387.755762 -21.93709)
			(xy 387.633963 -21.89417) (xy 387.515038 -21.843833) (xy 387.399437 -21.786271) (xy 387.287598 -21.721701)
			(xy 387.179947 -21.650369) (xy 387.076892 -21.572545) (xy 386.978822 -21.488524) (xy 386.886111 -21.398625)
			(xy 386.799111 -21.30319) (xy 386.71815 -21.20258) (xy 386.643536 -21.097177) (xy 386.575553 -20.98738)
			(xy 386.514458 -20.873606) (xy 386.460483 -20.756287) (xy 386.413832 -20.635868) (xy 386.374683 -20.512805)
			(xy 386.343184 -20.387566) (xy 386.319455 -20.260625) (xy 386.303585 -20.132465) (xy 386.295635 -20.00357)
			(xy 380.00178 -20.00357) (xy 380.00178 -21.037296) (xy 380.006606 -21.04771) (xy 380.017913 -21.073078)
			(xy 380.033868 -21.126277) (xy 380.041924 -21.18123) (xy 380.04242 -21.209) (xy 380.041934 -21.236251)
			(xy 380.034178 -21.290199) (xy 380.018823 -21.342494) (xy 379.996181 -21.392071) (xy 379.966715 -21.437921)
			(xy 379.931024 -21.479112) (xy 379.889833 -21.514803) (xy 379.843983 -21.544269) (xy 379.794406 -21.566911)
			(xy 379.742111 -21.582266) (xy 379.688163 -21.590022) (xy 379.633661 -21.590022) (xy 379.579713 -21.582266)
			(xy 379.527418 -21.566911) (xy 379.477841 -21.544269) (xy 379.431991 -21.514803) (xy 379.3908 -21.479112)
			(xy 379.355109 -21.437921) (xy 379.325643 -21.392071) (xy 379.303001 -21.342494) (xy 379.287646 -21.290199)
			(xy 379.27989 -21.236251) (xy 379.279404 -21.209) (xy 379.279909 -21.181232) (xy 379.287987 -21.126285)
			(xy 379.303932 -21.073086) (xy 379.315218 -21.04771) (xy 379.320044 -21.037296) (xy 379.320044 -18.56867)
			(xy 379.316742 -18.555716) (xy 379.313186 -18.549874) (xy 379.303789 -18.532621) (xy 379.290417 -18.495685)
			(xy 379.283632 -18.456993) (xy 379.283214 -18.437352) (xy 379.283214 -18.169382) (xy 379.297692 -18.169382)
			(xy 379.309245 -18.167617) (xy 379.329061 -18.15528) (xy 379.341408 -18.13547) (xy 379.343158 -18.123916)
			(xy 379.343158 -17.645126) (xy 379.334014 -17.645126) (xy 379.32401 -17.644601) (xy 379.305524 -17.636951)
			(xy 379.291371 -17.62281) (xy 379.283707 -17.604329) (xy 379.283214 -17.594326) (xy 379.283214 -17.377156)
			(xy 379.283672 -17.357518) (xy 379.290463 -17.318833) (xy 379.303801 -17.28189) (xy 379.313186 -17.264634)
			(xy 379.316742 -17.258792) (xy 379.320044 -17.245838) (xy 379.320044 -17.063212) (xy 379.315218 -17.053052)
			(xy 379.303839 -17.027568) (xy 379.287776 -16.97412) (xy 379.279658 -16.918905) (xy 379.27915 -16.891)
			(xy 378.899674 -16.891) (xy 378.899185 -16.918905) (xy 378.891061 -16.974122) (xy 378.874987 -17.027568)
			(xy 378.863606 -17.053052) (xy 378.85878 -17.063212) (xy 378.85878 -17.245838) (xy 378.862082 -17.258792)
			(xy 378.865638 -17.264634) (xy 378.875032 -17.281889) (xy 378.888407 -17.318823) (xy 378.895192 -17.357515)
			(xy 378.89561 -17.377156) (xy 378.89561 -17.645126) (xy 378.881132 -17.645126) (xy 378.869581 -17.646901)
			(xy 378.849763 -17.659232) (xy 378.837415 -17.679039) (xy 378.835666 -17.690592) (xy 378.835666 -18.169382)
			(xy 378.84481 -18.169382) (xy 378.854816 -18.16988) (xy 378.873305 -18.177539) (xy 378.887456 -18.191689)
			(xy 378.895119 -18.210176) (xy 378.89561 -18.220182) (xy 378.89561 -18.437352) (xy 378.895165 -18.456991)
			(xy 378.88837 -18.495677) (xy 378.875026 -18.532619) (xy 378.865638 -18.549874) (xy 378.862082 -18.555716)
			(xy 378.85878 -18.56867) (xy 378.85878 -20.389088) (xy 378.858136 -20.419198) (xy 378.847531 -20.478477)
			(xy 378.837698 -20.506944) (xy 378.836174 -20.511516) (xy 378.831248 -20.537816) (xy 378.814948 -20.58878)
			(xy 378.791688 -20.636967) (xy 378.761924 -20.681431) (xy 378.726239 -20.721302) (xy 378.685335 -20.755796)
			(xy 378.640012 -20.784236) (xy 378.59116 -20.806066) (xy 378.539738 -20.820857) (xy 378.486754 -20.828319)
			(xy 378.46 -20.828762) (xy 378.432731 -20.828276) (xy 378.378747 -20.820514) (xy 378.326417 -20.805149)
			(xy 378.276807 -20.782492) (xy 378.230926 -20.753006) (xy 378.189709 -20.717291) (xy 378.153994 -20.676074)
			(xy 378.124508 -20.630193) (xy 378.101851 -20.580583) (xy 378.086486 -20.528253) (xy 378.078724 -20.474269)
			(xy 378.078238 -20.447) (xy 360.215434 -20.447) (xy 369.444524 -29.67609) (xy 369.445032 -29.676598)
			(xy 369.45241 -29.683189) (xy 369.470709 -29.690656) (xy 369.480592 -29.691076) (xy 384.20421 -29.691076)
			(xy 384.214087 -29.690617) (xy 384.232386 -29.683173) (xy 384.23977 -29.676598) (xy 384.959098 -28.95727)
			(xy 384.959606 -28.956762) (xy 384.966195 -28.949384) (xy 384.973658 -28.931084) (xy 384.974084 -28.921202)
			(xy 384.974084 -25.462992) (xy 384.974508 -25.452922) (xy 384.982223 -25.434318) (xy 384.98907 -25.426924)
			(xy 385.330446 -25.085548) (xy 385.33705 -25.07361) (xy 385.338828 -25.066752) (xy 385.340667 -25.059985)
			(xy 385.347502 -25.047746) (xy 385.35229 -25.042622) (xy 386.526786 -23.868126) (xy 386.534188 -23.86129)
			(xy 386.552786 -23.853583) (xy 386.562854 -23.85314) (xy 395.941296 -23.85314) (xy 395.951307 -23.852653)
			(xy 395.969807 -23.844996) (xy 395.983971 -23.830844) (xy 395.991645 -23.812351) (xy 395.992096 -23.80234)
			(xy 395.992096 -17.185132) (xy 395.991842 -17.1831) (xy 395.988866 -17.14189) (xy 395.985688 -17.059317)
			(xy 395.985492 -17.018) (xy 395.985699 -16.976683) (xy 395.988874 -16.894111) (xy 395.991842 -16.8529)
			(xy 395.992096 -16.850868) (xy 395.992096 -16.272764) (xy 395.992611 -16.208709) (xy 396.000996 -16.080873)
			(xy 396.017729 -15.95386) (xy 396.042737 -15.828214) (xy 396.075913 -15.704474) (xy 396.117115 -15.58317)
			(xy 396.166167 -15.464822) (xy 396.222858 -15.349937) (xy 396.286944 -15.239008) (xy 396.358153 -15.132511)
			(xy 396.436177 -15.030901) (xy 396.520683 -14.934615) (xy 396.565628 -14.888972) (xy 397.542512 -13.912088)
			(xy 397.588149 -13.867136) (xy 397.684433 -13.782626) (xy 397.786041 -13.704599) (xy 397.892538 -13.633389)
			(xy 398.003467 -13.569301) (xy 398.118352 -13.512611) (xy 398.236701 -13.46356) (xy 398.358007 -13.422361)
			(xy 398.481749 -13.389189) (xy 398.607397 -13.364186) (xy 398.734411 -13.34746) (xy 398.862248 -13.339082)
			(xy 398.926304 -13.338556) (xy 402.41347 -13.338556) (xy 402.477525 -13.339072) (xy 402.60536 -13.347459)
			(xy 402.732372 -13.364194) (xy 402.858017 -13.389203) (xy 402.981757 -13.422381) (xy 403.10306 -13.463584)
			(xy 403.221407 -13.512636) (xy 403.336291 -13.569327) (xy 403.447219 -13.633414) (xy 403.553715 -13.704622)
			(xy 403.655324 -13.782647) (xy 403.75161 -13.867152) (xy 403.797262 -13.912088) (xy 404.169118 -14.283944)
			(xy 404.214075 -14.329581) (xy 404.298597 -14.425863) (xy 404.376639 -14.52747) (xy 404.447866 -14.633964)
			(xy 404.511972 -14.744891) (xy 404.568684 -14.859774) (xy 404.617757 -14.978122) (xy 404.658983 -15.099426)
			(xy 404.692183 -15.223168) (xy 404.717217 -15.348817) (xy 404.733975 -15.475835) (xy 404.742388 -15.603677)
			(xy 404.742904 -15.667736) (xy 404.742904 -23.518622) (xy 404.743365 -23.528499) (xy 404.75081 -23.546796)
			(xy 404.757382 -23.554182) (xy 405.013414 -23.810214) (xy 405.013922 -23.810722) (xy 405.0213 -23.817312)
			(xy 405.039599 -23.824779) (xy 405.049482 -23.8252) (xy 409.172918 -23.8252) (xy 409.182795 -23.82474)
			(xy 409.201094 -23.817297) (xy 409.208478 -23.810722) (xy 411.744414 -21.274786) (xy 411.751809 -21.267932)
			(xy 411.770408 -21.26019) (xy 411.780482 -21.2598) (xy 413.973518 -21.2598) (xy 413.983395 -21.25934)
			(xy 414.001694 -21.251897) (xy 414.009078 -21.245322) (xy 414.132014 -21.122386) (xy 414.132522 -21.121878)
			(xy 414.139112 -21.1145) (xy 414.146579 -21.096201) (xy 414.147 -21.086318) (xy 414.147 -16.861282)
			(xy 414.147427 -16.851213) (xy 414.155146 -16.832614) (xy 414.161986 -16.825214) (xy 414.995614 -15.991586)
			(xy 415.003009 -15.984732) (xy 415.021608 -15.97699) (xy 415.031682 -15.9766) (xy 419.917118 -15.9766)
			(xy 419.927187 -15.977027) (xy 419.945786 -15.984746) (xy 419.953186 -15.991586) (xy 421.828214 -17.866614)
			(xy 421.835068 -17.874009) (xy 421.84281 -17.892608) (xy 421.8432 -17.902682) (xy 421.8432 -23.423118)
			(xy 421.84366 -23.432995) (xy 421.851103 -23.451294) (xy 421.857678 -23.458678) (xy 423.987214 -25.588214)
			(xy 423.987722 -25.588722) (xy 423.9951 -25.595312) (xy 424.013399 -25.602779) (xy 424.023282 -25.6032)
			(xy 425.962318 -25.6032) (xy 425.972195 -25.60274) (xy 425.990494 -25.595297) (xy 425.997878 -25.588722)
			(xy 426.247814 -25.338786) (xy 426.248322 -25.338278) (xy 426.254912 -25.3309) (xy 426.262379 -25.312601)
			(xy 426.2628 -25.302718) (xy 426.2628 -21.433282) (xy 426.263227 -21.423213) (xy 426.270946 -21.404614)
			(xy 426.277786 -21.397214) (xy 428.737014 -18.937986) (xy 428.744409 -18.931132) (xy 428.763008 -18.92339)
			(xy 428.773082 -18.923) (xy 431.804318 -18.923) (xy 431.814387 -18.923427) (xy 431.832986 -18.931146)
			(xy 431.840386 -18.937986) (xy 432.953414 -20.051014) (xy 432.960268 -20.058409) (xy 432.96801 -20.077008)
			(xy 432.9684 -20.087082) (xy 432.9684 -22.8092) (xy 432.968888 -22.819208) (xy 432.976548 -22.837699)
			(xy 432.990701 -22.851852) (xy 433.009192 -22.859512) (xy 433.0192 -22.86) (xy 433.709318 -22.86)
			(xy 433.719195 -22.85954) (xy 433.737494 -22.852097) (xy 433.744878 -22.845522) (xy 434.401214 -22.188932)
			(xy 434.401722 -22.188424) (xy 434.408304 -22.181043) (xy 434.415751 -22.162744) (xy 434.4162 -22.152864)
			(xy 434.4162 -21.255482) (xy 434.416627 -21.245413) (xy 434.424346 -21.226814) (xy 434.431186 -21.219414)
			(xy 434.680614 -20.969986) (xy 434.688009 -20.963132) (xy 434.706608 -20.95539) (xy 434.716682 -20.955)
			(xy 437.519318 -20.955) (xy 437.529387 -20.955427) (xy 437.547986 -20.963146) (xy 437.555386 -20.969986)
			(xy 438.414414 -21.829014) (xy 438.421268 -21.836409) (xy 438.42901 -21.855008) (xy 438.4294 -21.865082)
			(xy 438.4294 -26.648918) (xy 438.42986 -26.658795) (xy 438.437303 -26.677094) (xy 438.443878 -26.684478)
			(xy 438.541414 -26.782014) (xy 438.541922 -26.782522) (xy 438.5493 -26.789112) (xy 438.567599 -26.796579)
			(xy 438.577482 -26.797) (xy 441.583318 -26.797) (xy 441.593195 -26.79654) (xy 441.611494 -26.789097)
			(xy 441.618878 -26.782522) (xy 443.303914 -25.097486) (xy 443.311309 -25.090632) (xy 443.329908 -25.08289)
			(xy 443.339982 -25.0825) (xy 450.223382 -25.0825) (xy 450.233446 -25.082938) (xy 450.252028 -25.090674)
			(xy 450.25945 -25.097486) (xy 450.431916 -25.269952) (xy 450.447918 -25.277572) (xy 450.456808 -25.278334)
			(xy 450.508087 -25.283768) (xy 450.609607 -25.301897) (xy 450.709324 -25.328197) (xy 450.806581 -25.362495)
			(xy 450.900736 -25.404564) (xy 450.991171 -25.454128) (xy 451.07729 -25.510861) (xy 451.158527 -25.574389)
			(xy 451.234345 -25.644294) (xy 451.304247 -25.720115) (xy 451.367771 -25.801354) (xy 451.4245 -25.887475)
			(xy 451.47406 -25.977913) (xy 451.516126 -26.07207) (xy 451.550419 -26.169328) (xy 451.576714 -26.269046)
			(xy 451.594839 -26.370567) (xy 451.600316 -26.421842) (xy 451.601078 -26.430732) (xy 451.608698 -26.446734)
			(xy 451.943978 -26.782014) (xy 451.950825 -26.789412) (xy 451.958557 -26.80801) (xy 451.958964 -26.818082)
			(xy 451.958964 -43.378882) (xy 451.959435 -43.388755) (xy 451.96689 -43.40704) (xy 451.973442 -43.414442)
			(xy 455.407014 -46.848014) (xy 455.413868 -46.855409) (xy 455.42161 -46.874008) (xy 455.422 -46.884082)
			(xy 455.422 -47.625) (xy 456.843382 -47.625) (xy 456.847453 -47.569378) (xy 456.859579 -47.514941)
			(xy 456.879502 -47.46285) (xy 456.906798 -47.414215) (xy 456.940884 -47.370072) (xy 456.981033 -47.331363)
			(xy 457.026391 -47.298912) (xy 457.075991 -47.273411) (xy 457.128775 -47.255404) (xy 457.183618 -47.245274)
			(xy 457.239352 -47.243237) (xy 457.246286 -47.244) (xy 459.738728 -47.244) (xy 459.742801 -47.188341)
			(xy 459.754936 -47.133868) (xy 459.774872 -47.081742) (xy 459.802186 -47.033074) (xy 459.836294 -46.988902)
			(xy 459.876471 -46.950167) (xy 459.921859 -46.917695) (xy 459.971491 -46.892177) (xy 460.024311 -46.874158)
			(xy 460.07919 -46.864021) (xy 460.134961 -46.861983) (xy 460.190435 -46.868086) (xy 460.244428 -46.882202)
			(xy 460.295791 -46.904029) (xy 460.343429 -46.933102) (xy 460.386325 -46.968801) (xy 460.423567 -47.010365)
			(xy 460.454361 -47.056909) (xy 460.478049 -47.10744) (xy 460.494127 -47.160882) (xy 460.502253 -47.216096)
			(xy 460.502762 -47.244) (xy 460.502253 -47.271904) (xy 460.494127 -47.327118) (xy 460.478049 -47.38056)
			(xy 460.454361 -47.431091) (xy 460.423567 -47.477635) (xy 460.386325 -47.519199) (xy 460.343429 -47.554898)
			(xy 460.295791 -47.583971) (xy 460.244428 -47.605798) (xy 460.190435 -47.619914) (xy 460.134961 -47.626017)
			(xy 460.07919 -47.623979) (xy 460.024311 -47.613842) (xy 459.971491 -47.595823) (xy 459.921859 -47.570305)
			(xy 459.876471 -47.537833) (xy 459.836294 -47.499098) (xy 459.802186 -47.454926) (xy 459.774872 -47.406258)
			(xy 459.754936 -47.354132) (xy 459.742801 -47.299659) (xy 459.738728 -47.244) (xy 457.246286 -47.244)
			(xy 457.294789 -47.249337) (xy 457.348746 -47.263443) (xy 457.400075 -47.285255) (xy 457.447681 -47.314309)
			(xy 457.490549 -47.349984) (xy 457.527766 -47.391521) (xy 457.558539 -47.438034) (xy 457.582211 -47.488531)
			(xy 457.598279 -47.541938) (xy 457.606399 -47.597114) (xy 457.606908 -47.625) (xy 457.606399 -47.652886)
			(xy 457.598279 -47.708062) (xy 457.58506 -47.752) (xy 461.262982 -47.752) (xy 461.267053 -47.696378)
			(xy 461.279179 -47.641941) (xy 461.299102 -47.58985) (xy 461.326398 -47.541215) (xy 461.360484 -47.497072)
			(xy 461.400633 -47.458363) (xy 461.445991 -47.425912) (xy 461.495591 -47.400411) (xy 461.548375 -47.382404)
			(xy 461.603218 -47.372274) (xy 461.658952 -47.370237) (xy 461.714389 -47.376337) (xy 461.768346 -47.390443)
			(xy 461.819675 -47.412255) (xy 461.867281 -47.441309) (xy 461.910149 -47.476984) (xy 461.947366 -47.518521)
			(xy 461.978139 -47.565034) (xy 462.001811 -47.615531) (xy 462.017879 -47.668938) (xy 462.025999 -47.724114)
			(xy 462.026508 -47.752) (xy 462.025999 -47.779886) (xy 462.017879 -47.835062) (xy 462.001811 -47.888469)
			(xy 461.978139 -47.938966) (xy 461.947366 -47.985479) (xy 461.910149 -48.027016) (xy 461.867281 -48.062691)
			(xy 461.819675 -48.091745) (xy 461.768346 -48.113557) (xy 461.714389 -48.127663) (xy 461.658952 -48.133763)
			(xy 461.603218 -48.131726) (xy 461.548375 -48.121596) (xy 461.495591 -48.103589) (xy 461.445991 -48.078088)
			(xy 461.400633 -48.045637) (xy 461.360484 -48.006928) (xy 461.326398 -47.962785) (xy 461.299102 -47.91415)
			(xy 461.279179 -47.862059) (xy 461.267053 -47.807622) (xy 461.262982 -47.752) (xy 457.58506 -47.752)
			(xy 457.582211 -47.761469) (xy 457.558539 -47.811966) (xy 457.527766 -47.858479) (xy 457.490549 -47.900016)
			(xy 457.447681 -47.935691) (xy 457.400075 -47.964745) (xy 457.348746 -47.986557) (xy 457.294789 -48.000663)
			(xy 457.239352 -48.006763) (xy 457.183618 -48.004726) (xy 457.128775 -47.994596) (xy 457.075991 -47.976589)
			(xy 457.026391 -47.951088) (xy 456.981033 -47.918637) (xy 456.940884 -47.879928) (xy 456.906798 -47.835785)
			(xy 456.879502 -47.78715) (xy 456.859579 -47.735059) (xy 456.847453 -47.680622) (xy 456.843382 -47.625)
			(xy 455.422 -47.625) (xy 455.422 -49.561961) (xy 459.130394 -49.561961) (xy 459.130394 -49.498039)
			(xy 459.138405 -49.434621) (xy 459.154302 -49.372707) (xy 459.177834 -49.313274) (xy 459.208628 -49.257259)
			(xy 459.246201 -49.205544) (xy 459.289958 -49.158947) (xy 459.339211 -49.118202) (xy 459.393182 -49.083951)
			(xy 459.451021 -49.056734) (xy 459.511814 -49.036981) (xy 459.574604 -49.025003) (xy 459.6384 -49.02099)
			(xy 459.702196 -49.025003) (xy 459.764986 -49.036981) (xy 459.825779 -49.056734) (xy 459.883618 -49.083951)
			(xy 459.937589 -49.118202) (xy 459.986842 -49.158947) (xy 460.030599 -49.205544) (xy 460.068172 -49.257259)
			(xy 460.098966 -49.313274) (xy 460.122498 -49.372707) (xy 460.138395 -49.434621) (xy 460.146406 -49.498039)
			(xy 460.146908 -49.53) (xy 460.146406 -49.561961) (xy 460.138395 -49.625379) (xy 460.122498 -49.687293)
			(xy 460.098966 -49.746726) (xy 460.068172 -49.802741) (xy 460.030599 -49.854456) (xy 459.986842 -49.901053)
			(xy 459.937589 -49.941798) (xy 459.883618 -49.976049) (xy 459.825779 -50.003266) (xy 459.764986 -50.023019)
			(xy 459.702196 -50.034997) (xy 459.6384 -50.039011) (xy 459.574604 -50.034997) (xy 459.511814 -50.023019)
			(xy 459.451021 -50.003266) (xy 459.393182 -49.976049) (xy 459.339211 -49.941798) (xy 459.289958 -49.901053)
			(xy 459.246201 -49.854456) (xy 459.208628 -49.802741) (xy 459.177834 -49.746726) (xy 459.154302 -49.687293)
			(xy 459.138405 -49.625379) (xy 459.130394 -49.561961) (xy 455.422 -49.561961) (xy 455.422 -53.191918)
			(xy 455.421573 -53.201987) (xy 455.413854 -53.220586) (xy 455.407014 -53.227986) (xy 454.700386 -53.934614)
			(xy 454.692991 -53.941468) (xy 454.674392 -53.94921) (xy 454.664318 -53.9496) (xy 421.69461 -53.9496)
			(xy 421.684539 -53.950021) (xy 421.665932 -53.957733) (xy 421.658542 -53.964586) (xy 421.656764 -53.966364)
			(xy 421.622985 -53.999497) (xy 421.551168 -54.061116) (xy 421.474883 -54.11711) (xy 421.39457 -54.167155)
			(xy 421.310693 -54.210963) (xy 421.267382 -54.230016) (xy 421.263022 -54.231999) (xy 421.255095 -54.237373)
			(xy 421.251634 -54.240684) (xy 419.499947 -55.992371) (xy 468.668437 -55.992371) (xy 468.67219 -55.880397)
			(xy 468.677498 -55.824628) (xy 468.679784 -55.810658) (xy 468.679784 -55.809388) (xy 468.686718 -55.753065)
			(xy 468.707507 -55.641495) (xy 468.736148 -55.531677) (xy 468.772495 -55.424164) (xy 468.816367 -55.319496)
			(xy 468.867542 -55.218199) (xy 468.925765 -55.12078) (xy 468.990742 -55.027731) (xy 469.062147 -54.939519)
			(xy 469.139621 -54.856585) (xy 469.222776 -54.779349) (xy 469.311192 -54.708196) (xy 469.404427 -54.643485)
			(xy 469.502011 -54.585541) (xy 469.603454 -54.534655) (xy 469.708247 -54.491083) (xy 469.815864 -54.455043)
			(xy 469.925763 -54.426716) (xy 470.037392 -54.406246) (xy 470.150191 -54.393734) (xy 470.263593 -54.389244)
			(xy 470.377028 -54.392798) (xy 470.489927 -54.404379) (xy 470.601721 -54.423927) (xy 470.71185 -54.451346)
			(xy 470.819761 -54.486496) (xy 470.92491 -54.529202) (xy 471.02677 -54.579249) (xy 471.124829 -54.636386)
			(xy 471.218594 -54.700325) (xy 471.307595 -54.770746) (xy 471.391383 -54.847294) (xy 471.469539 -54.929585)
			(xy 471.54167 -55.017206) (xy 471.607413 -55.109715) (xy 471.666437 -55.20665) (xy 471.718447 -55.307521)
			(xy 471.763181 -55.411824) (xy 471.800415 -55.519033) (xy 471.82996 -55.628611) (xy 471.85167 -55.740006)
			(xy 471.865434 -55.852659) (xy 471.871184 -55.966004) (xy 471.870532 -56.022748) (xy 471.870532 -56.031638)
			(xy 471.870532 -56.0324) (xy 471.86854 -56.088385) (xy 471.85775 -56.199902) (xy 471.83919 -56.310391)
			(xy 471.812951 -56.419313) (xy 471.779162 -56.526133) (xy 471.737987 -56.63033) (xy 471.689628 -56.731393)
			(xy 471.634322 -56.828828) (xy 471.57234 -56.922158) (xy 471.503984 -57.010927) (xy 471.42959 -57.094699)
			(xy 471.349521 -57.173065) (xy 471.264169 -57.245642) (xy 471.173951 -57.312074) (xy 471.079311 -57.372036)
			(xy 470.980709 -57.425235) (xy 470.87863 -57.471411) (xy 470.773572 -57.510337) (xy 470.66605 -57.541822)
			(xy 470.55659 -57.565714) (xy 470.445727 -57.581895) (xy 470.334005 -57.590285) (xy 470.221969 -57.590844)
			(xy 470.110168 -57.583569) (xy 469.99915 -57.568496) (xy 469.889456 -57.545698) (xy 469.781625 -57.515287)
			(xy 469.676184 -57.477411) (xy 469.573649 -57.432257) (xy 469.474522 -57.380044) (xy 469.379288 -57.32103)
			(xy 469.288412 -57.255501) (xy 469.20234 -57.18378) (xy 469.121493 -57.106217) (xy 469.046266 -57.023191)
			(xy 468.977028 -56.935109) (xy 468.914117 -56.842402) (xy 468.857841 -56.745524) (xy 468.808476 -56.644948)
			(xy 468.766264 -56.541168) (xy 468.73141 -56.43469) (xy 468.704085 -56.326036) (xy 468.684424 -56.215737)
			(xy 468.672522 -56.104334) (xy 468.668437 -55.992371) (xy 419.499947 -55.992371) (xy 418.352986 -57.139332)
			(xy 418.34562 -57.146444) (xy 418.338 -57.16524) (xy 418.338 -60.099956) (xy 422.484046 -60.099956)
			(xy 422.488076 -59.957621) (xy 422.500151 -59.815741) (xy 422.520234 -59.674773) (xy 422.548261 -59.535166)
			(xy 422.584141 -59.397368) (xy 422.627759 -59.261821) (xy 422.678976 -59.128959) (xy 422.737627 -58.999207)
			(xy 422.803525 -58.872981) (xy 422.876459 -58.750685) (xy 422.956196 -58.632712) (xy 423.042478 -58.519439)
			(xy 423.135031 -58.411228) (xy 423.233558 -58.308427) (xy 423.337743 -58.211365) (xy 423.447252 -58.120353)
			(xy 423.561735 -58.035681) (xy 423.680825 -57.957623) (xy 423.80414 -57.886427) (xy 423.931286 -57.822321)
			(xy 424.061855 -57.765512) (xy 424.195429 -57.71618) (xy 424.33158 -57.674484) (xy 424.469871 -57.640558)
			(xy 424.609861 -57.61451) (xy 424.7511 -57.596424) (xy 424.893136 -57.586357) (xy 425.035514 -57.584342)
			(xy 425.177778 -57.590385) (xy 425.319472 -57.604467) (xy 425.460142 -57.626543) (xy 425.599339 -57.656543)
			(xy 425.736615 -57.694369) (xy 425.871531 -57.739901) (xy 426.003655 -57.792992) (xy 426.132564 -57.853474)
			(xy 426.257845 -57.921152) (xy 426.379096 -57.995809) (xy 426.495929 -58.077207) (xy 426.60797 -58.165084)
			(xy 426.71486 -58.259159) (xy 426.816257 -58.359131) (xy 426.911835 -58.464679) (xy 427.001289 -58.575465)
			(xy 427.084331 -58.691134) (xy 427.160697 -58.811317) (xy 427.230141 -58.935627) (xy 427.292441 -59.063668)
			(xy 427.347397 -59.195027) (xy 427.394834 -59.329286) (xy 427.434598 -59.466013) (xy 427.466564 -59.604771)
			(xy 427.490629 -59.745115) (xy 427.506715 -59.886596) (xy 427.51477 -60.02876) (xy 427.515274 -60.099956)
			(xy 427.51477 -60.171152) (xy 427.506715 -60.313316) (xy 427.490629 -60.454797) (xy 427.466564 -60.595141)
			(xy 427.434598 -60.733899) (xy 427.394834 -60.870626) (xy 427.347397 -61.004885) (xy 427.292441 -61.136244)
			(xy 427.230141 -61.264285) (xy 427.160697 -61.388595) (xy 427.084331 -61.508778) (xy 427.001289 -61.624447)
			(xy 426.911835 -61.735233) (xy 426.816257 -61.840781) (xy 426.71486 -61.940753) (xy 426.60797 -62.034828)
			(xy 426.495929 -62.122705) (xy 426.379096 -62.204103) (xy 426.257845 -62.27876) (xy 426.132564 -62.346438)
			(xy 426.003655 -62.40692) (xy 425.871531 -62.460011) (xy 425.736615 -62.505543) (xy 425.599339 -62.543369)
			(xy 425.460142 -62.573369) (xy 425.319472 -62.595445) (xy 425.177778 -62.609527) (xy 425.035514 -62.61557)
			(xy 424.893136 -62.613555) (xy 424.7511 -62.603488) (xy 424.609861 -62.585402) (xy 424.469871 -62.559354)
			(xy 424.33158 -62.525428) (xy 424.195429 -62.483732) (xy 424.061855 -62.4344) (xy 423.931286 -62.377591)
			(xy 423.80414 -62.313485) (xy 423.680825 -62.242289) (xy 423.561735 -62.164231) (xy 423.447252 -62.079559)
			(xy 423.337743 -61.988547) (xy 423.233558 -61.891485) (xy 423.135031 -61.788684) (xy 423.042478 -61.680473)
			(xy 422.956196 -61.5672) (xy 422.876459 -61.449227) (xy 422.803525 -61.326931) (xy 422.737627 -61.200705)
			(xy 422.678976 -61.070953) (xy 422.627759 -60.938091) (xy 422.584141 -60.802544) (xy 422.548261 -60.664746)
			(xy 422.520234 -60.525139) (xy 422.500151 -60.384171) (xy 422.488076 -60.242291) (xy 422.484046 -60.099956)
			(xy 418.338 -60.099956) (xy 418.338 -63.707518) (xy 437.3626 -63.707518) (xy 437.3626 -62.403482)
			(xy 437.36299 -62.393408) (xy 437.370732 -62.374809) (xy 437.377586 -62.367414) (xy 438.051194 -61.693806)
			(xy 438.058603 -61.686977) (xy 438.077195 -61.679251) (xy 438.087262 -61.67882) (xy 440.287918 -61.67882)
			(xy 440.297989 -61.679231) (xy 440.316587 -61.686961) (xy 440.323986 -61.693806) (xy 440.591194 -61.961014)
			(xy 440.598601 -61.967846) (xy 440.617195 -61.97557) (xy 440.627262 -61.976) (xy 453.394318 -61.976)
			(xy 453.404392 -61.97639) (xy 453.422991 -61.984132) (xy 453.430386 -61.990986) (xy 453.527414 -62.088014)
			(xy 453.534526 -62.09538) (xy 453.553322 -62.103) (xy 456.715622 -62.103) (xy 456.724766 -62.110366)
			(xy 457.236322 -62.621922) (xy 457.243167 -62.629318) (xy 457.250884 -62.64792) (xy 457.251308 -62.65799)
			(xy 457.251308 -86.89213) (xy 457.250922 -86.902204) (xy 457.243176 -86.920803) (xy 457.236322 -86.928198)
			(xy 452.866506 -91.298014) (xy 452.859099 -91.304846) (xy 452.840505 -91.31257) (xy 452.830438 -91.313)
			(xy 449.870322 -91.313) (xy 449.851526 -91.32062) (xy 449.844414 -91.327986) (xy 449.747386 -91.425014)
			(xy 449.740546 -91.432414) (xy 449.732827 -91.451013) (xy 449.7324 -91.461082) (xy 449.7324 -91.549982)
			(xy 470.018627 -91.549982) (xy 470.022616 -91.437017) (xy 470.034564 -91.324614) (xy 470.054411 -91.213334)
			(xy 470.082057 -91.103732) (xy 470.117367 -90.996352) (xy 470.160162 -90.891731) (xy 470.210231 -90.790389)
			(xy 470.267324 -90.692831) (xy 470.331157 -90.599544) (xy 470.40141 -90.510991) (xy 470.477735 -90.427615)
			(xy 470.559751 -90.349831) (xy 470.64705 -90.278025) (xy 470.739196 -90.212556) (xy 470.835731 -90.153751)
			(xy 470.936174 -90.101901) (xy 471.040024 -90.057266) (xy 471.146763 -90.020067) (xy 471.255861 -89.99049)
			(xy 471.366773 -89.968682) (xy 471.478947 -89.954753) (xy 471.591825 -89.94877) (xy 471.704843 -89.950765)
			(xy 471.817439 -89.960727) (xy 471.929052 -89.978607) (xy 472.039125 -90.004315) (xy 472.147111 -90.037724)
			(xy 472.252471 -90.078667) (xy 472.354681 -90.126939) (xy 472.453231 -90.182302) (xy 472.547631 -90.244477)
			(xy 472.637409 -90.313157) (xy 472.722119 -90.387999) (xy 472.801339 -90.46863) (xy 472.874674 -90.554647)
			(xy 472.941759 -90.645624) (xy 473.002259 -90.741106) (xy 473.055873 -90.840618) (xy 473.102335 -90.943664)
			(xy 473.141412 -91.04973) (xy 473.172909 -91.158289) (xy 473.196671 -91.268799) (xy 473.212578 -91.38071)
			(xy 473.220551 -91.493464) (xy 473.22105 -91.549982) (xy 473.220551 -91.6065) (xy 473.212578 -91.719254)
			(xy 473.196671 -91.831165) (xy 473.172909 -91.941675) (xy 473.141412 -92.050234) (xy 473.102335 -92.1563)
			(xy 473.055873 -92.259346) (xy 473.002259 -92.358858) (xy 472.941759 -92.45434) (xy 472.874674 -92.545317)
			(xy 472.801339 -92.631334) (xy 472.722119 -92.711965) (xy 472.637409 -92.786807) (xy 472.547631 -92.855487)
			(xy 472.453231 -92.917662) (xy 472.354681 -92.973025) (xy 472.252471 -93.021297) (xy 472.147111 -93.06224)
			(xy 472.039125 -93.095649) (xy 471.929052 -93.121357) (xy 471.817439 -93.139237) (xy 471.704843 -93.149199)
			(xy 471.591825 -93.151194) (xy 471.478947 -93.145211) (xy 471.366773 -93.131282) (xy 471.255861 -93.109474)
			(xy 471.146763 -93.079897) (xy 471.040024 -93.042698) (xy 470.936174 -92.998063) (xy 470.835731 -92.946213)
			(xy 470.739196 -92.887408) (xy 470.64705 -92.821939) (xy 470.559751 -92.750133) (xy 470.477735 -92.672349)
			(xy 470.40141 -92.588973) (xy 470.331157 -92.50042) (xy 470.267324 -92.407133) (xy 470.210231 -92.309575)
			(xy 470.160162 -92.208233) (xy 470.117367 -92.103612) (xy 470.082057 -91.996232) (xy 470.054411 -91.88663)
			(xy 470.034564 -91.77535) (xy 470.022616 -91.662947) (xy 470.018627 -91.549982) (xy 449.7324 -91.549982)
			(xy 449.7324 -96.494092) (xy 449.732803 -96.504164) (xy 449.740536 -96.522764) (xy 449.747386 -96.53016)
			(xy 450.051424 -96.834198) (xy 450.058536 -96.841564) (xy 450.077332 -96.849184) (xy 454.217278 -96.849184)
			(xy 454.227349 -96.849598) (xy 454.245948 -96.857324) (xy 454.253346 -96.86417) (xy 455.010012 -97.620836)
			(xy 455.016862 -97.628228) (xy 455.024575 -97.646834) (xy 455.024998 -97.656904) (xy 455.024998 -103.857806)
			(xy 455.024603 -103.867879) (xy 455.016864 -103.886478) (xy 455.010012 -103.893874) (xy 454.270872 -104.633014)
			(xy 454.263477 -104.639861) (xy 454.244874 -104.647576) (xy 454.234804 -104.648) (xy 452.268082 -104.648)
			(xy 452.258008 -104.64839) (xy 452.239409 -104.656132) (xy 452.232014 -104.662986) (xy 449.848986 -107.046014)
			(xy 449.841586 -107.052854) (xy 449.822987 -107.060573) (xy 449.812918 -107.061) (xy 443.759082 -107.061)
			(xy 443.749008 -107.06061) (xy 443.730409 -107.052868) (xy 443.723014 -107.046014) (xy 443.016386 -106.339386)
			(xy 443.009546 -106.331986) (xy 443.001827 -106.313387) (xy 443.0014 -106.303318) (xy 443.0014 -97.658682)
			(xy 443.00179 -97.648608) (xy 443.009532 -97.630009) (xy 443.016386 -97.622614) (xy 445.272414 -95.366586)
			(xy 445.279254 -95.359186) (xy 445.286973 -95.340587) (xy 445.2874 -95.330518) (xy 445.2874 -84.095082)
			(xy 445.28701 -84.085008) (xy 445.279268 -84.066409) (xy 445.272414 -84.059014) (xy 445.201294 -83.987894)
			(xy 445.194182 -83.980528) (xy 445.175386 -83.972908) (xy 443.17539 -83.972908) (xy 443.165317 -83.972512)
			(xy 443.146718 -83.964773) (xy 443.139322 -83.957922) (xy 442.762386 -83.580986) (xy 442.755546 -83.573586)
			(xy 442.747827 -83.554987) (xy 442.7474 -83.544918) (xy 442.7474 -73.300082) (xy 442.74701 -73.290008)
			(xy 442.739268 -73.271409) (xy 442.732414 -73.264014) (xy 442.127386 -72.658986) (xy 442.120274 -72.65162)
			(xy 442.101478 -72.644) (xy 439.339482 -72.644) (xy 439.329408 -72.64361) (xy 439.310809 -72.635868)
			(xy 439.303414 -72.629014) (xy 438.444386 -71.769986) (xy 438.437546 -71.762586) (xy 438.429827 -71.743987)
			(xy 438.4294 -71.733918) (xy 438.4294 -64.816482) (xy 438.42901 -64.806408) (xy 438.421268 -64.787809)
			(xy 438.414414 -64.780414) (xy 437.377586 -63.743586) (xy 437.370746 -63.736186) (xy 437.363027 -63.717587)
			(xy 437.3626 -63.707518) (xy 418.338 -63.707518) (xy 418.338 -104.549956) (xy 422.484046 -104.549956)
			(xy 422.488076 -104.407621) (xy 422.500151 -104.265741) (xy 422.520234 -104.124773) (xy 422.548261 -103.985166)
			(xy 422.584141 -103.847368) (xy 422.627759 -103.711821) (xy 422.678976 -103.578959) (xy 422.737627 -103.449207)
			(xy 422.803525 -103.322981) (xy 422.876459 -103.200685) (xy 422.956196 -103.082712) (xy 423.042478 -102.969439)
			(xy 423.135031 -102.861228) (xy 423.233558 -102.758427) (xy 423.337743 -102.661365) (xy 423.447252 -102.570353)
			(xy 423.561735 -102.485681) (xy 423.680825 -102.407623) (xy 423.80414 -102.336427) (xy 423.931286 -102.272321)
			(xy 424.061855 -102.215512) (xy 424.195429 -102.16618) (xy 424.33158 -102.124484) (xy 424.469871 -102.090558)
			(xy 424.609861 -102.06451) (xy 424.7511 -102.046424) (xy 424.893136 -102.036357) (xy 425.035514 -102.034342)
			(xy 425.177778 -102.040385) (xy 425.319472 -102.054467) (xy 425.460142 -102.076543) (xy 425.599339 -102.106543)
			(xy 425.736615 -102.144369) (xy 425.871531 -102.189901) (xy 426.003655 -102.242992) (xy 426.132564 -102.303474)
			(xy 426.257845 -102.371152) (xy 426.379096 -102.445809) (xy 426.495929 -102.527207) (xy 426.60797 -102.615084)
			(xy 426.71486 -102.709159) (xy 426.816257 -102.809131) (xy 426.911835 -102.914679) (xy 427.001289 -103.025465)
			(xy 427.084331 -103.141134) (xy 427.160697 -103.261317) (xy 427.230141 -103.385627) (xy 427.292441 -103.513668)
			(xy 427.347397 -103.645027) (xy 427.394834 -103.779286) (xy 427.434598 -103.916013) (xy 427.466564 -104.054771)
			(xy 427.490629 -104.195115) (xy 427.506715 -104.336596) (xy 427.51477 -104.47876) (xy 427.515274 -104.549956)
			(xy 427.51477 -104.621152) (xy 427.506715 -104.763316) (xy 427.490629 -104.904797) (xy 427.466564 -105.045141)
			(xy 427.434598 -105.183899) (xy 427.394834 -105.320626) (xy 427.347397 -105.454885) (xy 427.292441 -105.586244)
			(xy 427.230141 -105.714285) (xy 427.160697 -105.838595) (xy 427.084331 -105.958778) (xy 427.001289 -106.074447)
			(xy 426.911835 -106.185233) (xy 426.816257 -106.290781) (xy 426.71486 -106.390753) (xy 426.60797 -106.484828)
			(xy 426.495929 -106.572705) (xy 426.379096 -106.654103) (xy 426.257845 -106.72876) (xy 426.132564 -106.796438)
			(xy 426.003655 -106.85692) (xy 425.871531 -106.910011) (xy 425.736615 -106.955543) (xy 425.599339 -106.993369)
			(xy 425.460142 -107.023369) (xy 425.319472 -107.045445) (xy 425.177778 -107.059527) (xy 425.035514 -107.06557)
			(xy 424.893136 -107.063555) (xy 424.7511 -107.053488) (xy 424.609861 -107.035402) (xy 424.469871 -107.009354)
			(xy 424.33158 -106.975428) (xy 424.195429 -106.933732) (xy 424.061855 -106.8844) (xy 423.931286 -106.827591)
			(xy 423.80414 -106.763485) (xy 423.680825 -106.692289) (xy 423.561735 -106.614231) (xy 423.447252 -106.529559)
			(xy 423.337743 -106.438547) (xy 423.233558 -106.341485) (xy 423.135031 -106.238684) (xy 423.042478 -106.130473)
			(xy 422.956196 -106.0172) (xy 422.876459 -105.899227) (xy 422.803525 -105.776931) (xy 422.737627 -105.650705)
			(xy 422.678976 -105.520953) (xy 422.627759 -105.388091) (xy 422.584141 -105.252544) (xy 422.548261 -105.114746)
			(xy 422.520234 -104.975139) (xy 422.500151 -104.834171) (xy 422.488076 -104.692291) (xy 422.484046 -104.549956)
			(xy 418.338 -104.549956) (xy 418.338 -108.772452) (xy 466.257894 -108.772452) (xy 466.258404 -108.744547)
			(xy 466.26652 -108.689332) (xy 466.282586 -108.635885) (xy 466.293962 -108.6104) (xy 466.298788 -108.599986)
			(xy 466.298788 -108.166916) (xy 466.295486 -108.154216) (xy 466.29193 -108.148374) (xy 466.282514 -108.131085)
			(xy 466.269156 -108.094056) (xy 466.262376 -108.05528) (xy 466.261958 -108.035598) (xy 466.261958 -107.76458)
			(xy 466.278468 -107.76458) (xy 466.289582 -107.762385) (xy 466.308464 -107.749923) (xy 466.320168 -107.730563)
			(xy 466.321902 -107.719368) (xy 466.321902 -107.291378) (xy 466.321482 -107.281495) (xy 466.314015 -107.263196)
			(xy 466.307424 -107.255818) (xy 466.306916 -107.25531) (xy 466.277198 -107.225592) (xy 466.270308 -107.218205)
			(xy 466.262448 -107.199613) (xy 466.261958 -107.189524) (xy 466.261958 -106.969306) (xy 466.262393 -106.949625)
			(xy 466.269164 -106.910849) (xy 466.282522 -106.873822) (xy 466.29193 -106.85653) (xy 466.295486 -106.850688)
			(xy 466.298788 -106.837988) (xy 466.298788 -106.658918) (xy 466.293962 -106.648504) (xy 466.282602 -106.623012)
			(xy 466.266531 -106.569568) (xy 466.258406 -106.514356) (xy 466.257894 -106.486452) (xy 466.25838 -106.459183)
			(xy 466.266142 -106.405199) (xy 466.281507 -106.352869) (xy 466.304164 -106.303259) (xy 466.33365 -106.257378)
			(xy 466.369365 -106.216161) (xy 466.410582 -106.180446) (xy 466.456463 -106.15096) (xy 466.506073 -106.128303)
			(xy 466.558403 -106.112938) (xy 466.612387 -106.105176) (xy 466.666925 -106.105176) (xy 466.720909 -106.112938)
			(xy 466.773239 -106.128303) (xy 466.822849 -106.15096) (xy 466.86873 -106.180446) (xy 466.909947 -106.216161)
			(xy 466.945662 -106.257378) (xy 466.975148 -106.303259) (xy 466.997805 -106.352869) (xy 467.01317 -106.405199)
			(xy 467.020932 -106.459183) (xy 467.021418 -106.486452) (xy 467.527894 -106.486452) (xy 467.52838 -106.459183)
			(xy 467.536142 -106.405199) (xy 467.551507 -106.352869) (xy 467.574164 -106.303259) (xy 467.60365 -106.257378)
			(xy 467.639365 -106.216161) (xy 467.680582 -106.180446) (xy 467.726463 -106.15096) (xy 467.776073 -106.128303)
			(xy 467.828403 -106.112938) (xy 467.882387 -106.105176) (xy 467.936925 -106.105176) (xy 467.990909 -106.112938)
			(xy 468.043239 -106.128303) (xy 468.092849 -106.15096) (xy 468.13873 -106.180446) (xy 468.179947 -106.216161)
			(xy 468.215662 -106.257378) (xy 468.245148 -106.303259) (xy 468.267805 -106.352869) (xy 468.28317 -106.405199)
			(xy 468.290932 -106.459183) (xy 468.291418 -106.486452) (xy 468.797894 -106.486452) (xy 468.79838 -106.459183)
			(xy 468.806142 -106.405199) (xy 468.821507 -106.352869) (xy 468.844164 -106.303259) (xy 468.87365 -106.257378)
			(xy 468.909365 -106.216161) (xy 468.950582 -106.180446) (xy 468.996463 -106.15096) (xy 469.046073 -106.128303)
			(xy 469.098403 -106.112938) (xy 469.152387 -106.105176) (xy 469.206925 -106.105176) (xy 469.260909 -106.112938)
			(xy 469.313239 -106.128303) (xy 469.362849 -106.15096) (xy 469.40873 -106.180446) (xy 469.449947 -106.216161)
			(xy 469.485662 -106.257378) (xy 469.515148 -106.303259) (xy 469.537805 -106.352869) (xy 469.55317 -106.405199)
			(xy 469.560932 -106.459183) (xy 469.561418 -106.486452) (xy 470.067894 -106.486452) (xy 470.06838 -106.459183)
			(xy 470.076142 -106.405199) (xy 470.091507 -106.352869) (xy 470.114164 -106.303259) (xy 470.14365 -106.257378)
			(xy 470.179365 -106.216161) (xy 470.220582 -106.180446) (xy 470.266463 -106.15096) (xy 470.316073 -106.128303)
			(xy 470.368403 -106.112938) (xy 470.422387 -106.105176) (xy 470.476925 -106.105176) (xy 470.530909 -106.112938)
			(xy 470.583239 -106.128303) (xy 470.632849 -106.15096) (xy 470.67873 -106.180446) (xy 470.719947 -106.216161)
			(xy 470.755662 -106.257378) (xy 470.785148 -106.303259) (xy 470.807805 -106.352869) (xy 470.82317 -106.405199)
			(xy 470.830932 -106.459183) (xy 470.831418 -106.486452) (xy 470.830908 -106.514357) (xy 470.822792 -106.569572)
			(xy 470.806726 -106.623019) (xy 470.79535 -106.648504) (xy 470.790524 -106.658918) (xy 470.790524 -106.837988)
			(xy 470.793826 -106.850688) (xy 470.797382 -106.85653) (xy 470.8068 -106.873818) (xy 470.820157 -106.910847)
			(xy 470.826936 -106.949624) (xy 470.827354 -106.969306) (xy 470.827354 -107.240324) (xy 470.810844 -107.240324)
			(xy 470.79973 -107.242523) (xy 470.780848 -107.254982) (xy 470.769143 -107.274342) (xy 470.76741 -107.285536)
			(xy 470.76741 -107.713526) (xy 470.767825 -107.723409) (xy 470.775295 -107.741709) (xy 470.781888 -107.749086)
			(xy 470.782396 -107.749594) (xy 470.812114 -107.779312) (xy 470.818993 -107.786708) (xy 470.826862 -107.805292)
			(xy 470.827354 -107.81538) (xy 470.827354 -108.035598) (xy 470.826919 -108.055279) (xy 470.820147 -108.094055)
			(xy 470.806789 -108.131082) (xy 470.797382 -108.148374) (xy 470.793826 -108.154216) (xy 470.790524 -108.166916)
			(xy 470.790524 -110.454948) (xy 470.79535 -110.465362) (xy 470.806638 -110.490738) (xy 470.822601 -110.543933)
			(xy 470.830664 -110.598883) (xy 470.831164 -110.626652) (xy 470.830678 -110.653903) (xy 470.822922 -110.707851)
			(xy 470.807567 -110.760146) (xy 470.784925 -110.809723) (xy 470.755459 -110.855573) (xy 470.719768 -110.896764)
			(xy 470.678577 -110.932455) (xy 470.632727 -110.961921) (xy 470.58315 -110.984563) (xy 470.530855 -110.999918)
			(xy 470.476907 -111.007674) (xy 470.422405 -111.007674) (xy 470.368457 -110.999918) (xy 470.316162 -110.984563)
			(xy 470.266585 -110.961921) (xy 470.220735 -110.932455) (xy 470.179544 -110.896764) (xy 470.143853 -110.855573)
			(xy 470.114387 -110.809723) (xy 470.091745 -110.760146) (xy 470.07639 -110.707851) (xy 470.068634 -110.653903)
			(xy 470.068148 -110.626652) (xy 470.068667 -110.598884) (xy 470.07674 -110.543938) (xy 470.092678 -110.490739)
			(xy 470.103962 -110.465362) (xy 470.108788 -110.454948) (xy 470.108788 -108.166916) (xy 470.105486 -108.154216)
			(xy 470.10193 -108.148374) (xy 470.092514 -108.131085) (xy 470.079156 -108.094056) (xy 470.072376 -108.05528)
			(xy 470.071958 -108.035598) (xy 470.071958 -107.76458) (xy 470.088468 -107.76458) (xy 470.099582 -107.762385)
			(xy 470.118464 -107.749923) (xy 470.130168 -107.730563) (xy 470.131902 -107.719368) (xy 470.131902 -107.291378)
			(xy 470.131482 -107.281495) (xy 470.124015 -107.263196) (xy 470.117424 -107.255818) (xy 470.116916 -107.25531)
			(xy 470.087198 -107.225592) (xy 470.080308 -107.218205) (xy 470.072448 -107.199613) (xy 470.071958 -107.189524)
			(xy 470.071958 -106.969306) (xy 470.072393 -106.949625) (xy 470.079164 -106.910849) (xy 470.092522 -106.873822)
			(xy 470.10193 -106.85653) (xy 470.105486 -106.850688) (xy 470.108788 -106.837988) (xy 470.108788 -106.658918)
			(xy 470.103962 -106.648504) (xy 470.092602 -106.623012) (xy 470.076531 -106.569568) (xy 470.068406 -106.514356)
			(xy 470.067894 -106.486452) (xy 469.561418 -106.486452) (xy 469.560908 -106.514357) (xy 469.552792 -106.569572)
			(xy 469.536726 -106.623019) (xy 469.52535 -106.648504) (xy 469.520524 -106.658918) (xy 469.520524 -106.837988)
			(xy 469.523826 -106.850688) (xy 469.527382 -106.85653) (xy 469.5368 -106.873818) (xy 469.550157 -106.910847)
			(xy 469.556936 -106.949624) (xy 469.557354 -106.969306) (xy 469.557354 -107.240324) (xy 469.540844 -107.240324)
			(xy 469.52973 -107.242523) (xy 469.510848 -107.254982) (xy 469.499143 -107.274342) (xy 469.49741 -107.285536)
			(xy 469.49741 -107.713526) (xy 469.497825 -107.723409) (xy 469.505295 -107.741709) (xy 469.511888 -107.749086)
			(xy 469.512396 -107.749594) (xy 469.542114 -107.779312) (xy 469.548993 -107.786708) (xy 469.556862 -107.805292)
			(xy 469.557354 -107.81538) (xy 469.557354 -108.035598) (xy 469.556919 -108.055279) (xy 469.550147 -108.094055)
			(xy 469.536789 -108.131082) (xy 469.527382 -108.148374) (xy 469.523826 -108.154216) (xy 469.520524 -108.166916)
			(xy 469.520524 -109.192568) (xy 469.52535 -109.202982) (xy 469.536645 -109.228356) (xy 469.552605 -109.281552)
			(xy 469.560665 -109.336503) (xy 469.561164 -109.364272) (xy 469.560678 -109.391523) (xy 469.552922 -109.445471)
			(xy 469.537567 -109.497766) (xy 469.514925 -109.547343) (xy 469.485459 -109.593193) (xy 469.449768 -109.634384)
			(xy 469.408577 -109.670075) (xy 469.362727 -109.699541) (xy 469.31315 -109.722183) (xy 469.260855 -109.737538)
			(xy 469.206907 -109.745294) (xy 469.152405 -109.745294) (xy 469.098457 -109.737538) (xy 469.046162 -109.722183)
			(xy 468.996585 -109.699541) (xy 468.950735 -109.670075) (xy 468.909544 -109.634384) (xy 468.873853 -109.593193)
			(xy 468.844387 -109.547343) (xy 468.821745 -109.497766) (xy 468.80639 -109.445471) (xy 468.798634 -109.391523)
			(xy 468.798148 -109.364272) (xy 468.798674 -109.336505) (xy 468.806744 -109.281559) (xy 468.82268 -109.228359)
			(xy 468.833962 -109.202982) (xy 468.838788 -109.192568) (xy 468.838788 -108.166916) (xy 468.835486 -108.154216)
			(xy 468.83193 -108.148374) (xy 468.822514 -108.131085) (xy 468.809156 -108.094056) (xy 468.802376 -108.05528)
			(xy 468.801958 -108.035598) (xy 468.801958 -107.76458) (xy 468.818468 -107.76458) (xy 468.829582 -107.762385)
			(xy 468.848464 -107.749923) (xy 468.860168 -107.730563) (xy 468.861902 -107.719368) (xy 468.861902 -107.291378)
			(xy 468.861482 -107.281495) (xy 468.854015 -107.263196) (xy 468.847424 -107.255818) (xy 468.846916 -107.25531)
			(xy 468.817198 -107.225592) (xy 468.810308 -107.218205) (xy 468.802448 -107.199613) (xy 468.801958 -107.189524)
			(xy 468.801958 -106.969306) (xy 468.802393 -106.949625) (xy 468.809164 -106.910849) (xy 468.822522 -106.873822)
			(xy 468.83193 -106.85653) (xy 468.835486 -106.850688) (xy 468.838788 -106.837988) (xy 468.838788 -106.658918)
			(xy 468.833962 -106.648504) (xy 468.822602 -106.623012) (xy 468.806531 -106.569568) (xy 468.798406 -106.514356)
			(xy 468.797894 -106.486452) (xy 468.291418 -106.486452) (xy 468.290908 -106.514357) (xy 468.282792 -106.569572)
			(xy 468.266726 -106.623019) (xy 468.25535 -106.648504) (xy 468.250524 -106.658918) (xy 468.250524 -106.837988)
			(xy 468.253826 -106.850688) (xy 468.257382 -106.85653) (xy 468.2668 -106.873818) (xy 468.280157 -106.910847)
			(xy 468.286936 -106.949624) (xy 468.287354 -106.969306) (xy 468.287354 -107.240324) (xy 468.270844 -107.240324)
			(xy 468.25973 -107.242523) (xy 468.240848 -107.254982) (xy 468.229143 -107.274342) (xy 468.22741 -107.285536)
			(xy 468.22741 -107.713526) (xy 468.227825 -107.723409) (xy 468.235295 -107.741709) (xy 468.241888 -107.749086)
			(xy 468.242396 -107.749594) (xy 468.272114 -107.779312) (xy 468.278993 -107.786708) (xy 468.286862 -107.805292)
			(xy 468.287354 -107.81538) (xy 468.287354 -108.035598) (xy 468.286919 -108.055279) (xy 468.280147 -108.094055)
			(xy 468.266789 -108.131082) (xy 468.257382 -108.148374) (xy 468.253826 -108.154216) (xy 468.250524 -108.166916)
			(xy 468.250524 -109.642148) (xy 468.25535 -109.652562) (xy 468.266638 -109.677938) (xy 468.282601 -109.731133)
			(xy 468.290664 -109.786083) (xy 468.291164 -109.813852) (xy 468.290678 -109.841103) (xy 468.282922 -109.895051)
			(xy 468.267567 -109.947346) (xy 468.244925 -109.996923) (xy 468.215459 -110.042773) (xy 468.179768 -110.083964)
			(xy 468.138577 -110.119655) (xy 468.092727 -110.149121) (xy 468.04315 -110.171763) (xy 467.990855 -110.187118)
			(xy 467.936907 -110.194874) (xy 467.882405 -110.194874) (xy 467.828457 -110.187118) (xy 467.776162 -110.171763)
			(xy 467.726585 -110.149121) (xy 467.680735 -110.119655) (xy 467.639544 -110.083964) (xy 467.603853 -110.042773)
			(xy 467.574387 -109.996923) (xy 467.551745 -109.947346) (xy 467.53639 -109.895051) (xy 467.528634 -109.841103)
			(xy 467.528148 -109.813852) (xy 467.528667 -109.786084) (xy 467.53674 -109.731138) (xy 467.552678 -109.677939)
			(xy 467.563962 -109.652562) (xy 467.568788 -109.642148) (xy 467.568788 -108.166916) (xy 467.565486 -108.154216)
			(xy 467.56193 -108.148374) (xy 467.552514 -108.131085) (xy 467.539156 -108.094056) (xy 467.532376 -108.05528)
			(xy 467.531958 -108.035598) (xy 467.531958 -107.76458) (xy 467.548468 -107.76458) (xy 467.559582 -107.762385)
			(xy 467.578464 -107.749923) (xy 467.590168 -107.730563) (xy 467.591902 -107.719368) (xy 467.591902 -107.291378)
			(xy 467.591482 -107.281495) (xy 467.584015 -107.263196) (xy 467.577424 -107.255818) (xy 467.576916 -107.25531)
			(xy 467.547198 -107.225592) (xy 467.540308 -107.218205) (xy 467.532448 -107.199613) (xy 467.531958 -107.189524)
			(xy 467.531958 -106.969306) (xy 467.532393 -106.949625) (xy 467.539164 -106.910849) (xy 467.552522 -106.873822)
			(xy 467.56193 -106.85653) (xy 467.565486 -106.850688) (xy 467.568788 -106.837988) (xy 467.568788 -106.658918)
			(xy 467.563962 -106.648504) (xy 467.552602 -106.623012) (xy 467.536531 -106.569568) (xy 467.528406 -106.514356)
			(xy 467.527894 -106.486452) (xy 467.021418 -106.486452) (xy 467.020908 -106.514357) (xy 467.012792 -106.569572)
			(xy 466.996726 -106.623019) (xy 466.98535 -106.648504) (xy 466.980524 -106.658918) (xy 466.980524 -106.837988)
			(xy 466.983826 -106.850688) (xy 466.987382 -106.85653) (xy 466.9968 -106.873818) (xy 467.010157 -106.910847)
			(xy 467.016936 -106.949624) (xy 467.017354 -106.969306) (xy 467.017354 -107.240324) (xy 467.000844 -107.240324)
			(xy 466.98973 -107.242523) (xy 466.970848 -107.254982) (xy 466.959143 -107.274342) (xy 466.95741 -107.285536)
			(xy 466.95741 -107.713526) (xy 466.957825 -107.723409) (xy 466.965295 -107.741709) (xy 466.971888 -107.749086)
			(xy 466.972396 -107.749594) (xy 467.002114 -107.779312) (xy 467.008993 -107.786708) (xy 467.016862 -107.805292)
			(xy 467.017354 -107.81538) (xy 467.017354 -108.035598) (xy 467.016919 -108.055279) (xy 467.010147 -108.094055)
			(xy 466.996789 -108.131082) (xy 466.987382 -108.148374) (xy 466.983826 -108.154216) (xy 466.980524 -108.166916)
			(xy 466.980524 -108.599986) (xy 466.98535 -108.6104) (xy 466.996712 -108.635891) (xy 467.012782 -108.689335)
			(xy 467.020907 -108.744548) (xy 467.021418 -108.772452) (xy 467.020932 -108.799721) (xy 467.01317 -108.853705)
			(xy 466.997805 -108.906035) (xy 466.975148 -108.955645) (xy 466.945662 -109.001526) (xy 466.909947 -109.042743)
			(xy 466.86873 -109.078458) (xy 466.822849 -109.107944) (xy 466.773239 -109.130601) (xy 466.720909 -109.145966)
			(xy 466.666925 -109.153728) (xy 466.612387 -109.153728) (xy 466.558403 -109.145966) (xy 466.506073 -109.130601)
			(xy 466.456463 -109.107944) (xy 466.410582 -109.078458) (xy 466.369365 -109.042743) (xy 466.33365 -109.001526)
			(xy 466.304164 -108.955645) (xy 466.281507 -108.906035) (xy 466.266142 -108.853705) (xy 466.25838 -108.799721)
			(xy 466.257894 -108.772452) (xy 418.338 -108.772452) (xy 418.338 -127.850273) (xy 434.474354 -127.850273)
			(xy 434.474354 -127.736719) (xy 434.482275 -127.623443) (xy 434.498078 -127.510995) (xy 434.521687 -127.399924)
			(xy 434.552987 -127.290769) (xy 434.591824 -127.184064) (xy 434.63801 -127.080329) (xy 434.69132 -126.980067)
			(xy 434.751494 -126.883769) (xy 434.818239 -126.791903) (xy 434.891229 -126.704916) (xy 434.97011 -126.623233)
			(xy 435.054496 -126.547251) (xy 435.143977 -126.477341) (xy 435.238117 -126.413843) (xy 435.336457 -126.357066)
			(xy 435.438517 -126.307288) (xy 435.543802 -126.26475) (xy 435.651797 -126.22966) (xy 435.761977 -126.202189)
			(xy 435.873805 -126.182471) (xy 435.986736 -126.170601) (xy 436.10022 -126.166639) (xy 436.213704 -126.170601)
			(xy 436.326635 -126.182471) (xy 436.438463 -126.202189) (xy 436.548643 -126.22966) (xy 436.656638 -126.26475)
			(xy 436.761923 -126.307288) (xy 436.863983 -126.357066) (xy 436.962323 -126.413843) (xy 437.056463 -126.477341)
			(xy 437.145944 -126.547251) (xy 437.23033 -126.623233) (xy 437.309211 -126.704916) (xy 437.382201 -126.791903)
			(xy 437.448946 -126.883769) (xy 437.50912 -126.980067) (xy 437.56243 -127.080329) (xy 437.608616 -127.184064)
			(xy 437.647453 -127.290769) (xy 437.678753 -127.399924) (xy 437.702362 -127.510995) (xy 437.718165 -127.623443)
			(xy 437.726086 -127.736719) (xy 437.726582 -127.793496) (xy 437.726086 -127.850273) (xy 437.718165 -127.963549)
			(xy 437.702362 -128.075997) (xy 437.678753 -128.187068) (xy 437.647453 -128.296223) (xy 437.608616 -128.402928)
			(xy 437.56243 -128.506663) (xy 437.50912 -128.606925) (xy 437.448946 -128.703223) (xy 437.382201 -128.795089)
			(xy 437.309211 -128.882076) (xy 437.23033 -128.963759) (xy 437.145944 -129.039741) (xy 437.056463 -129.109651)
			(xy 436.962323 -129.173149) (xy 436.863983 -129.229926) (xy 436.761923 -129.279704) (xy 436.656638 -129.322242)
			(xy 436.548643 -129.357332) (xy 436.438463 -129.384803) (xy 436.326635 -129.404521) (xy 436.213704 -129.416391)
			(xy 436.10022 -129.420354) (xy 435.986736 -129.416391) (xy 435.873805 -129.404521) (xy 435.761977 -129.384803)
			(xy 435.651797 -129.357332) (xy 435.543802 -129.322242) (xy 435.438517 -129.279704) (xy 435.336457 -129.229926)
			(xy 435.238117 -129.173149) (xy 435.143977 -129.109651) (xy 435.054496 -129.039741) (xy 434.97011 -128.963759)
			(xy 434.891229 -128.882076) (xy 434.818239 -128.795089) (xy 434.751494 -128.703223) (xy 434.69132 -128.606925)
			(xy 434.63801 -128.506663) (xy 434.591824 -128.402928) (xy 434.552987 -128.296223) (xy 434.521687 -128.187068)
			(xy 434.498078 -128.075997) (xy 434.482275 -127.963549) (xy 434.474354 -127.850273) (xy 418.338 -127.850273)
			(xy 418.338 -149.330918) (xy 418.337573 -149.340987) (xy 418.329854 -149.359586) (xy 418.323014 -149.366986)
			(xy 415.558986 -152.131014) (xy 415.551591 -152.137868) (xy 415.532992 -152.14561) (xy 415.522918 -152.146)
			(xy 403.032722 -152.146) (xy 403.013926 -152.15362) (xy 403.006814 -152.160986) (xy 402.884386 -152.283414)
			(xy 402.87702 -152.290526) (xy 402.8694 -152.309322) (xy 402.8694 -169.320718) (xy 402.86986 -169.330595)
			(xy 402.877303 -169.348894) (xy 402.883878 -169.356278) (xy 402.930614 -169.403014) (xy 402.931122 -169.403522)
			(xy 402.9385 -169.410112) (xy 402.956799 -169.417579) (xy 402.966682 -169.418)
		)
		(stroke
			(width 0)
			(type solid)
		)
		(fill yes)
		(layer "F.Cu")
		(net "GND")
	)
	(gr_poly
		(pts
			(xy 178.278536 -82.5246) (xy 178.278536 -80.78216) (xy 174.620936 -80.78216) (xy 174.620936 -82.5754)
			(xy 174.671736 -82.6262) (xy 178.176936 -82.6262)
		)
		(stroke
			(width 0)
			(type solid)
		)
		(fill yes)
		(layer "B.Cu")
		(net "P52V_HS2")
	)
	(gr_poly
		(pts
			(xy 324.104 -79.7052) (xy 324.104 -47.0662) (xy 323.7738 -46.736) (xy 311.2516 -46.736) (xy 311.2516 -79.629)
			(xy 311.6072 -79.9846) (xy 323.8246 -79.9846)
		)
		(stroke
			(width 0)
			(type solid)
		)
		(fill yes)
		(layer "B.Cu")
		(net "P52V_HS1_DRAIN_1")
	)
	(gr_poly
		(pts
			(xy 136.368536 -79.629) (xy 136.368536 -47.192692) (xy 135.911844 -46.736) (xy 123.846336 -46.736)
			(xy 123.516136 -47.0662) (xy 123.516136 -79.7052) (xy 123.795536 -79.9846) (xy 136.012936 -79.9846)
		)
		(stroke
			(width 0)
			(type solid)
		)
		(fill yes)
		(layer "B.Cu")
		(net "P52V_HS2_DRAIN_1")
	)
	(gr_poly
		(pts
			(xy 136.368536 -45.7962) (xy 136.368536 -15.0114) (xy 135.708136 -14.351) (xy 124.151136 -14.351)
			(xy 123.516136 -14.986) (xy 123.516136 -45.8724) (xy 123.795536 -46.1518) (xy 136.012936 -46.1518)
		)
		(stroke
			(width 0)
			(type solid)
		)
		(fill yes)
		(layer "B.Cu")
		(net "P52V_HS2_DRAIN_2")
	)
	(gr_poly
		(pts
			(xy 167.553894 -60.576968) (xy 167.553894 -58.59399) (xy 167.469312 -58.509408) (xy 166.28872 -58.509408)
			(xy 166.257224 -58.540904) (xy 166.257224 -60.60313) (xy 166.297102 -60.643008) (xy 167.487854 -60.643008)
		)
		(stroke
			(width 0)
			(type solid)
		)
		(fill yes)
		(layer "B.Cu")
		(net "P52V_HS2")
	)
	(gr_poly
		(pts
			(xy 257.683 -50.557684) (xy 257.683 -46.692312) (xy 254.297688 -43.307) (xy 250.69673 -43.307) (xy 247.265952 -46.737778)
			(xy 247.265952 -50.684938) (xy 247.513094 -50.93208) (xy 257.308604 -50.93208)
		)
		(stroke
			(width 0)
			(type solid)
		)
		(fill yes)
		(layer "B.Cu")
		(net "P52V_1_FUSE_1")
	)
	(gr_poly
		(pts
			(xy 272.9992 -59.4614) (xy 272.9992 -57.6326) (xy 272.9484 -57.5818) (xy 269.4432 -57.5818) (xy 269.3416 -57.6834)
			(xy 269.3416 -59.436) (xy 269.3924 -59.4868) (xy 272.9738 -59.4868)
		)
		(stroke
			(width 0)
			(type solid)
		)
		(fill yes)
		(layer "B.Cu")
		(net "P52V_HS1")
	)
	(gr_poly
		(pts
			(xy 286.998156 -82.276442) (xy 286.998156 -78.711552) (xy 286.85236 -78.565756) (xy 284.227524 -78.565756)
			(xy 284.099 -78.69428) (xy 284.099 -82.169) (xy 284.353 -82.423) (xy 286.851598 -82.423)
		)
		(stroke
			(width 0)
			(type solid)
		)
		(fill yes)
		(layer "B.Cu")
		(net "P52V_HS1_DVCC")
	)
	(gr_poly
		(pts
			(xy 290.6014 -82.296) (xy 290.6014 -80.772) (xy 290.4744 -80.645) (xy 288.6964 -80.645) (xy 288.5694 -80.772)
			(xy 288.5694 -82.296) (xy 288.6964 -82.423) (xy 290.4744 -82.423)
		)
		(stroke
			(width 0)
			(type solid)
		)
		(fill yes)
		(layer "B.Cu")
		(net "GND")
	)
	(gr_poly
		(pts
			(xy 324.104 -45.8724) (xy 324.104 -15.1638) (xy 323.2912 -14.351) (xy 311.9628 -14.351) (xy 311.2516 -15.0622)
			(xy 311.2516 -45.7962) (xy 311.6072 -46.1518) (xy 323.8246 -46.1518)
		)
		(stroke
			(width 0)
			(type solid)
		)
		(fill yes)
		(layer "B.Cu")
		(net "P52V_HS1_DRAIN_2")
	)
	(gr_poly
		(pts
			(xy 281.372818 -79.628746) (xy 281.372818 -78.070202) (xy 281.24023 -77.937614) (xy 281.182572 -77.879956)
			(xy 280.058622 -77.879956) (xy 279.941528 -77.99705) (xy 279.941528 -79.930752) (xy 279.947878 -79.937102)
			(xy 281.064462 -79.937102)
		)
		(stroke
			(width 0)
			(type solid)
		)
		(fill yes)
		(layer "B.Cu")
		(net "P52V_HS1")
	)
	(gr_poly
		(pts
			(xy 455.0664 -66.421) (xy 455.0664 -65.151) (xy 455.0664 -62.865) (xy 454.6854 -62.484) (xy 441.805568 -62.484)
			(xy 441.462414 -62.827154) (xy 441.462414 -66.456052) (xy 441.935362 -66.929) (xy 454.5584 -66.929)
		)
		(stroke
			(width 0)
			(type solid)
		)
		(fill yes)
		(layer "B.Cu")
		(net "P3V3_AUX")
	)
	(gr_poly
		(pts
			(xy 159.050736 -60.044838) (xy 159.050736 -59.436) (xy 159.050736 -57.912) (xy 158.923736 -57.785)
			(xy 157.7848 -57.785) (xy 157.629352 -57.940448) (xy 157.629352 -59.563) (xy 157.629352 -60.052204)
			(xy 157.770068 -60.19292) (xy 158.902654 -60.19292)
		)
		(stroke
			(width 0)
			(type solid)
		)
		(fill yes)
		(layer "B.Cu")
		(net "GND")
	)
	(gr_poly
		(pts
			(xy 151.515572 -67.050412) (xy 151.515572 -65.477136) (xy 151.708612 -65.284096) (xy 151.708612 -63.246)
			(xy 150.332186 -63.246) (xy 150.311358 -63.266828) (xy 150.311358 -65.385696) (xy 151.182578 -66.256916)
			(xy 151.182578 -67.042538) (xy 151.209248 -67.069208) (xy 151.496776 -67.069208)
		)
		(stroke
			(width 0)
			(type solid)
		)
		(fill yes)
		(layer "B.Cu")
		(net "P52V_HS2_VDSFB")
	)
	(gr_poly
		(pts
			(xy 163.425124 -61.609732) (xy 163.425124 -60.50788) (xy 163.425124 -58.015124) (xy 163.260532 -57.850532)
			(xy 162.50539 -57.850532) (xy 162.05581 -57.850532) (xy 160.703006 -57.850532) (xy 160.62198 -57.931558)
			(xy 160.62198 -61.496448) (xy 160.767776 -61.642244) (xy 163.392612 -61.642244)
		)
		(stroke
			(width 0)
			(type solid)
		)
		(fill yes)
		(layer "B.Cu")
		(net "P52V_HS2_DVCC")
	)
	(gr_poly
		(pts
			(xy 299.10405 -80.435958) (xy 299.10405 -74.07148) (xy 297.747182 -72.714612) (xy 296.582592 -72.714612)
			(xy 296.576496 -72.720454) (xy 296.576496 -72.999346) (xy 297.661838 -74.084688) (xy 297.715432 -74.138282)
			(xy 297.715432 -80.534764) (xy 297.835574 -80.654906) (xy 298.885102 -80.654906)
		)
		(stroke
			(width 0)
			(type solid)
		)
		(fill yes)
		(layer "B.Cu")
		(net "P52V_HS1")
	)
	(gr_poly
		(pts
			(xy 151.684736 -80.193642) (xy 151.684736 -78.493366) (xy 151.537924 -78.346554) (xy 151.537924 -73.187306)
			(xy 151.504396 -73.153778) (xy 151.21001 -73.153778) (xy 151.189944 -73.173844) (xy 151.189944 -74.574908)
			(xy 149.448774 -76.316078) (xy 149.448774 -80.095344) (xy 149.612858 -80.259428) (xy 151.61895 -80.259428)
		)
		(stroke
			(width 0)
			(type solid)
		)
		(fill yes)
		(layer "B.Cu")
		(net "P52V_2")
	)
	(gr_poly
		(pts
			(xy 265.463274 -70.019926) (xy 266.5476 -70.019926) (xy 266.616942 -69.950584) (xy 266.616942 -69.751448)
			(xy 266.563348 -69.697854) (xy 265.277346 -69.697854) (xy 264.9982 -69.977) (xy 261.2898 -69.977)
			(xy 261.1882 -70.0786) (xy 261.1882 -71.9328) (xy 261.2644 -72.009) (xy 263.4742 -72.009)
		)
		(stroke
			(width 0)
			(type solid)
		)
		(fill yes)
		(layer "B.Cu")
		(net "P52V_HS1")
	)
	(gr_poly
		(pts
			(xy 277.241 -86.487) (xy 277.241 -84.6836) (xy 277.14956 -84.59216) (xy 264.83056 -84.59216) (xy 264.0965 -83.8581)
			(xy 264.0965 -79.069946) (xy 262.433054 -79.069946) (xy 262.382 -79.121) (xy 262.382 -85.9536) (xy 263.271 -86.8426)
			(xy 263.271 -86.868) (xy 276.86 -86.868)
		)
		(stroke
			(width 0)
			(type solid)
		)
		(fill yes)
		(layer "B.Cu")
		(net "P52V_1")
	)
	(gr_poly
		(pts
			(xy 278.65832 -75.809602) (xy 278.65832 -73.121266) (xy 278.543766 -73.006712) (xy 275.250148 -73.006712)
			(xy 274.425664 -72.182482) (xy 273.738848 -72.182482) (xy 273.692366 -72.228964) (xy 273.692366 -72.486774)
			(xy 274.984718 -73.779126) (xy 275.624798 -73.779126) (xy 277.675594 -75.829922) (xy 278.638 -75.829922)
		)
		(stroke
			(width 0)
			(type solid)
		)
		(fill yes)
		(layer "B.Cu")
		(net "P52V_HS1_ISET")
	)
	(gr_poly
		(pts
			(xy 296.94251 -77.641196) (xy 296.94251 -74.906632) (xy 296.437558 -74.40168) (xy 296.437558 -73.165462)
			(xy 296.410888 -73.138792) (xy 296.12336 -73.138792) (xy 296.104564 -73.157588) (xy 296.104564 -75.586082)
			(xy 295.814496 -75.87615) (xy 295.814496 -77.64018) (xy 295.82872 -77.654404) (xy 296.929556 -77.654404)
		)
		(stroke
			(width 0)
			(type solid)
		)
		(fill yes)
		(layer "B.Cu")
		(net "P52V_HS1_VDSFB")
	)
	(gr_poly
		(pts
			(xy 186.144916 -73.115424) (xy 186.144916 -72.124316) (xy 186.0296 -72.009) (xy 184.425336 -72.009)
			(xy 184.205372 -71.789036) (xy 182.568596 -71.789036) (xy 181.964076 -71.184516) (xy 181.073044 -71.184516)
			(xy 181.008528 -71.249032) (xy 181.008528 -71.46925) (xy 181.06771 -71.528432) (xy 181.83733 -71.528432)
			(xy 183.486298 -73.1774) (xy 186.08294 -73.1774)
		)
		(stroke
			(width 0)
			(type solid)
		)
		(fill yes)
		(layer "B.Cu")
		(net "P52V_HS2_VCP")
	)
	(gr_poly
		(pts
			(xy 266.611608 -68.958968) (xy 266.611608 -68.73875) (xy 266.552426 -68.679568) (xy 265.782806 -68.679568)
			(xy 264.074402 -66.971164) (xy 263.581642 -66.971164) (xy 261.507478 -66.971164) (xy 261.47522 -67.003422)
			(xy 261.47522 -68.163948) (xy 261.47522 -68.30568) (xy 261.588504 -68.418964) (xy 265.05154 -68.418964)
			(xy 265.65606 -69.023484) (xy 266.547092 -69.023484)
		)
		(stroke
			(width 0)
			(type solid)
		)
		(fill yes)
		(layer "B.Cu")
		(net "P52V_HS1_VCP")
	)
	(gr_poly
		(pts
			(xy 182.589932 -70.263004) (xy 182.781448 -70.263004) (xy 186.053476 -70.263004) (xy 186.144662 -70.171818)
			(xy 186.144662 -69.097144) (xy 186.144662 -68.292726) (xy 186.050936 -68.199) (xy 184.145936 -68.199)
			(xy 182.156862 -70.188074) (xy 181.91607 -70.188074) (xy 181.072536 -70.188074) (xy 181.003194 -70.257416)
			(xy 181.003194 -70.456552) (xy 181.056788 -70.510146) (xy 182.066946 -70.510146) (xy 182.34279 -70.510146)
		)
		(stroke
			(width 0)
			(type solid)
		)
		(fill yes)
		(layer "B.Cu")
		(net "P52V_HS2")
	)
	(gr_poly
		(pts
			(xy 170.95978 -69.868288) (xy 170.95978 -69.596) (xy 171.54652 -69.00926) (xy 173.915324 -69.00926)
			(xy 173.943518 -68.981066) (xy 173.943518 -68.725796) (xy 173.91507 -68.697348) (xy 171.995084 -68.697348)
			(xy 171.362878 -68.065142) (xy 170.87088 -68.065142) (xy 170.449494 -68.065142) (xy 170.36034 -68.154296)
			(xy 170.36034 -68.907914) (xy 170.044364 -69.22389) (xy 170.044364 -69.949314) (xy 170.068494 -69.973444)
			(xy 170.854624 -69.973444)
		)
		(stroke
			(width 0)
			(type solid)
		)
		(fill yes)
		(layer "B.Cu")
		(net "P52V_HS2_VCAP")
	)
	(gr_poly
		(pts
			(xy 173.92777 -67.979036) (xy 173.92777 -67.721226) (xy 172.635418 -66.428874) (xy 171.995338 -66.428874)
			(xy 169.780966 -64.214502) (xy 169.780966 -56.45023) (xy 169.728896 -56.39816) (xy 168.372536 -56.39816)
			(xy 168.331896 -56.4388) (xy 168.331896 -63.474092) (xy 168.94429 -64.086486) (xy 168.94429 -64.415924)
			(xy 168.94429 -67.069208) (xy 169.07637 -67.201288) (xy 172.369988 -67.201288) (xy 173.194472 -68.025518)
			(xy 173.881288 -68.025518)
		)
		(stroke
			(width 0)
			(type solid)
		)
		(fill yes)
		(layer "B.Cu")
		(net "P52V_HS2_ISET")
	)
	(gr_poly
		(pts
			(xy 277.259796 -72.053704) (xy 277.259796 -71.300086) (xy 277.575772 -70.98411) (xy 277.575772 -70.258686)
			(xy 277.551642 -70.234556) (xy 276.765512 -70.234556) (xy 276.660356 -70.339712) (xy 276.660356 -70.612)
			(xy 276.073616 -71.19874) (xy 273.704812 -71.19874) (xy 273.676618 -71.226934) (xy 273.676618 -71.482204)
			(xy 273.705066 -71.510652) (xy 275.625052 -71.510652) (xy 276.257258 -72.142858) (xy 276.749256 -72.142858)
			(xy 277.170642 -72.142858)
		)
		(stroke
			(width 0)
			(type solid)
		)
		(fill yes)
		(layer "B.Cu")
		(net "P52V_HS1_VCAP")
	)
	(gr_poly
		(pts
			(xy 279.163272 -82.046826) (xy 279.163272 -76.414122) (xy 278.675846 -75.926696) (xy 278.663908 -75.914758)
			(xy 278.662638 -75.913488) (xy 278.65832 -75.90917) (xy 278.65832 -75.522074) (xy 277.690834 -75.522074)
			(xy 277.52929 -75.683618) (xy 278.007826 -76.162154) (xy 278.007826 -81.584038) (xy 277.06193 -82.529934)
			(xy 275.836634 -82.529934) (xy 275.64334 -82.723228) (xy 275.64334 -83.779614) (xy 275.673566 -83.80984)
			(xy 277.400258 -83.80984)
		)
		(stroke
			(width 0)
			(type solid)
		)
		(fill yes)
		(layer "B.Cu")
		(net "P52V_HS1_ISET")
	)
	(gr_poly
		(pts
			(xy 151.04364 -67.487546) (xy 151.04364 -67.208654) (xy 149.958298 -66.123312) (xy 149.958298 -62.718442)
			(xy 150.194772 -62.481968) (xy 151.703278 -62.481968) (xy 151.751538 -62.433708) (xy 151.751538 -61.072522)
			(xy 151.402542 -60.723526) (xy 151.402542 -60.674758) (xy 151.402542 -60.408058) (xy 151.402542 -59.00547)
			(xy 151.30018 -58.903108) (xy 149.69871 -58.903108) (xy 149.252432 -59.349386) (xy 149.252432 -66.872866)
			(xy 149.891496 -67.51193) (xy 151.019256 -67.51193)
		)
		(stroke
			(width 0)
			(type solid)
		)
		(fill yes)
		(layer "B.Cu")
		(net "P52V_HS2")
	)
	(gr_poly
		(pts
			(xy 177.978816 -63.589154) (xy 177.978816 -62.510416) (xy 177.7238 -62.2554) (xy 177.3174 -62.2554)
			(xy 177.3174 -60.6806) (xy 176.509426 -59.872626) (xy 170.744896 -59.872626) (xy 170.415966 -60.201556)
			(xy 170.415966 -63.590932) (xy 170.457114 -63.63208) (xy 175.029114 -63.63208) (xy 175.073818 -63.587376)
			(xy 175.073818 -62.889384) (xy 175.43018 -62.533022) (xy 177.085498 -62.533022) (xy 177.144426 -62.59195)
			(xy 177.144426 -63.342012) (xy 177.437542 -63.635128) (xy 177.495454 -63.635128) (xy 177.932842 -63.635128)
		)
		(stroke
			(width 0)
			(type solid)
		)
		(fill yes)
		(layer "B.Cu")
		(net "GND1_FIELD_SIGNAL")
	)
	(gr_poly
		(pts
			(xy 273.464528 -72.386444) (xy 273.464528 -66.809366) (xy 273.440144 -66.784982) (xy 270.792194 -66.784982)
			(xy 270.559022 -66.55181) (xy 270.559022 -65.748916) (xy 270.559022 -65.526412) (xy 269.911068 -64.878458)
			(xy 269.911068 -62.13221) (xy 269.881858 -62.103) (xy 269.375382 -62.103) (xy 267.745718 -62.103)
			(xy 267.718286 -62.130432) (xy 267.718286 -63.375286) (xy 270.2433 -65.9003) (xy 270.2433 -66.58102)
			(xy 270.646652 -66.984372) (xy 270.646652 -72.39381) (xy 270.664178 -72.411336) (xy 273.439636 -72.411336)
		)
		(stroke
			(width 0)
			(type solid)
		)
		(fill yes)
		(layer "B.Cu")
		(net "GND_FIELD_SIGNAL")
	)
	(gr_poly
		(pts
			(xy 277.20417 -80.006444) (xy 277.20417 -76.617068) (xy 277.163022 -76.57592) (xy 272.591022 -76.57592)
			(xy 272.546318 -76.620624) (xy 272.546318 -77.318616) (xy 272.189956 -77.674978) (xy 270.534638 -77.674978)
			(xy 270.167862 -77.308202) (xy 270.167862 -76.616052) (xy 270.124682 -76.572872) (xy 269.687294 -76.572872)
			(xy 269.64132 -76.618846) (xy 269.64132 -77.34808) (xy 268.1224 -78.867) (xy 267.208 -78.867) (xy 267.208 -80.0354)
			(xy 268.7828 -80.0354) (xy 269.082774 -80.335374) (xy 276.87524 -80.335374)
		)
		(stroke
			(width 0)
			(type solid)
		)
		(fill yes)
		(layer "B.Cu")
		(net "GND_FIELD_SIGNAL")
	)
	(gr_poly
		(pts
			(arc
				(start 342.926924 -101.331014)
				(mid 342.946447 -101.327113)
				(end 342.962992 -101.316028)
			)
			(arc
				(start 344.428572 -99.850448)
				(mid 344.439683 -99.833914)
				(end 344.443558 -99.81438)
			)
			(xy 344.443558 -85.160358) (xy 342.1888 -82.9056) (xy 338.0486 -82.9056) (xy 334.141064 -86.813136)
			(arc
				(start 315.359034 -86.813136)
				(mid 315.339511 -86.809235)
				(end 315.322966 -86.79815)
			)
			(xy 312.93816 -84.413344) (xy 301.865792 -84.413344) (xy 300.99 -85.289136) (xy 300.99 -100.823014)
			(xy 301.498 -101.331014)
		)
		(stroke
			(width 0)
			(type solid)
		)
		(fill yes)
		(layer "B.Cu")
		(net "GND")
	)
	(gr_poly
		(pts
			(xy 153.504392 -67.06108) (xy 153.504392 -66.352928) (xy 153.496772 -66.345308) (xy 153.496772 -66.2178)
			(xy 153.416 -66.137028) (xy 153.416 -64.9224) (xy 153.496772 -64.841628) (xy 153.496772 -62.951614)
			(xy 153.854912 -62.593474) (xy 153.854912 -62.13856) (xy 153.367232 -61.65088) (xy 153.367232 -59.028838)
			(xy 153.276046 -58.937652) (xy 152.222708 -58.937652) (xy 152.183084 -58.977276) (xy 152.183084 -60.387484)
			(xy 152.590754 -60.795154) (xy 152.590754 -65.712848) (xy 153.202386 -66.32448) (xy 153.202386 -67.0814)
			(xy 153.23058 -67.109594) (xy 153.455878 -67.109594)
		)
		(stroke
			(width 0)
			(type solid)
		)
		(fill yes)
		(layer "B.Cu")
		(net "P52V_HS2_FB")
	)
	(gr_poly
		(pts
			(xy 268.8082 -77.0636) (xy 268.8082 -74.5998) (xy 269.0622 -74.3458) (xy 269.0622 -72.3138) (xy 269.3416 -72.0344)
			(xy 269.3416 -67.8688) (xy 269.0622 -67.5894) (xy 269.0622 -65.8114) (xy 268.9606 -65.7098) (xy 266.7762 -65.7098)
			(xy 266.7254 -65.7606) (xy 266.7254 -66.4972) (xy 267.8176 -67.5894) (xy 267.8176 -71.374) (xy 268.732 -72.2884)
			(xy 268.732 -74.0664) (xy 267.589 -75.2094) (xy 262.382 -75.2094) (xy 262.2804 -75.311) (xy 262.2804 -76.670154)
			(xy 262.4963 -76.886054) (xy 267.005054 -76.886054) (xy 267.208 -77.089) (xy 268.7828 -77.089)
		)
		(stroke
			(width 0)
			(type solid)
		)
		(fill yes)
		(layer "B.Cu")
		(net "P52V_HS1_VCC")
	)
	(gr_poly
		(pts
			(xy 180.894736 -74.4474) (xy 180.894736 -73.7108) (xy 179.802536 -72.6186) (xy 179.802536 -68.834)
			(xy 178.888136 -67.9196) (xy 178.888136 -66.1416) (xy 180.397404 -64.632332) (xy 180.397404 -59.13501)
			(xy 180.30063 -59.038236) (xy 178.710082 -59.038236) (xy 178.669442 -59.078876) (xy 178.669442 -60.16244)
			(xy 179.0954 -60.588398) (xy 179.0954 -60.6806) (xy 179.0954 -63.5762) (xy 179.0954 -64.189864) (xy 179.0954 -64.315086)
			(xy 178.557936 -64.85255) (xy 178.557936 -67.8942) (xy 178.278536 -68.1736) (xy 178.278536 -72.3392)
			(xy 178.557936 -72.6186) (xy 178.557936 -74.392536) (xy 178.6636 -74.4982) (xy 180.843936 -74.4982)
		)
		(stroke
			(width 0)
			(type solid)
		)
		(fill yes)
		(layer "B.Cu")
		(net "P52V_HS2_VCC")
	)
	(gr_poly
		(pts
			(xy 296.942002 -79.937102) (xy 296.942002 -78.56474) (xy 296.936414 -78.559152) (xy 295.889172 -78.559152)
			(xy 295.65727 -78.559152) (xy 295.615868 -78.559152) (xy 295.029382 -77.972666) (xy 295.029382 -77.931264)
			(xy 295.029382 -77.699362) (xy 295.029382 -74.495152) (xy 294.41775 -73.88352) (xy 294.41775 -73.1266)
			(xy 294.389556 -73.098406) (xy 294.164258 -73.098406) (xy 294.115744 -73.14692) (xy 294.115744 -73.855072)
			(xy 294.123364 -73.862692) (xy 294.123364 -74.0156) (xy 294.386 -74.278236) (xy 294.386 -76.99375)
			(xy 294.386 -77.052424) (xy 293.765224 -77.6732) (xy 293.765224 -78.06944) (xy 293.813484 -78.1177)
			(xy 293.858442 -78.1177) (xy 295.269666 -79.528924) (xy 295.69664 -79.955898) (xy 296.923206 -79.955898)
		)
		(stroke
			(width 0)
			(type solid)
		)
		(fill yes)
		(layer "B.Cu")
		(net "P52V_HS1_FB")
	)
	(gr_poly
		(pts
			(arc
				(start 81.713578 -16.002)
				(mid 81.354422 -16.002)
				(end 81.713578 -16.002)
			)
		)
		(stroke
			(width 0)
			(type solid)
		)
		(fill yes)
		(layer "B.Cu")
		(net "GND")
	)
	(gr_poly
		(pts
			(arc
				(start 82.475578 -19.558)
				(mid 82.116422 -19.558)
				(end 82.475578 -19.558)
			)
		)
		(stroke
			(width 0)
			(type solid)
		)
		(fill yes)
		(layer "B.Cu")
		(net "GND")
	)
	(gr_poly
		(pts
			(arc
				(start 162.993578 -66.421)
				(mid 162.634422 -66.421)
				(end 162.993578 -66.421)
			)
		)
		(stroke
			(width 0)
			(type solid)
		)
		(fill yes)
		(layer "B.Cu")
		(net "GND")
	)
	(gr_poly
		(pts
			(arc
				(start 167.565578 -72.136)
				(mid 167.206422 -72.136)
				(end 167.565578 -72.136)
			)
		)
		(stroke
			(width 0)
			(type solid)
		)
		(fill yes)
		(layer "B.Cu")
		(net "GND")
	)
	(gr_poly
		(pts
			(arc
				(start 223.826578 -93.853)
				(mid 223.467422 -93.853)
				(end 223.826578 -93.853)
			)
		)
		(stroke
			(width 0)
			(type solid)
		)
		(fill yes)
		(layer "B.Cu")
		(net "GND")
	)
	(gr_poly
		(pts
			(arc
				(start 279.960578 -68.199)
				(mid 279.601422 -68.199)
				(end 279.960578 -68.199)
			)
		)
		(stroke
			(width 0)
			(type solid)
		)
		(fill yes)
		(layer "B.Cu")
		(net "GND")
	)
	(gr_poly
		(pts
			(arc
				(start 284.278578 -71.882)
				(mid 283.919422 -71.882)
				(end 284.278578 -71.882)
			)
		)
		(stroke
			(width 0)
			(type solid)
		)
		(fill yes)
		(layer "B.Cu")
		(net "GND")
	)
	(gr_poly
		(pts
			(arc
				(start 378.639578 -21.336)
				(mid 378.280422 -21.336)
				(end 378.639578 -21.336)
			)
		)
		(stroke
			(width 0)
			(type solid)
		)
		(fill yes)
		(layer "B.Cu")
		(net "GND")
	)
	(gr_poly
		(pts
			(arc
				(start 432.258978 -45.339)
				(mid 431.899822 -45.339)
				(end 432.258978 -45.339)
			)
		)
		(stroke
			(width 0)
			(type solid)
		)
		(fill yes)
		(layer "B.Cu")
		(net "GND")
	)
	(gr_poly
		(pts
			(arc
				(start 435.027578 -38.862)
				(mid 434.668422 -38.862)
				(end 435.027578 -38.862)
			)
		)
		(stroke
			(width 0)
			(type solid)
		)
		(fill yes)
		(layer "B.Cu")
		(net "GND")
	)
	(gr_poly
		(pts
			(arc
				(start 448.108578 -28.702)
				(mid 447.749422 -28.702)
				(end 448.108578 -28.702)
			)
		)
		(stroke
			(width 0)
			(type solid)
		)
		(fill yes)
		(layer "B.Cu")
		(net "GND")
	)
	(gr_poly
		(pts
			(arc
				(start 448.235578 -27.178)
				(mid 447.876422 -27.178)
				(end 448.235578 -27.178)
			)
		)
		(stroke
			(width 0)
			(type solid)
		)
		(fill yes)
		(layer "B.Cu")
		(net "GND")
	)
	(gr_poly
		(pts
			(arc
				(start 450.648578 -30.734)
				(mid 450.289422 -30.734)
				(end 450.648578 -30.734)
			)
		)
		(stroke
			(width 0)
			(type solid)
		)
		(fill yes)
		(layer "B.Cu")
		(net "GND")
	)
	(gr_poly
		(pts
			(arc
				(start 468.682578 -105.791)
				(mid 468.323422 -105.791)
				(end 468.682578 -105.791)
			)
		)
		(stroke
			(width 0)
			(type solid)
		)
		(fill yes)
		(layer "B.Cu")
		(net "GND")
	)
	(gr_poly
		(pts
			(arc
				(start 469.444578 -110.998)
				(mid 469.085422 -110.998)
				(end 469.444578 -110.998)
			)
		)
		(stroke
			(width 0)
			(type solid)
		)
		(fill yes)
		(layer "B.Cu")
		(net "GND")
	)
	(gr_poly
		(pts
			(arc
				(start 192.663318 -50.927)
				(mid 192.682841 -50.923099)
				(end 192.699386 -50.912014)
			)
			(arc
				(start 193.018664 -50.592736)
				(mid 193.029775 -50.576202)
				(end 193.03365 -50.556668)
			)
			(arc
				(start 193.03365 -46.661832)
				(mid 193.029749 -46.642309)
				(end 193.018664 -46.625764)
			)
			(arc
				(start 189.714886 -43.321986)
				(mid 189.698352 -43.310875)
				(end 189.678818 -43.307)
			)
			(arc
				(start 186.101482 -43.307)
				(mid 186.081959 -43.310901)
				(end 186.065414 -43.321986)
			)
			(arc
				(start 182.666386 -46.721014)
				(mid 182.655275 -46.737548)
				(end 182.6514 -46.757082)
			)
			(arc
				(start 182.6514 -50.651918)
				(mid 182.655301 -50.671441)
				(end 182.666386 -50.687986)
			)
			(arc
				(start 182.890414 -50.912014)
				(mid 182.906948 -50.923125)
				(end 182.926482 -50.927)
			)
		)
		(stroke
			(width 0)
			(type solid)
		)
		(fill yes)
		(layer "B.Cu")
		(net "P52V_2_FUSE_1")
	)
	(gr_poly
		(pts
			(xy 180.365654 -56.8579) (xy 180.365654 -55.889144) (xy 180.053742 -55.577232) (xy 178.774852 -55.577232)
			(xy 177.949098 -54.751478) (xy 177.949098 -54.745636) (xy 176.848008 -54.745636) (xy 173.769782 -51.66741)
			(xy 172.350938 -51.66741) (xy 171.671488 -50.98796) (xy 171.671488 -43.334686) (xy 173.671738 -41.334436)
			(xy 192.02781 -41.334436) (xy 197.861174 -47.1678) (xy 209.698336 -47.1678)
			(arc
				(start 209.98815 -46.877986)
				(mid 209.999261 -46.861452)
				(end 210.003136 -46.841918)
			)
			(arc
				(start 210.003136 -30.047184)
				(mid 209.999235 -30.027661)
				(end 209.98815 -30.011116)
			)
			(arc
				(start 209.21345 -29.236416)
				(mid 209.196916 -29.225305)
				(end 209.177382 -29.22143)
			)
			(xy 161.90595 -29.22143) (xy 159.9184 -27.23388) (xy 159.9184 -16.2052) (xy 158.4452 -14.732) (xy 144.158716 -14.732)
			(xy 143.650716 -15.24) (xy 143.650716 -31.518606) (xy 143.925798 -31.793688) (xy 146.554952 -31.793688)
			(xy 147.722336 -32.961072) (xy 148.63572 -32.961072) (xy 148.988272 -33.313624) (xy 148.988272 -45.30979)
			(xy 159.294322 -55.61584) (xy 176.598072 -55.61584) (xy 177.929286 -56.947054) (xy 180.2765 -56.947054)
		)
		(stroke
			(width 0)
			(type solid)
		)
		(fill yes)
		(layer "B.Cu")
		(net "P52V_2")
	)
	(gr_poly
		(pts
			(xy 297.090592 -66.373756) (xy 302.052736 -66.373756) (xy 303.969166 -64.457326) (xy 303.969166 -46.886622)
			(xy 303.721516 -46.638972) (xy 299.458126 -46.638972) (xy 298.631864 -45.81271) (xy 298.631864 -33.31337)
			(xy 298.984162 -32.961072) (xy 303.936146 -32.961072) (xy 303.96942 -32.927798) (xy 303.96942 -14.53642)
			(xy 303.911 -14.478) (xy 281.331162 -14.478) (xy 279.484836 -16.324326) (xy 279.484836 -26.865072)
			(xy 277.128478 -29.22143)
			(arc
				(start 230.533956 -29.22143)
				(mid 230.514433 -29.225331)
				(end 230.497888 -29.236416)
			)
			(arc
				(start 230.011986 -29.722318)
				(mid 230.000875 -29.738852)
				(end 229.997 -29.758386)
			)
			(arc
				(start 229.997 -46.820836)
				(mid 230.000901 -46.840359)
				(end 230.011986 -46.856904)
			)
			(xy 230.246682 -47.0916) (xy 243.0018 -47.0916) (xy 248.777252 -41.316148) (xy 273.93011 -41.316148)
			(xy 275.948648 -43.334686) (xy 275.948648 -49.849532) (xy 276.742652 -50.643536) (xy 294.968676 -50.643536)
			(xy 295.920922 -51.595782) (xy 295.920922 -61.700156) (xy 296.6974 -62.476634) (xy 296.6974 -65.71996)
			(xy 296.082212 -66.335148) (xy 296.082212 -67.020694) (xy 296.11574 -67.054222) (xy 296.410126 -67.054222)
		)
		(stroke
			(width 0)
			(type solid)
		)
		(fill yes)
		(layer "B.Cu")
		(net "P52V_1")
	)
	(gr_poly
		(pts
			(xy 419.5572 -26.5176) (xy 419.5572 -25.527) (xy 421.59428 -23.48992) (xy 421.59428 -9.652) (xy 421.596058 -9.652)
			(xy 421.59428 -9.50214) (xy 421.59428 -3.23088) (xy 420.3954 -2.032) (xy 418.762688 -2.032) (xy 418.761672 -2.032254)
			(xy 418.70884 -2.03327) (xy 418.656008 -2.032254) (xy 418.654992 -2.032) (xy 413.682688 -2.032) (xy 413.681672 -2.032254)
			(xy 413.62884 -2.03327) (xy 413.576008 -2.032254) (xy 413.574992 -2.032) (xy 408.602688 -2.032) (xy 408.601672 -2.032254)
			(xy 408.54884 -2.03327) (xy 408.496008 -2.032254) (xy 408.494992 -2.032) (xy 403.522688 -2.032) (xy 403.521672 -2.032254)
			(xy 403.46884 -2.03327) (xy 403.416008 -2.032254) (xy 403.414992 -2.032) (xy 398.442688 -2.032) (xy 398.441672 -2.032254)
			(xy 398.38884 -2.03327) (xy 398.336008 -2.032254) (xy 398.334992 -2.032) (xy 393.362688 -2.032) (xy 393.361672 -2.032254)
			(xy 393.30884 -2.03327) (xy 393.256008 -2.032254) (xy 393.254992 -2.032) (xy 388.282688 -2.032) (xy 388.281672 -2.032254)
			(xy 388.22884 -2.03327) (xy 388.176008 -2.032254) (xy 388.174992 -2.032) (xy 383.202688 -2.032) (xy 383.201672 -2.032254)
			(xy 383.14884 -2.03327) (xy 383.096008 -2.032254) (xy 383.094992 -2.032)
			(arc
				(start 380.578614 -2.032)
				(mid 380.556285 -2.037295)
				(end 380.538482 -2.051812)
			)
			(xy 380.482094 -2.124964) (xy 380.477268 -2.14757)
			(arc
				(start 380.480316 -2.159254)
				(mid 379.685377 -4.071077)
				(end 377.629674 -3.824986)
			)
			(xy 377.620276 -3.816096) (xy 377.595892 -3.809238) (xy 377.487688 -3.833622) (xy 377.468638 -3.850386)
			(arc
				(start 377.464066 -3.862578)
				(mid 377.294825 -4.192685)
				(end 377.053856 -4.474718)
			)
			(xy 377.045982 -4.48183) (xy 377.0376 -4.500626)
			(arc
				(start 377.036076 -4.584192)
				(mid 377.039775 -4.604265)
				(end 377.051062 -4.621276)
			)
			(arc
				(start 380.034546 -7.60476)
				(mid 380.050992 -7.615686)
				(end 380.07036 -7.619492)
			)
			(xy 406.958292 -7.619492)
			(arc
				(start 415.208212 -15.869412)
				(mid 415.219323 -15.885946)
				(end 415.223198 -15.90548)
			)
			(xy 415.223198 -25.891998) (xy 416.0774 -26.7462) (xy 419.3286 -26.7462)
		)
		(stroke
			(width 0)
			(type solid)
		)
		(fill yes)
		(layer "B.Cu")
		(net "P12V_FAN_LED")
	)
	(gr_poly
		(pts
			(xy 391.88644 -169.87266) (xy 391.896506 -169.872228) (xy 391.915096 -169.864499) (xy 391.922508 -169.857674)
			(xy 392.292332 -169.48785) (xy 392.299178 -169.480452) (xy 392.306905 -169.461853) (xy 392.307318 -169.451782)
			(xy 392.307318 -164.263578) (xy 392.306891 -164.253509) (xy 392.299173 -164.234909) (xy 392.292332 -164.22751)
			(xy 391.858246 -163.793424) (xy 391.850846 -163.786584) (xy 391.832247 -163.778865) (xy 391.822178 -163.778438)
			(xy 387.392164 -163.778438) (xy 387.388862 -163.778946) (xy 387.34183 -163.784701) (xy 387.247267 -163.790842)
			(xy 387.152505 -163.790842) (xy 387.057942 -163.784701) (xy 387.01091 -163.778946) (xy 387.007608 -163.778438)
			(xy 362.849922 -163.778438) (xy 362.839859 -163.778876) (xy 362.821279 -163.786615) (xy 362.813854 -163.793424)
			(xy 362.332016 -164.275262) (xy 362.325178 -164.282663) (xy 362.317463 -164.301262) (xy 362.31703 -164.31133)
			(xy 362.31703 -167.684408) (xy 365.513862 -167.684408) (xy 365.513862 -167.57578) (xy 365.521791 -167.467442)
			(xy 365.537608 -167.359971) (xy 365.561227 -167.253942) (xy 365.592523 -167.14992) (xy 365.631328 -167.048459)
			(xy 365.677436 -166.950102) (xy 365.7306 -166.855373) (xy 365.790538 -166.764778) (xy 365.856928 -166.678799)
			(xy 365.929418 -166.597896) (xy 366.007619 -166.5225) (xy 366.091116 -166.453014) (xy 366.179462 -166.389807)
			(xy 366.272186 -166.333219) (xy 366.368794 -166.283549) (xy 366.468769 -166.241064) (xy 366.571579 -166.205991)
			(xy 366.676675 -166.178515) (xy 366.783496 -166.158784) (xy 366.891472 -166.146903) (xy 367.000028 -166.142936)
			(xy 367.108584 -166.146903) (xy 367.21656 -166.158784) (xy 367.323381 -166.178515) (xy 367.428477 -166.205991)
			(xy 367.531287 -166.241064) (xy 367.631262 -166.283549) (xy 367.72787 -166.333219) (xy 367.820594 -166.389807)
			(xy 367.90894 -166.453014) (xy 367.992437 -166.5225) (xy 368.070638 -166.597896) (xy 368.143128 -166.678799)
			(xy 368.209518 -166.764778) (xy 368.269456 -166.855373) (xy 368.32262 -166.950102) (xy 368.368728 -167.048459)
			(xy 368.407533 -167.14992) (xy 368.438829 -167.253942) (xy 368.462448 -167.359971) (xy 368.478265 -167.467442)
			(xy 368.486194 -167.57578) (xy 368.48669 -167.630094) (xy 368.486194 -167.684408) (xy 368.478265 -167.792746)
			(xy 368.462448 -167.900217) (xy 368.438829 -168.006246) (xy 368.407533 -168.110268) (xy 368.368728 -168.211729)
			(xy 368.32262 -168.310086) (xy 368.269456 -168.404815) (xy 368.209518 -168.49541) (xy 368.143128 -168.581389)
			(xy 368.070638 -168.662292) (xy 367.992437 -168.737688) (xy 367.90894 -168.807174) (xy 367.820594 -168.870381)
			(xy 367.72787 -168.926969) (xy 367.631262 -168.976639) (xy 367.531287 -169.019124) (xy 367.428477 -169.054197)
			(xy 367.323381 -169.081673) (xy 367.21656 -169.101404) (xy 367.108584 -169.113285) (xy 367.000028 -169.117252)
			(xy 366.891472 -169.113285) (xy 366.783496 -169.101404) (xy 366.676675 -169.081673) (xy 366.571579 -169.054197)
			(xy 366.468769 -169.019124) (xy 366.368794 -168.976639) (xy 366.272186 -168.926969) (xy 366.179462 -168.870381)
			(xy 366.091116 -168.807174) (xy 366.007619 -168.737688) (xy 365.929418 -168.662292) (xy 365.856928 -168.581389)
			(xy 365.790538 -168.49541) (xy 365.7306 -168.404815) (xy 365.677436 -168.310086) (xy 365.631328 -168.211729)
			(xy 365.592523 -168.110268) (xy 365.561227 -168.006246) (xy 365.537608 -167.900217) (xy 365.521791 -167.792746)
			(xy 365.513862 -167.684408) (xy 362.31703 -167.684408) (xy 362.31703 -169.364152) (xy 362.317463 -169.374217)
			(xy 362.325194 -169.392805) (xy 362.332016 -169.40022) (xy 362.78947 -169.857674) (xy 362.796871 -169.864512)
			(xy 362.81547 -169.872225) (xy 362.825538 -169.87266)
		)
		(stroke
			(width 0)
			(type solid)
		)
		(fill yes)
		(layer "B.Cu")
		(net "GND")
	)
	(gr_poly
		(pts
			(arc
				(start 148.314918 -100.457)
				(mid 148.334441 -100.453099)
				(end 148.350986 -100.442014)
			)
			(arc
				(start 155.941014 -92.851986)
				(mid 155.957548 -92.840875)
				(end 155.977082 -92.837)
			)
			(arc
				(start 159.871918 -92.837)
				(mid 159.891441 -92.840901)
				(end 159.907986 -92.851986)
			)
			(xy 164.71265 -97.65665)
			(arc
				(start 195.528692 -97.65665)
				(mid 195.548215 -97.652749)
				(end 195.56476 -97.641664)
			)
			(arc
				(start 209.440526 -83.765898)
				(mid 209.454861 -83.738117)
				(end 209.450178 -83.707224)
			)
			(arc
				(start 209.448146 -83.703414)
				(mid 209.13059 -83.740522)
				(end 208.811114 -83.752944)
			)
			(arc
				(start 208.810098 -83.752944)
				(mid 204.68209 -79.624936)
				(end 208.810098 -75.496928)
			)
			(arc
				(start 208.810098 -75.496928)
				(mid 209.413093 -75.541244)
				(end 210.003136 -75.673204)
			)
			(xy 210.003136 -55.328566) (xy 209.583528 -54.908958) (xy 182.75681 -54.908958) (xy 182.558182 -55.107586)
			(xy 182.558182 -59.0931) (xy 182.77332 -59.308238) (xy 187.487052 -59.308238) (xy 187.9854 -59.806586)
			(xy 187.9854 -79.0956) (xy 178.017932 -89.063068)
			(arc
				(start 169.791126 -89.063068)
				(mid 169.774592 -89.074179)
				(end 169.755058 -89.078054)
			)
			(arc
				(start 161.971482 -89.078054)
				(mid 161.290322 -89.309339)
				(end 160.575244 -89.38768)
			)
			(arc
				(start 160.575244 -89.38768)
				(mid 159.860165 -89.309346)
				(end 159.179006 -89.078054)
			)
			(arc
				(start 155.635706 -89.078054)
				(mid 155.616183 -89.074153)
				(end 155.599638 -89.063068)
			)
			(arc
				(start 155.551378 -89.063068)
				(mid 155.531855 -89.059167)
				(end 155.51531 -89.048082)
			)
			(xy 151.866092 -85.398864)
			(arc
				(start 106.146346 -85.398864)
				(mid 106.126823 -85.394963)
				(end 106.110278 -85.383878)
			)
			(arc
				(start 103.164386 -82.437986)
				(mid 103.147852 -82.426875)
				(end 103.128318 -82.423)
			)
			(arc
				(start 97.328482 -82.423)
				(mid 97.308959 -82.426901)
				(end 97.292414 -82.437986)
			)
			(arc
				(start 88.305386 -91.425014)
				(mid 88.294275 -91.441548)
				(end 88.2904 -91.461082)
			)
			(arc
				(start 88.2904 -100.689918)
				(mid 88.294301 -100.709441)
				(end 88.305386 -100.725986)
			)
			(arc
				(start 88.910414 -101.331014)
				(mid 88.926948 -101.342125)
				(end 88.946482 -101.346)
			)
			(xy 116.564918 -101.346) (xy 147.425918 -101.346)
		)
		(stroke
			(width 0)
			(type solid)
		)
		(fill yes)
		(layer "B.Cu")
		(net "GND")
	)
	(gr_poly
		(pts
			(xy 293.677086 -79.658972) (xy 293.677086 -78.24216) (xy 293.523924 -78.088998) (xy 293.523924 -76.639928)
			(xy 293.443406 -76.55941) (xy 293.097458 -76.55941) (xy 293.08933 -76.567538) (xy 292.196012 -75.67422)
			(xy 292.196012 -74.131932) (xy 292.434772 -73.893172) (xy 292.434772 -72.88657) (xy 292.490906 -72.830436)
			(xy 294.13327 -72.830436) (xy 294.48506 -72.478646) (xy 294.48506 -67.404996) (xy 294.464994 -67.38493)
			(xy 292.99027 -67.38493) (xy 292.92931 -67.32397) (xy 292.92931 -65.8368) (xy 293.44747 -65.31864)
			(xy 293.786306 -65.31864) (xy 294.3479 -64.757046) (xy 294.3479 -61.8109) (xy 294.1574 -61.6204)
			(xy 294.1574 -59.177682) (xy 293.789862 -58.810144) (xy 281.964892 -58.810144) (xy 277.198328 -54.04358)
			(xy 268.15415 -54.04358) (xy 267.718286 -54.479444) (xy 267.718286 -62.956694) (xy 268.867382 -62.956694)
			(xy 269.267686 -62.55639) (xy 269.267686 -62.301374) (xy 268.578584 -61.61278) (xy 268.578584 -57.192164)
			(xy 269.099538 -56.67121) (xy 273.634962 -56.67121) (xy 273.935952 -56.9722) (xy 273.935952 -61.754766)
			(xy 273.613372 -62.077346) (xy 272.474182 -62.077346) (xy 272.38833 -62.163198) (xy 272.38833 -63.259462)
			(xy 272.495772 -63.366904) (xy 274.78482 -63.366904) (xy 277.439374 -60.71235) (xy 280.072338 -60.71235)
			(xy 280.48077 -61.120782) (xy 280.48077 -63.399416) (xy 280.309066 -63.57112) (xy 278.52497 -63.57112)
			(xy 278.482044 -63.614046) (xy 278.482044 -64.087248) (xy 278.535638 -64.140842) (xy 280.298906 -64.140842)
			(xy 280.449274 -64.29121) (xy 280.449274 -70.083934) (xy 280.309574 -70.223634) (xy 278.203152 -70.223634)
			(xy 278.160226 -70.26656) (xy 278.160226 -70.965314) (xy 278.23541 -71.040498) (xy 279.267158 -71.040498)
			(xy 279.385268 -71.158608) (xy 279.385268 -72.620124) (xy 279.41778 -72.652636) (xy 281.720036 -72.652636)
			(xy 281.8384 -72.771) (xy 281.8384 -74.168) (xy 281.7114 -74.295) (xy 278.947118 -74.295) (xy 278.915876 -74.326242)
			(xy 278.915876 -75.184) (xy 282.065728 -75.184) (xy 282.069801 -75.128341) (xy 282.081936 -75.073868)
			(xy 282.101872 -75.021742) (xy 282.129186 -74.973074) (xy 282.163294 -74.928902) (xy 282.203471 -74.890167)
			(xy 282.248859 -74.857695) (xy 282.298491 -74.832177) (xy 282.351311 -74.814158) (xy 282.40619 -74.804021)
			(xy 282.461961 -74.801983) (xy 282.517435 -74.808086) (xy 282.571428 -74.822202) (xy 282.622791 -74.844029)
			(xy 282.670429 -74.873102) (xy 282.713325 -74.908801) (xy 282.750567 -74.950365) (xy 282.781361 -74.996909)
			(xy 282.805049 -75.04744) (xy 282.821127 -75.100882) (xy 282.829253 -75.156096) (xy 282.829762 -75.184)
			(xy 282.829253 -75.211904) (xy 282.821127 -75.267118) (xy 282.805049 -75.32056) (xy 282.781361 -75.371091)
			(xy 282.750567 -75.417635) (xy 282.713325 -75.459199) (xy 282.670429 -75.494898) (xy 282.622791 -75.523971)
			(xy 282.571428 -75.545798) (xy 282.517435 -75.559914) (xy 282.461961 -75.566017) (xy 282.40619 -75.563979)
			(xy 282.351311 -75.553842) (xy 282.298491 -75.535823) (xy 282.248859 -75.510305) (xy 282.203471 -75.477833)
			(xy 282.163294 -75.439098) (xy 282.129186 -75.394926) (xy 282.101872 -75.346258) (xy 282.081936 -75.294132)
			(xy 282.069801 -75.239659) (xy 282.065728 -75.184) (xy 278.915876 -75.184) (xy 278.915876 -75.782932)
			(xy 278.950674 -75.81773) (xy 281.288236 -75.81773) (xy 282.083764 -76.613258) (xy 284.920944 -76.613258)
			(xy 285.028386 -76.505816) (xy 285.028386 -75.076304) (xy 284.308296 -74.356214) (xy 284.308296 -72.517)
			(xy 284.18917 -72.397874) (xy 284.166808 -72.401548) (xy 284.12166 -72.40549) (xy 284.099 -72.405748)
			(xy 284.066081 -72.405231) (xy 284.000762 -72.39698) (xy 283.936993 -72.380607) (xy 283.875778 -72.35637)
			(xy 283.818084 -72.324652) (xy 283.76482 -72.285954) (xy 283.716827 -72.240885) (xy 283.67486 -72.190156)
			(xy 283.639582 -72.134567) (xy 283.61155 -72.074995) (xy 283.591205 -72.01238) (xy 283.578868 -71.947708)
			(xy 283.574734 -71.882) (xy 283.578868 -71.816292) (xy 283.591205 -71.75162) (xy 283.61155 -71.689005)
			(xy 283.639582 -71.629433) (xy 283.67486 -71.573844) (xy 283.716827 -71.523115) (xy 283.76482 -71.478046)
			(xy 283.818084 -71.439348) (xy 283.875778 -71.40763) (xy 283.936993 -71.383393) (xy 284.000762 -71.36702)
			(xy 284.066081 -71.358769) (xy 284.099 -71.358252) (xy 284.131076 -71.358704) (xy 284.194756 -71.36647)
			(xy 284.226 -71.373746) (xy 284.44317 -71.373746) (xy 284.811978 -71.004938) (xy 285.746698 -71.004938)
			(xy 285.795974 -70.955662) (xy 285.795974 -70.554342) (xy 285.721552 -70.47992) (xy 284.877764 -70.47992)
			(xy 284.763464 -70.36562) (xy 284.763464 -68.39331) (xy 284.960568 -68.196206) (xy 285.750254 -68.196206)
			(xy 285.78302 -68.16344) (xy 285.78302 -66.398648) (xy 285.71444 -66.330068) (xy 284.842458 -66.330068)
			(xy 284.635194 -66.122804) (xy 284.635194 -64.205612) (xy 283.924756 -63.495174) (xy 283.924756 -62.246002)
			(xy 284.12567 -62.045088) (xy 284.12567 -61.64326) (xy 285.050484 -60.718446) (xy 292.698678 -60.718446)
			(xy 292.96741 -60.987178) (xy 292.96741 -61.626496) (xy 293.633906 -62.292992) (xy 293.633906 -64.554608)
			(xy 292.607746 -65.580768) (xy 292.607746 -67.343782) (xy 292.565582 -67.385946) (xy 290.814506 -67.385946)
			(xy 290.785804 -67.414648) (xy 290.785804 -72.784716) (xy 290.838382 -72.837294) (xy 291.571934 -72.837294)
			(xy 291.611304 -72.876664) (xy 291.611304 -76.140056) (xy 292.871906 -77.400658) (xy 292.871906 -79.659226)
			(xy 292.912038 -79.699358) (xy 293.6367 -79.699358)
		)
		(stroke
			(width 0)
			(type solid)
		)
		(fill yes)
		(layer "B.Cu")
		(net "GND_FIELD_SIGNAL")
	)
	(gr_poly
		(pts
			(xy 216.949528 -7.298944)
			(arc
				(start 216.95156 -7.279132)
				(mid 217.614859 -5.925703)
				(end 219.001848 -5.335778)
			)
			(arc
				(start 219.001848 -5.335778)
				(mid 219.01556 -5.333175)
				(end 219.02801 -5.326888)
			)
			(arc
				(start 219.02801 -5.326888)
				(mid 219.607515 -5.048157)
				(end 220.2434 -4.952492)
			)
			(arc
				(start 220.2434 -4.952492)
				(mid 220.867575 -5.04474)
				(end 221.43847 -5.313426)
			)
			(arc
				(start 221.43847 -5.313426)
				(mid 221.453672 -5.320099)
				(end 221.47022 -5.321554)
			)
			(arc
				(start 221.47022 -5.321554)
				(mid 221.546754 -5.31753)
				(end 221.623382 -5.31622)
			)
			(arc
				(start 221.623382 -5.31622)
				(mid 223.079128 -5.880649)
				(end 223.774 -7.278878)
			)
			(xy 223.775778 -7.29869) (xy 223.80448 -7.324852)
			(arc
				(start 361.46105 -7.324852)
				(mid 361.480407 -7.321019)
				(end 361.496864 -7.31012)
			)
			(arc
				(start 361.810554 -6.99643)
				(mid 361.821665 -6.979896)
				(end 361.82554 -6.960362)
			)
			(arc
				(start 361.82554 -3.894582)
				(mid 361.829441 -3.875059)
				(end 361.840526 -3.858514)
			)
			(xy 361.861608 -3.837432) (xy 361.869228 -3.820922)
			(arc
				(start 361.869736 -3.811778)
				(mid 363.158768 -2.277577)
				(end 365.022892 -3.012948)
			)
			(arc
				(start 365.022892 -3.012948)
				(mid 365.051326 -3.034095)
				(end 365.086646 -3.03149)
			)
			(arc
				(start 365.086646 -3.03149)
				(mid 365.591166 -2.863343)
				(end 366.119918 -2.806446)
			)
			(arc
				(start 366.119918 -2.806446)
				(mid 366.764286 -2.891424)
				(end 367.364518 -3.14071)
			)
			(arc
				(start 367.364518 -3.14071)
				(mid 367.389918 -3.147523)
				(end 367.415318 -3.14071)
			)
			(arc
				(start 367.415318 -3.14071)
				(mid 368.015563 -2.891469)
				(end 368.659918 -2.806446)
			)
			(arc
				(start 368.659918 -2.806446)
				(mid 368.912694 -2.819395)
				(end 369.162838 -2.858008)
			)
			(xy 369.174268 -2.860294) (xy 369.196112 -2.85496)
			(arc
				(start 369.266216 -2.79781)
				(mid 369.280027 -2.78024)
				(end 369.285012 -2.75844)
			)
			(arc
				(start 369.285012 -1.221994)
				(mid 369.281111 -1.202471)
				(end 369.270026 -1.185926)
			)
			(arc
				(start 369.047776 -0.963676)
				(mid 369.031242 -0.952565)
				(end 369.011708 -0.94869)
			)
			(arc
				(start 82.407252 -0.94869)
				(mid 82.387729 -0.952591)
				(end 82.371184 -0.963676)
			)
			(arc
				(start 81.897474 -1.437386)
				(mid 81.886363 -1.45392)
				(end 81.882488 -1.473454)
			)
			(arc
				(start 81.882488 -6.896608)
				(mid 81.886389 -6.916131)
				(end 81.897474 -6.932676)
			)
			(arc
				(start 82.274918 -7.31012)
				(mid 82.291364 -7.321046)
				(end 82.310732 -7.324852)
			)
			(xy 216.920826 -7.324852)
		)
		(stroke
			(width 0)
			(type solid)
		)
		(fill yes)
		(layer "B.Cu")
		(net "P52V_FAN")
	)
	(gr_poly
		(pts
			(xy 254.613918 -96.52) (xy 254.623987 -96.519573) (xy 254.642586 -96.511854) (xy 254.649986 -96.505014)
			(xy 257.541014 -93.613986) (xy 257.547868 -93.606591) (xy 257.55561 -93.587992) (xy 257.556 -93.577918)
			(xy 257.556 -62.505082) (xy 257.555573 -62.495013) (xy 257.547854 -62.476414) (xy 257.541014 -62.469014)
			(xy 257.541014 -55.026306) (xy 257.540593 -55.016235) (xy 257.532881 -54.997628) (xy 257.526028 -54.990238)
			(xy 257.255264 -54.719474) (xy 257.247867 -54.712625) (xy 257.229268 -54.704892) (xy 257.219196 -54.704488)
			(xy 230.364538 -54.704488) (xy 230.354473 -54.704922) (xy 230.335883 -54.712651) (xy 230.32847 -54.719474)
			(xy 230.011986 -55.035958) (xy 230.005139 -55.043356) (xy 229.997413 -55.061955) (xy 229.997 -55.072026)
			(xy 229.997 -79.624936) (xy 234.681532 -79.624936) (xy 234.685517 -79.443595) (xy 234.697463 -79.262603)
			(xy 234.717347 -79.082311) (xy 234.745131 -78.903067) (xy 234.780762 -78.725215) (xy 234.82417 -78.549101)
			(xy 234.875272 -78.375063) (xy 234.93397 -78.203438) (xy 235.000149 -78.034557) (xy 235.073682 -77.868745)
			(xy 235.154427 -77.706324) (xy 235.242229 -77.547605) (xy 235.336918 -77.392897) (xy 235.43831 -77.242497)
			(xy 235.546211 -77.096696) (xy 235.660412 -76.955775) (xy 235.780693 -76.820006) (xy 235.906821 -76.689652)
			(xy 236.038553 -76.564963) (xy 236.175635 -76.446181) (xy 236.317802 -76.333535) (xy 236.464779 -76.227242)
			(xy 236.616284 -76.127508) (xy 236.772023 -76.034524) (xy 236.931696 -75.948471) (xy 237.094995 -75.869515)
			(xy 237.261604 -75.797807) (xy 237.431202 -75.733487) (xy 237.603462 -75.676679) (xy 237.77805 -75.627491)
			(xy 237.954631 -75.58602) (xy 238.132863 -75.552345) (xy 238.312402 -75.526531) (xy 238.492901 -75.508629)
			(xy 238.674013 -75.498671) (xy 238.855387 -75.496679) (xy 239.036674 -75.502655) (xy 239.217523 -75.516589)
			(xy 239.397586 -75.538452) (xy 239.576514 -75.568204) (xy 239.753963 -75.605786) (xy 239.92959 -75.651126)
			(xy 240.103056 -75.704137) (xy 240.274026 -75.764716) (xy 240.442171 -75.832746) (xy 240.607164 -75.908096)
			(xy 240.768689 -75.990621) (xy 240.926433 -76.080161) (xy 241.080092 -76.176543) (xy 241.229369 -76.279581)
			(xy 241.373976 -76.389077) (xy 241.513634 -76.504819) (xy 241.648074 -76.626584) (xy 241.777035 -76.754136)
			(xy 241.900269 -76.88723) (xy 242.017538 -77.025608) (xy 242.128616 -77.169004) (xy 242.233288 -77.31714)
			(xy 242.331352 -77.469731) (xy 242.422619 -77.626482) (xy 242.506913 -77.787091) (xy 242.584071 -77.951247)
			(xy 242.653944 -78.118634) (xy 242.716398 -78.288928) (xy 242.77131 -78.461801) (xy 242.818577 -78.63692)
			(xy 242.858106 -78.813945) (xy 242.889821 -78.992536) (xy 242.892475 -79.012554) (xy 248.106928 -79.012554)
			(xy 248.106928 -78.952586) (xy 248.114756 -78.89313) (xy 248.130277 -78.835205) (xy 248.153226 -78.779801)
			(xy 248.18321 -78.727867) (xy 248.219716 -78.680291) (xy 248.262121 -78.637886) (xy 248.309697 -78.60138)
			(xy 248.361631 -78.571396) (xy 248.417035 -78.548447) (xy 248.47496 -78.532926) (xy 248.534416 -78.525098)
			(xy 248.594384 -78.525098) (xy 248.65384 -78.532926) (xy 248.711765 -78.548447) (xy 248.767169 -78.571396)
			(xy 248.819103 -78.60138) (xy 248.866679 -78.637886) (xy 248.909084 -78.680291) (xy 248.94559 -78.727867)
			(xy 248.975574 -78.779801) (xy 248.998523 -78.835205) (xy 249.014044 -78.89313) (xy 249.021872 -78.952586)
			(xy 249.022362 -78.98257) (xy 249.021872 -79.012554) (xy 249.014044 -79.07201) (xy 248.998523 -79.129935)
			(xy 248.975574 -79.185339) (xy 248.94559 -79.237273) (xy 248.909084 -79.284849) (xy 248.866679 -79.327254)
			(xy 248.819103 -79.36376) (xy 248.767169 -79.393744) (xy 248.711765 -79.416693) (xy 248.65384 -79.432214)
			(xy 248.594384 -79.440042) (xy 248.534416 -79.440042) (xy 248.47496 -79.432214) (xy 248.417035 -79.416693)
			(xy 248.361631 -79.393744) (xy 248.309697 -79.36376) (xy 248.262121 -79.327254) (xy 248.219716 -79.284849)
			(xy 248.18321 -79.237273) (xy 248.153226 -79.185339) (xy 248.130277 -79.129935) (xy 248.114756 -79.07201)
			(xy 248.106928 -79.012554) (xy 242.892475 -79.012554) (xy 242.913662 -79.172348) (xy 242.929581 -79.353033)
			(xy 242.937548 -79.534243) (xy 242.938046 -79.624936) (xy 242.937548 -79.715629) (xy 242.929581 -79.896839)
			(xy 242.913662 -80.077524) (xy 242.889821 -80.257336) (xy 242.858106 -80.435927) (xy 242.818577 -80.612952)
			(xy 242.77131 -80.788071) (xy 242.716398 -80.960944) (xy 242.653944 -81.131238) (xy 242.584071 -81.298625)
			(xy 242.506913 -81.462781) (xy 242.422619 -81.62339) (xy 242.331352 -81.780141) (xy 242.233288 -81.932732)
			(xy 242.128616 -82.080868) (xy 242.017538 -82.224264) (xy 241.900269 -82.362642) (xy 241.777035 -82.495736)
			(xy 241.648074 -82.623288) (xy 241.513634 -82.745053) (xy 241.373976 -82.860795) (xy 241.229369 -82.970291)
			(xy 241.080092 -83.073329) (xy 240.926433 -83.169711) (xy 240.768689 -83.259251) (xy 240.607164 -83.341776)
			(xy 240.442171 -83.417126) (xy 240.274026 -83.485156) (xy 240.103056 -83.545735) (xy 239.92959 -83.598746)
			(xy 239.753963 -83.644086) (xy 239.576514 -83.681668) (xy 239.397586 -83.71142) (xy 239.217523 -83.733283)
			(xy 239.036674 -83.747217) (xy 238.855387 -83.753193) (xy 238.674013 -83.751201) (xy 238.492901 -83.741243)
			(xy 238.312402 -83.723341) (xy 238.132863 -83.697527) (xy 237.954631 -83.663852) (xy 237.77805 -83.622381)
			(xy 237.603462 -83.573193) (xy 237.431202 -83.516385) (xy 237.261604 -83.452065) (xy 237.094995 -83.380357)
			(xy 236.931696 -83.301401) (xy 236.772023 -83.215348) (xy 236.616284 -83.122364) (xy 236.464779 -83.02263)
			(xy 236.317802 -82.916337) (xy 236.175635 -82.803691) (xy 236.038553 -82.684909) (xy 235.906821 -82.56022)
			(xy 235.780693 -82.429866) (xy 235.660412 -82.294097) (xy 235.546211 -82.153176) (xy 235.43831 -82.007375)
			(xy 235.336918 -81.856975) (xy 235.242229 -81.702267) (xy 235.154427 -81.543548) (xy 235.073682 -81.381127)
			(xy 235.000149 -81.215315) (xy 234.93397 -81.046434) (xy 234.875272 -80.874809) (xy 234.82417 -80.700771)
			(xy 234.780762 -80.524657) (xy 234.745131 -80.346805) (xy 234.717347 -80.167561) (xy 234.697463 -79.987269)
			(xy 234.685517 -79.806277) (xy 234.681532 -79.624936) (xy 229.997 -79.624936) (xy 229.997 -81.4832)
			(xy 245.0338 -96.52)
		)
		(stroke
			(width 0)
			(type solid)
		)
		(fill yes)
		(layer "B.Cu")
		(net "GND")
	)
	(gr_poly
		(pts
			(xy 20.00377 -104.544876) (xy 20.003269 -104.444746) (xy 19.995257 -104.244646) (xy 19.979245 -104.045027)
			(xy 19.955259 -103.846208) (xy 19.923338 -103.648509) (xy 19.883533 -103.452244) (xy 19.835907 -103.25773)
			(xy 19.780536 -103.065276) (xy 19.71751 -102.875193) (xy 19.64693 -102.687783) (xy 19.568907 -102.503347)
			(xy 19.483568 -102.32218) (xy 19.391049 -102.144573) (xy 19.291498 -101.970809) (xy 19.185074 -101.801168)
			(xy 19.071948 -101.63592) (xy 18.952302 -101.475331) (xy 18.826326 -101.319658) (xy 18.694222 -101.169149)
			(xy 18.556203 -101.024047) (xy 18.412488 -100.884583) (xy 18.263309 -100.75098) (xy 18.108904 -100.623453)
			(xy 17.94952 -100.502205) (xy 17.785412 -100.387432) (xy 17.616844 -100.279317) (xy 17.444086 -100.178032)
			(xy 17.267413 -100.08374) (xy 17.087109 -99.996593) (xy 16.903463 -99.916729) (xy 16.716768 -99.844277)
			(xy 16.527325 -99.779352) (xy 16.335435 -99.722059) (xy 16.141407 -99.672489) (xy 15.94555 -99.630722)
			(xy 15.74818 -99.596825) (xy 15.549611 -99.570851) (xy 15.350162 -99.552843) (xy 15.150153 -99.542829)
			(xy 14.949902 -99.540825) (xy 14.749732 -99.546835) (xy 14.549963 -99.560849) (xy 14.350915 -99.582845)
			(xy 14.152905 -99.612786) (xy 13.956253 -99.650626) (xy 13.761271 -99.696304) (xy 13.568274 -99.749746)
			(xy 13.377569 -99.810867) (xy 13.189462 -99.879569) (xy 13.004255 -99.955742) (xy 12.822243 -100.039265)
			(xy 12.643719 -100.130002) (xy 12.468968 -100.22781) (xy 12.298271 -100.332531) (xy 12.1319 -100.443998)
			(xy 11.970122 -100.562032) (xy 11.813196 -100.686444) (xy 11.661373 -100.817035) (xy 11.514897 -100.953596)
			(xy 11.374002 -101.095908) (xy 11.238913 -101.243743) (xy 11.109848 -101.396865) (xy 10.987012 -101.555027)
			(xy 10.870602 -101.717978) (xy 10.760806 -101.885456) (xy 10.657798 -102.057193) (xy 10.561743 -102.232913)
			(xy 10.472796 -102.412336) (xy 10.391099 -102.595174) (xy 10.316783 -102.781135) (xy 10.249966 -102.969919)
			(xy 10.190756 -103.161226) (xy 10.139247 -103.354749) (xy 10.095523 -103.550177) (xy 10.059652 -103.747199)
			(xy 10.031693 -103.945498) (xy 10.01169 -104.144756) (xy 9.999676 -104.344656) (xy 9.995669 -104.544876)
			(xy 12.482326 -104.544876) (xy 12.486358 -104.40244) (xy 12.498442 -104.260461) (xy 12.51854 -104.119392)
			(xy 12.546586 -103.979686) (xy 12.582491 -103.841791) (xy 12.62614 -103.706148) (xy 12.677393 -103.573192)
			(xy 12.736086 -103.443349) (xy 12.802031 -103.317034) (xy 12.875016 -103.194652) (xy 12.954809 -103.076595)
			(xy 13.041153 -102.963241) (xy 13.133771 -102.854954) (xy 13.232367 -102.752081) (xy 13.336626 -102.65495)
			(xy 13.446213 -102.563873) (xy 13.560777 -102.479142) (xy 13.679951 -102.401028) (xy 13.803353 -102.329782)
			(xy 13.930589 -102.265631) (xy 14.06125 -102.208781) (xy 14.194918 -102.159415) (xy 14.331165 -102.11769)
			(xy 14.469554 -102.083739) (xy 14.609643 -102.057673) (xy 14.750982 -102.039574) (xy 14.893118 -102.0295)
			(xy 15.035597 -102.027484) (xy 15.177961 -102.033531) (xy 15.319756 -102.047623) (xy 15.460526 -102.069715)
			(xy 15.59982 -102.099735) (xy 15.737194 -102.137588) (xy 15.872205 -102.183152) (xy 16.004423 -102.236282)
			(xy 16.133423 -102.296806) (xy 16.258792 -102.364532) (xy 16.380129 -102.439242) (xy 16.497045 -102.520697)
			(xy 16.609165 -102.608636) (xy 16.716131 -102.702778) (xy 16.817599 -102.80282) (xy 16.913244 -102.908443)
			(xy 17.002761 -103.019307) (xy 17.085863 -103.135059) (xy 17.162282 -103.255326) (xy 17.231775 -103.379724)
			(xy 17.294119 -103.507855) (xy 17.349114 -103.639308) (xy 17.396585 -103.773661) (xy 17.436378 -103.910485)
			(xy 17.468366 -104.049341) (xy 17.492447 -104.189784) (xy 17.508545 -104.331365) (xy 17.516606 -104.47363)
			(xy 17.51711 -104.544876) (xy 17.516606 -104.616122) (xy 17.508545 -104.758387) (xy 17.492447 -104.899968)
			(xy 17.468366 -105.040411) (xy 17.436378 -105.179267) (xy 17.396585 -105.316091) (xy 17.349114 -105.450444)
			(xy 17.294119 -105.581897) (xy 17.231775 -105.710028) (xy 17.162282 -105.834426) (xy 17.085863 -105.954693)
			(xy 17.002761 -106.070445) (xy 16.913244 -106.181309) (xy 16.817599 -106.286932) (xy 16.716131 -106.386974)
			(xy 16.609165 -106.481116) (xy 16.497045 -106.569055) (xy 16.380129 -106.65051) (xy 16.258792 -106.72522)
			(xy 16.133423 -106.792946) (xy 16.004423 -106.85347) (xy 15.872205 -106.9066) (xy 15.737194 -106.952164)
			(xy 15.59982 -106.990017) (xy 15.460526 -107.020037) (xy 15.319756 -107.042129) (xy 15.177961 -107.056221)
			(xy 15.035597 -107.062268) (xy 14.893118 -107.060252) (xy 14.750982 -107.050178) (xy 14.609643 -107.032079)
			(xy 14.469554 -107.006013) (xy 14.331165 -106.972062) (xy 14.194918 -106.930337) (xy 14.06125 -106.880971)
			(xy 13.930589 -106.824121) (xy 13.803353 -106.75997) (xy 13.679951 -106.688724) (xy 13.560777 -106.61061)
			(xy 13.446213 -106.525879) (xy 13.336626 -106.434802) (xy 13.232367 -106.337671) (xy 13.133771 -106.234798)
			(xy 13.041153 -106.126511) (xy 12.954809 -106.013157) (xy 12.875016 -105.8951) (xy 12.802031 -105.772718)
			(xy 12.736086 -105.646403) (xy 12.677393 -105.51656) (xy 12.62614 -105.383604) (xy 12.582491 -105.247961)
			(xy 12.546586 -105.110066) (xy 12.51854 -104.97036) (xy 12.498442 -104.829291) (xy 12.486358 -104.687312)
			(xy 12.482326 -104.544876) (xy 9.995669 -104.544876) (xy 9.999676 -104.745096) (xy 10.01169 -104.944996)
			(xy 10.031693 -105.144254) (xy 10.059652 -105.342553) (xy 10.095523 -105.539575) (xy 10.139247 -105.735003)
			(xy 10.190756 -105.928526) (xy 10.249966 -106.119833) (xy 10.316783 -106.308617) (xy 10.391099 -106.494578)
			(xy 10.472796 -106.677416) (xy 10.561743 -106.856839) (xy 10.657798 -107.032559) (xy 10.760806 -107.204296)
			(xy 10.870602 -107.371774) (xy 10.987012 -107.534725) (xy 11.109848 -107.692887) (xy 11.238913 -107.846009)
			(xy 11.374002 -107.993844) (xy 11.514897 -108.136156) (xy 11.661373 -108.272717) (xy 11.813196 -108.403308)
			(xy 11.970122 -108.52772) (xy 12.1319 -108.645754) (xy 12.298271 -108.757221) (xy 12.468968 -108.861942)
			(xy 12.643719 -108.95975) (xy 12.822243 -109.050487) (xy 13.004255 -109.13401) (xy 13.189462 -109.210183)
			(xy 13.377569 -109.278885) (xy 13.568274 -109.340006) (xy 13.761271 -109.393448) (xy 13.956253 -109.439126)
			(xy 14.152905 -109.476966) (xy 14.350915 -109.506907) (xy 14.549963 -109.528903) (xy 14.749732 -109.542917)
			(xy 14.949902 -109.548927) (xy 15.150153 -109.546923) (xy 15.350162 -109.536909) (xy 15.549611 -109.518901)
			(xy 15.74818 -109.492927) (xy 15.94555 -109.45903) (xy 16.141407 -109.417263) (xy 16.335435 -109.367693)
			(xy 16.527325 -109.3104) (xy 16.716768 -109.245475) (xy 16.903463 -109.173023) (xy 17.087109 -109.093159)
			(xy 17.267413 -109.006012) (xy 17.444086 -108.91172) (xy 17.616844 -108.810435) (xy 17.785412 -108.70232)
			(xy 17.94952 -108.587547) (xy 18.108904 -108.466299) (xy 18.263309 -108.338772) (xy 18.412488 -108.205169)
			(xy 18.556203 -108.065705) (xy 18.694222 -107.920603) (xy 18.826326 -107.770094) (xy 18.952302 -107.614421)
			(xy 19.071948 -107.453832) (xy 19.185074 -107.288584) (xy 19.291498 -107.118943) (xy 19.391049 -106.945179)
			(xy 19.483568 -106.767572) (xy 19.568907 -106.586405) (xy 19.64693 -106.401969) (xy 19.71751 -106.214559)
			(xy 19.780536 -106.024476) (xy 19.835907 -105.832022) (xy 19.883533 -105.637508) (xy 19.923338 -105.441243)
			(xy 19.955259 -105.243544) (xy 19.979245 -105.044725) (xy 19.995257 -104.845106) (xy 20.003269 -104.645006)
		)
		(stroke
			(width 0)
			(type solid)
		)
		(fill yes)
		(layer "B.Cu")
		(net "GND")
	)
	(gr_poly
		(pts
			(xy 20.00377 -60.099956) (xy 20.003269 -59.999826) (xy 19.995257 -59.799726) (xy 19.979245 -59.600107)
			(xy 19.955259 -59.401288) (xy 19.923338 -59.203589) (xy 19.883533 -59.007324) (xy 19.835907 -58.81281)
			(xy 19.780536 -58.620356) (xy 19.71751 -58.430273) (xy 19.64693 -58.242863) (xy 19.568907 -58.058427)
			(xy 19.483568 -57.87726) (xy 19.391049 -57.699653) (xy 19.291498 -57.525889) (xy 19.185074 -57.356248)
			(xy 19.071948 -57.191) (xy 18.952302 -57.030411) (xy 18.826326 -56.874738) (xy 18.694222 -56.724229)
			(xy 18.556203 -56.579127) (xy 18.412488 -56.439663) (xy 18.263309 -56.30606) (xy 18.108904 -56.178533)
			(xy 17.94952 -56.057285) (xy 17.785412 -55.942512) (xy 17.616844 -55.834397) (xy 17.444086 -55.733112)
			(xy 17.267413 -55.63882) (xy 17.087109 -55.551673) (xy 16.903463 -55.471809) (xy 16.716768 -55.399357)
			(xy 16.527325 -55.334432) (xy 16.335435 -55.277139) (xy 16.141407 -55.227569) (xy 15.94555 -55.185802)
			(xy 15.74818 -55.151905) (xy 15.549611 -55.125931) (xy 15.350162 -55.107923) (xy 15.150153 -55.097909)
			(xy 14.949902 -55.095905) (xy 14.749732 -55.101915) (xy 14.549963 -55.115929) (xy 14.350915 -55.137925)
			(xy 14.152905 -55.167866) (xy 13.956253 -55.205706) (xy 13.761271 -55.251384) (xy 13.568274 -55.304826)
			(xy 13.377569 -55.365947) (xy 13.189462 -55.434649) (xy 13.004255 -55.510822) (xy 12.822243 -55.594345)
			(xy 12.643719 -55.685082) (xy 12.468968 -55.78289) (xy 12.298271 -55.887611) (xy 12.1319 -55.999078)
			(xy 11.970122 -56.117112) (xy 11.813196 -56.241524) (xy 11.661373 -56.372115) (xy 11.514897 -56.508676)
			(xy 11.374002 -56.650988) (xy 11.238913 -56.798823) (xy 11.109848 -56.951945) (xy 10.987012 -57.110107)
			(xy 10.870602 -57.273058) (xy 10.760806 -57.440536) (xy 10.657798 -57.612273) (xy 10.561743 -57.787993)
			(xy 10.472796 -57.967416) (xy 10.391099 -58.150254) (xy 10.316783 -58.336215) (xy 10.249966 -58.524999)
			(xy 10.190756 -58.716306) (xy 10.139247 -58.909829) (xy 10.095523 -59.105257) (xy 10.059652 -59.302279)
			(xy 10.031693 -59.500578) (xy 10.01169 -59.699836) (xy 9.999676 -59.899736) (xy 9.995669 -60.099956)
			(xy 12.482326 -60.099956) (xy 12.486358 -59.95752) (xy 12.498442 -59.815541) (xy 12.51854 -59.674472)
			(xy 12.546586 -59.534766) (xy 12.582491 -59.396871) (xy 12.62614 -59.261228) (xy 12.677393 -59.128272)
			(xy 12.736086 -58.998429) (xy 12.802031 -58.872114) (xy 12.875016 -58.749732) (xy 12.954809 -58.631675)
			(xy 13.041153 -58.518321) (xy 13.133771 -58.410034) (xy 13.232367 -58.307161) (xy 13.336626 -58.21003)
			(xy 13.446213 -58.118953) (xy 13.560777 -58.034222) (xy 13.679951 -57.956108) (xy 13.803353 -57.884862)
			(xy 13.930589 -57.820711) (xy 14.06125 -57.763861) (xy 14.194918 -57.714495) (xy 14.331165 -57.67277)
			(xy 14.469554 -57.638819) (xy 14.609643 -57.612753) (xy 14.750982 -57.594654) (xy 14.893118 -57.58458)
			(xy 15.035597 -57.582564) (xy 15.177961 -57.588611) (xy 15.319756 -57.602703) (xy 15.460526 -57.624795)
			(xy 15.59982 -57.654815) (xy 15.737194 -57.692668) (xy 15.872205 -57.738232) (xy 16.004423 -57.791362)
			(xy 16.133423 -57.851886) (xy 16.258792 -57.919612) (xy 16.380129 -57.994322) (xy 16.497045 -58.075777)
			(xy 16.609165 -58.163716) (xy 16.716131 -58.257858) (xy 16.817599 -58.3579) (xy 16.913244 -58.463523)
			(xy 17.002761 -58.574387) (xy 17.085863 -58.690139) (xy 17.162282 -58.810406) (xy 17.231775 -58.934804)
			(xy 17.294119 -59.062935) (xy 17.349114 -59.194388) (xy 17.396585 -59.328741) (xy 17.436378 -59.465565)
			(xy 17.468366 -59.604421) (xy 17.492447 -59.744864) (xy 17.508545 -59.886445) (xy 17.516606 -60.02871)
			(xy 17.51711 -60.099956) (xy 17.516606 -60.171202) (xy 17.508545 -60.313467) (xy 17.492447 -60.455048)
			(xy 17.468366 -60.595491) (xy 17.436378 -60.734347) (xy 17.396585 -60.871171) (xy 17.349114 -61.005524)
			(xy 17.294119 -61.136977) (xy 17.231775 -61.265108) (xy 17.162282 -61.389506) (xy 17.085863 -61.509773)
			(xy 17.002761 -61.625525) (xy 16.913244 -61.736389) (xy 16.817599 -61.842012) (xy 16.716131 -61.942054)
			(xy 16.609165 -62.036196) (xy 16.497045 -62.124135) (xy 16.380129 -62.20559) (xy 16.258792 -62.2803)
			(xy 16.133423 -62.348026) (xy 16.004423 -62.40855) (xy 15.872205 -62.46168) (xy 15.737194 -62.507244)
			(xy 15.59982 -62.545097) (xy 15.460526 -62.575117) (xy 15.319756 -62.597209) (xy 15.177961 -62.611301)
			(xy 15.035597 -62.617348) (xy 14.893118 -62.615332) (xy 14.750982 -62.605258) (xy 14.609643 -62.587159)
			(xy 14.469554 -62.561093) (xy 14.331165 -62.527142) (xy 14.194918 -62.485417) (xy 14.06125 -62.436051)
			(xy 13.930589 -62.379201) (xy 13.803353 -62.31505) (xy 13.679951 -62.243804) (xy 13.560777 -62.16569)
			(xy 13.446213 -62.080959) (xy 13.336626 -61.989882) (xy 13.232367 -61.892751) (xy 13.133771 -61.789878)
			(xy 13.041153 -61.681591) (xy 12.954809 -61.568237) (xy 12.875016 -61.45018) (xy 12.802031 -61.327798)
			(xy 12.736086 -61.201483) (xy 12.677393 -61.07164) (xy 12.62614 -60.938684) (xy 12.582491 -60.803041)
			(xy 12.546586 -60.665146) (xy 12.51854 -60.52544) (xy 12.498442 -60.384371) (xy 12.486358 -60.242392)
			(xy 12.482326 -60.099956) (xy 9.995669 -60.099956) (xy 9.999676 -60.300176) (xy 10.01169 -60.500076)
			(xy 10.031693 -60.699334) (xy 10.059652 -60.897633) (xy 10.095523 -61.094655) (xy 10.139247 -61.290083)
			(xy 10.190756 -61.483606) (xy 10.249966 -61.674913) (xy 10.316783 -61.863697) (xy 10.391099 -62.049658)
			(xy 10.472796 -62.232496) (xy 10.561743 -62.411919) (xy 10.657798 -62.587639) (xy 10.760806 -62.759376)
			(xy 10.870602 -62.926854) (xy 10.987012 -63.089805) (xy 11.109848 -63.247967) (xy 11.238913 -63.401089)
			(xy 11.374002 -63.548924) (xy 11.514897 -63.691236) (xy 11.661373 -63.827797) (xy 11.813196 -63.958388)
			(xy 11.970122 -64.0828) (xy 12.1319 -64.200834) (xy 12.298271 -64.312301) (xy 12.468968 -64.417022)
			(xy 12.643719 -64.51483) (xy 12.822243 -64.605567) (xy 13.004255 -64.68909) (xy 13.189462 -64.765263)
			(xy 13.377569 -64.833965) (xy 13.568274 -64.895086) (xy 13.761271 -64.948528) (xy 13.956253 -64.994206)
			(xy 14.152905 -65.032046) (xy 14.350915 -65.061987) (xy 14.549963 -65.083983) (xy 14.749732 -65.097997)
			(xy 14.949902 -65.104007) (xy 15.150153 -65.102003) (xy 15.350162 -65.091989) (xy 15.549611 -65.073981)
			(xy 15.74818 -65.048007) (xy 15.94555 -65.01411) (xy 16.141407 -64.972343) (xy 16.335435 -64.922773)
			(xy 16.527325 -64.86548) (xy 16.716768 -64.800555) (xy 16.903463 -64.728103) (xy 17.087109 -64.648239)
			(xy 17.267413 -64.561092) (xy 17.444086 -64.4668) (xy 17.616844 -64.365515) (xy 17.785412 -64.2574)
			(xy 17.94952 -64.142627) (xy 18.108904 -64.021379) (xy 18.263309 -63.893852) (xy 18.412488 -63.760249)
			(xy 18.556203 -63.620785) (xy 18.694222 -63.475683) (xy 18.826326 -63.325174) (xy 18.952302 -63.169501)
			(xy 19.071948 -63.008912) (xy 19.185074 -62.843664) (xy 19.291498 -62.674023) (xy 19.391049 -62.500259)
			(xy 19.483568 -62.322652) (xy 19.568907 -62.141485) (xy 19.64693 -61.957049) (xy 19.71751 -61.769639)
			(xy 19.780536 -61.579556) (xy 19.835907 -61.387102) (xy 19.883533 -61.192588) (xy 19.923338 -60.996323)
			(xy 19.955259 -60.798624) (xy 19.979245 -60.599805) (xy 19.995257 -60.400186) (xy 20.003269 -60.200086)
		)
		(stroke
			(width 0)
			(type solid)
		)
		(fill yes)
		(layer "B.Cu")
		(net "GND")
	)
	(gr_poly
		(pts
			(xy 430.003712 -104.549956) (xy 430.003211 -104.449826) (xy 429.995199 -104.249726) (xy 429.979187 -104.050107)
			(xy 429.955201 -103.851288) (xy 429.92328 -103.653589) (xy 429.883475 -103.457324) (xy 429.835849 -103.26281)
			(xy 429.780478 -103.070356) (xy 429.717452 -102.880273) (xy 429.646872 -102.692863) (xy 429.568849 -102.508427)
			(xy 429.48351 -102.32726) (xy 429.390991 -102.149653) (xy 429.29144 -101.975889) (xy 429.185016 -101.806248)
			(xy 429.07189 -101.641) (xy 428.952244 -101.480411) (xy 428.826268 -101.324738) (xy 428.694164 -101.174229)
			(xy 428.556145 -101.029127) (xy 428.41243 -100.889663) (xy 428.263251 -100.75606) (xy 428.108846 -100.628533)
			(xy 427.949462 -100.507285) (xy 427.785354 -100.392512) (xy 427.616786 -100.284397) (xy 427.444028 -100.183112)
			(xy 427.267355 -100.08882) (xy 427.087051 -100.001673) (xy 426.903405 -99.921809) (xy 426.71671 -99.849357)
			(xy 426.527267 -99.784432) (xy 426.335377 -99.727139) (xy 426.141349 -99.677569) (xy 425.945492 -99.635802)
			(xy 425.748122 -99.601905) (xy 425.549553 -99.575931) (xy 425.350104 -99.557923) (xy 425.150095 -99.547909)
			(xy 424.949844 -99.545905) (xy 424.749674 -99.551915) (xy 424.549905 -99.565929) (xy 424.350857 -99.587925)
			(xy 424.152847 -99.617866) (xy 423.956195 -99.655706) (xy 423.761213 -99.701384) (xy 423.568216 -99.754826)
			(xy 423.377511 -99.815947) (xy 423.189404 -99.884649) (xy 423.004197 -99.960822) (xy 422.822185 -100.044345)
			(xy 422.643661 -100.135082) (xy 422.46891 -100.23289) (xy 422.298213 -100.337611) (xy 422.131842 -100.449078)
			(xy 421.970064 -100.567112) (xy 421.813138 -100.691524) (xy 421.661315 -100.822115) (xy 421.514839 -100.958676)
			(xy 421.373944 -101.100988) (xy 421.238855 -101.248823) (xy 421.10979 -101.401945) (xy 420.986954 -101.560107)
			(xy 420.870544 -101.723058) (xy 420.760748 -101.890536) (xy 420.65774 -102.062273) (xy 420.561685 -102.237993)
			(xy 420.472738 -102.417416) (xy 420.391041 -102.600254) (xy 420.316725 -102.786215) (xy 420.249908 -102.974999)
			(xy 420.190698 -103.166306) (xy 420.139189 -103.359829) (xy 420.095465 -103.555257) (xy 420.059594 -103.752279)
			(xy 420.031635 -103.950578) (xy 420.011632 -104.149836) (xy 419.999618 -104.349736) (xy 419.995611 -104.549956)
			(xy 422.482268 -104.549956) (xy 422.4863 -104.40752) (xy 422.498384 -104.265541) (xy 422.518482 -104.124472)
			(xy 422.546528 -103.984766) (xy 422.582433 -103.846871) (xy 422.626082 -103.711228) (xy 422.677335 -103.578272)
			(xy 422.736028 -103.448429) (xy 422.801973 -103.322114) (xy 422.874958 -103.199732) (xy 422.954751 -103.081675)
			(xy 423.041095 -102.968321) (xy 423.133713 -102.860034) (xy 423.232309 -102.757161) (xy 423.336568 -102.66003)
			(xy 423.446155 -102.568953) (xy 423.560719 -102.484222) (xy 423.679893 -102.406108) (xy 423.803295 -102.334862)
			(xy 423.930531 -102.270711) (xy 424.061192 -102.213861) (xy 424.19486 -102.164495) (xy 424.331107 -102.12277)
			(xy 424.469496 -102.088819) (xy 424.609585 -102.062753) (xy 424.750924 -102.044654) (xy 424.89306 -102.03458)
			(xy 425.035539 -102.032564) (xy 425.177903 -102.038611) (xy 425.319698 -102.052703) (xy 425.460468 -102.074795)
			(xy 425.599762 -102.104815) (xy 425.737136 -102.142668) (xy 425.872147 -102.188232) (xy 426.004365 -102.241362)
			(xy 426.133365 -102.301886) (xy 426.258734 -102.369612) (xy 426.380071 -102.444322) (xy 426.496987 -102.525777)
			(xy 426.609107 -102.613716) (xy 426.716073 -102.707858) (xy 426.817541 -102.8079) (xy 426.913186 -102.913523)
			(xy 427.002703 -103.024387) (xy 427.085805 -103.140139) (xy 427.162224 -103.260406) (xy 427.231717 -103.384804)
			(xy 427.294061 -103.512935) (xy 427.349056 -103.644388) (xy 427.396527 -103.778741) (xy 427.43632 -103.915565)
			(xy 427.468308 -104.054421) (xy 427.492389 -104.194864) (xy 427.508487 -104.336445) (xy 427.516548 -104.47871)
			(xy 427.517052 -104.549956) (xy 427.516548 -104.621202) (xy 427.508487 -104.763467) (xy 427.492389 -104.905048)
			(xy 427.468308 -105.045491) (xy 427.43632 -105.184347) (xy 427.396527 -105.321171) (xy 427.349056 -105.455524)
			(xy 427.294061 -105.586977) (xy 427.231717 -105.715108) (xy 427.162224 -105.839506) (xy 427.085805 -105.959773)
			(xy 427.002703 -106.075525) (xy 426.913186 -106.186389) (xy 426.817541 -106.292012) (xy 426.716073 -106.392054)
			(xy 426.609107 -106.486196) (xy 426.496987 -106.574135) (xy 426.380071 -106.65559) (xy 426.258734 -106.7303)
			(xy 426.133365 -106.798026) (xy 426.004365 -106.85855) (xy 425.872147 -106.91168) (xy 425.737136 -106.957244)
			(xy 425.599762 -106.995097) (xy 425.460468 -107.025117) (xy 425.319698 -107.047209) (xy 425.177903 -107.061301)
			(xy 425.035539 -107.067348) (xy 424.89306 -107.065332) (xy 424.750924 -107.055258) (xy 424.609585 -107.037159)
			(xy 424.469496 -107.011093) (xy 424.331107 -106.977142) (xy 424.19486 -106.935417) (xy 424.061192 -106.886051)
			(xy 423.930531 -106.829201) (xy 423.803295 -106.76505) (xy 423.679893 -106.693804) (xy 423.560719 -106.61569)
			(xy 423.446155 -106.530959) (xy 423.336568 -106.439882) (xy 423.232309 -106.342751) (xy 423.133713 -106.239878)
			(xy 423.041095 -106.131591) (xy 422.954751 -106.018237) (xy 422.874958 -105.90018) (xy 422.801973 -105.777798)
			(xy 422.736028 -105.651483) (xy 422.677335 -105.52164) (xy 422.626082 -105.388684) (xy 422.582433 -105.253041)
			(xy 422.546528 -105.115146) (xy 422.518482 -104.97544) (xy 422.498384 -104.834371) (xy 422.4863 -104.692392)
			(xy 422.482268 -104.549956) (xy 419.995611 -104.549956) (xy 419.999618 -104.750176) (xy 420.011632 -104.950076)
			(xy 420.031635 -105.149334) (xy 420.059594 -105.347633) (xy 420.095465 -105.544655) (xy 420.139189 -105.740083)
			(xy 420.190698 -105.933606) (xy 420.249908 -106.124913) (xy 420.316725 -106.313697) (xy 420.391041 -106.499658)
			(xy 420.472738 -106.682496) (xy 420.561685 -106.861919) (xy 420.65774 -107.037639) (xy 420.760748 -107.209376)
			(xy 420.870544 -107.376854) (xy 420.986954 -107.539805) (xy 421.10979 -107.697967) (xy 421.238855 -107.851089)
			(xy 421.373944 -107.998924) (xy 421.514839 -108.141236) (xy 421.661315 -108.277797) (xy 421.813138 -108.408388)
			(xy 421.970064 -108.5328) (xy 422.131842 -108.650834) (xy 422.298213 -108.762301) (xy 422.46891 -108.867022)
			(xy 422.643661 -108.96483) (xy 422.822185 -109.055567) (xy 423.004197 -109.13909) (xy 423.189404 -109.215263)
			(xy 423.377511 -109.283965) (xy 423.568216 -109.345086) (xy 423.761213 -109.398528) (xy 423.956195 -109.444206)
			(xy 424.152847 -109.482046) (xy 424.350857 -109.511987) (xy 424.549905 -109.533983) (xy 424.749674 -109.547997)
			(xy 424.949844 -109.554007) (xy 425.150095 -109.552003) (xy 425.350104 -109.541989) (xy 425.549553 -109.523981)
			(xy 425.748122 -109.498007) (xy 425.945492 -109.46411) (xy 426.141349 -109.422343) (xy 426.335377 -109.372773)
			(xy 426.527267 -109.31548) (xy 426.71671 -109.250555) (xy 426.903405 -109.178103) (xy 427.087051 -109.098239)
			(xy 427.267355 -109.011092) (xy 427.444028 -108.9168) (xy 427.616786 -108.815515) (xy 427.785354 -108.7074)
			(xy 427.949462 -108.592627) (xy 428.108846 -108.471379) (xy 428.263251 -108.343852) (xy 428.41243 -108.210249)
			(xy 428.556145 -108.070785) (xy 428.694164 -107.925683) (xy 428.826268 -107.775174) (xy 428.952244 -107.619501)
			(xy 429.07189 -107.458912) (xy 429.185016 -107.293664) (xy 429.29144 -107.124023) (xy 429.390991 -106.950259)
			(xy 429.48351 -106.772652) (xy 429.568849 -106.591485) (xy 429.646872 -106.407049) (xy 429.717452 -106.219639)
			(xy 429.780478 -106.029556) (xy 429.835849 -105.837102) (xy 429.883475 -105.642588) (xy 429.92328 -105.446323)
			(xy 429.955201 -105.248624) (xy 429.979187 -105.049805) (xy 429.995199 -104.850186) (xy 430.003211 -104.650086)
		)
		(stroke
			(width 0)
			(type solid)
		)
		(fill yes)
		(layer "B.Cu")
		(net "GND")
	)
	(gr_poly
		(pts
			(xy 430.003712 -60.099956) (xy 430.003211 -59.999826) (xy 429.995199 -59.799726) (xy 429.979187 -59.600107)
			(xy 429.955201 -59.401288) (xy 429.92328 -59.203589) (xy 429.883475 -59.007324) (xy 429.835849 -58.81281)
			(xy 429.780478 -58.620356) (xy 429.717452 -58.430273) (xy 429.646872 -58.242863) (xy 429.568849 -58.058427)
			(xy 429.48351 -57.87726) (xy 429.390991 -57.699653) (xy 429.29144 -57.525889) (xy 429.185016 -57.356248)
			(xy 429.07189 -57.191) (xy 428.952244 -57.030411) (xy 428.826268 -56.874738) (xy 428.694164 -56.724229)
			(xy 428.556145 -56.579127) (xy 428.41243 -56.439663) (xy 428.263251 -56.30606) (xy 428.108846 -56.178533)
			(xy 427.949462 -56.057285) (xy 427.785354 -55.942512) (xy 427.616786 -55.834397) (xy 427.444028 -55.733112)
			(xy 427.267355 -55.63882) (xy 427.087051 -55.551673) (xy 426.903405 -55.471809) (xy 426.71671 -55.399357)
			(xy 426.527267 -55.334432) (xy 426.335377 -55.277139) (xy 426.141349 -55.227569) (xy 425.945492 -55.185802)
			(xy 425.748122 -55.151905) (xy 425.549553 -55.125931) (xy 425.350104 -55.107923) (xy 425.150095 -55.097909)
			(xy 424.949844 -55.095905) (xy 424.749674 -55.101915) (xy 424.549905 -55.115929) (xy 424.350857 -55.137925)
			(xy 424.152847 -55.167866) (xy 423.956195 -55.205706) (xy 423.761213 -55.251384) (xy 423.568216 -55.304826)
			(xy 423.377511 -55.365947) (xy 423.189404 -55.434649) (xy 423.004197 -55.510822) (xy 422.822185 -55.594345)
			(xy 422.643661 -55.685082) (xy 422.46891 -55.78289) (xy 422.298213 -55.887611) (xy 422.131842 -55.999078)
			(xy 421.970064 -56.117112) (xy 421.813138 -56.241524) (xy 421.661315 -56.372115) (xy 421.514839 -56.508676)
			(xy 421.373944 -56.650988) (xy 421.238855 -56.798823) (xy 421.10979 -56.951945) (xy 420.986954 -57.110107)
			(xy 420.870544 -57.273058) (xy 420.760748 -57.440536) (xy 420.65774 -57.612273) (xy 420.561685 -57.787993)
			(xy 420.472738 -57.967416) (xy 420.391041 -58.150254) (xy 420.316725 -58.336215) (xy 420.249908 -58.524999)
			(xy 420.190698 -58.716306) (xy 420.139189 -58.909829) (xy 420.095465 -59.105257) (xy 420.059594 -59.302279)
			(xy 420.031635 -59.500578) (xy 420.011632 -59.699836) (xy 419.999618 -59.899736) (xy 419.995611 -60.099956)
			(xy 422.482268 -60.099956) (xy 422.4863 -59.95752) (xy 422.498384 -59.815541) (xy 422.518482 -59.674472)
			(xy 422.546528 -59.534766) (xy 422.582433 -59.396871) (xy 422.626082 -59.261228) (xy 422.677335 -59.128272)
			(xy 422.736028 -58.998429) (xy 422.801973 -58.872114) (xy 422.874958 -58.749732) (xy 422.954751 -58.631675)
			(xy 423.041095 -58.518321) (xy 423.133713 -58.410034) (xy 423.232309 -58.307161) (xy 423.336568 -58.21003)
			(xy 423.446155 -58.118953) (xy 423.560719 -58.034222) (xy 423.679893 -57.956108) (xy 423.803295 -57.884862)
			(xy 423.930531 -57.820711) (xy 424.061192 -57.763861) (xy 424.19486 -57.714495) (xy 424.331107 -57.67277)
			(xy 424.469496 -57.638819) (xy 424.609585 -57.612753) (xy 424.750924 -57.594654) (xy 424.89306 -57.58458)
			(xy 425.035539 -57.582564) (xy 425.177903 -57.588611) (xy 425.319698 -57.602703) (xy 425.460468 -57.624795)
			(xy 425.599762 -57.654815) (xy 425.737136 -57.692668) (xy 425.872147 -57.738232) (xy 426.004365 -57.791362)
			(xy 426.133365 -57.851886) (xy 426.258734 -57.919612) (xy 426.380071 -57.994322) (xy 426.496987 -58.075777)
			(xy 426.609107 -58.163716) (xy 426.716073 -58.257858) (xy 426.817541 -58.3579) (xy 426.913186 -58.463523)
			(xy 427.002703 -58.574387) (xy 427.085805 -58.690139) (xy 427.162224 -58.810406) (xy 427.231717 -58.934804)
			(xy 427.294061 -59.062935) (xy 427.349056 -59.194388) (xy 427.396527 -59.328741) (xy 427.43632 -59.465565)
			(xy 427.468308 -59.604421) (xy 427.492389 -59.744864) (xy 427.508487 -59.886445) (xy 427.516548 -60.02871)
			(xy 427.517052 -60.099956) (xy 427.516548 -60.171202) (xy 427.508487 -60.313467) (xy 427.492389 -60.455048)
			(xy 427.468308 -60.595491) (xy 427.43632 -60.734347) (xy 427.396527 -60.871171) (xy 427.349056 -61.005524)
			(xy 427.294061 -61.136977) (xy 427.231717 -61.265108) (xy 427.162224 -61.389506) (xy 427.085805 -61.509773)
			(xy 427.002703 -61.625525) (xy 426.913186 -61.736389) (xy 426.817541 -61.842012) (xy 426.716073 -61.942054)
			(xy 426.609107 -62.036196) (xy 426.496987 -62.124135) (xy 426.380071 -62.20559) (xy 426.258734 -62.2803)
			(xy 426.133365 -62.348026) (xy 426.004365 -62.40855) (xy 425.872147 -62.46168) (xy 425.737136 -62.507244)
			(xy 425.599762 -62.545097) (xy 425.460468 -62.575117) (xy 425.319698 -62.597209) (xy 425.177903 -62.611301)
			(xy 425.035539 -62.617348) (xy 424.89306 -62.615332) (xy 424.750924 -62.605258) (xy 424.609585 -62.587159)
			(xy 424.469496 -62.561093) (xy 424.331107 -62.527142) (xy 424.19486 -62.485417) (xy 424.061192 -62.436051)
			(xy 423.930531 -62.379201) (xy 423.803295 -62.31505) (xy 423.679893 -62.243804) (xy 423.560719 -62.16569)
			(xy 423.446155 -62.080959) (xy 423.336568 -61.989882) (xy 423.232309 -61.892751) (xy 423.133713 -61.789878)
			(xy 423.041095 -61.681591) (xy 422.954751 -61.568237) (xy 422.874958 -61.45018) (xy 422.801973 -61.327798)
			(xy 422.736028 -61.201483) (xy 422.677335 -61.07164) (xy 422.626082 -60.938684) (xy 422.582433 -60.803041)
			(xy 422.546528 -60.665146) (xy 422.518482 -60.52544) (xy 422.498384 -60.384371) (xy 422.4863 -60.242392)
			(xy 422.482268 -60.099956) (xy 419.995611 -60.099956) (xy 419.999618 -60.300176) (xy 420.011632 -60.500076)
			(xy 420.031635 -60.699334) (xy 420.059594 -60.897633) (xy 420.095465 -61.094655) (xy 420.139189 -61.290083)
			(xy 420.190698 -61.483606) (xy 420.249908 -61.674913) (xy 420.316725 -61.863697) (xy 420.391041 -62.049658)
			(xy 420.472738 -62.232496) (xy 420.561685 -62.411919) (xy 420.65774 -62.587639) (xy 420.760748 -62.759376)
			(xy 420.870544 -62.926854) (xy 420.986954 -63.089805) (xy 421.10979 -63.247967) (xy 421.238855 -63.401089)
			(xy 421.373944 -63.548924) (xy 421.514839 -63.691236) (xy 421.661315 -63.827797) (xy 421.813138 -63.958388)
			(xy 421.970064 -64.0828) (xy 422.131842 -64.200834) (xy 422.298213 -64.312301) (xy 422.46891 -64.417022)
			(xy 422.643661 -64.51483) (xy 422.822185 -64.605567) (xy 423.004197 -64.68909) (xy 423.189404 -64.765263)
			(xy 423.377511 -64.833965) (xy 423.568216 -64.895086) (xy 423.761213 -64.948528) (xy 423.956195 -64.994206)
			(xy 424.152847 -65.032046) (xy 424.350857 -65.061987) (xy 424.549905 -65.083983) (xy 424.749674 -65.097997)
			(xy 424.949844 -65.104007) (xy 425.150095 -65.102003) (xy 425.350104 -65.091989) (xy 425.549553 -65.073981)
			(xy 425.748122 -65.048007) (xy 425.945492 -65.01411) (xy 426.141349 -64.972343) (xy 426.335377 -64.922773)
			(xy 426.527267 -64.86548) (xy 426.71671 -64.800555) (xy 426.903405 -64.728103) (xy 427.087051 -64.648239)
			(xy 427.267355 -64.561092) (xy 427.444028 -64.4668) (xy 427.616786 -64.365515) (xy 427.785354 -64.2574)
			(xy 427.949462 -64.142627) (xy 428.108846 -64.021379) (xy 428.263251 -63.893852) (xy 428.41243 -63.760249)
			(xy 428.556145 -63.620785) (xy 428.694164 -63.475683) (xy 428.826268 -63.325174) (xy 428.952244 -63.169501)
			(xy 429.07189 -63.008912) (xy 429.185016 -62.843664) (xy 429.29144 -62.674023) (xy 429.390991 -62.500259)
			(xy 429.48351 -62.322652) (xy 429.568849 -62.141485) (xy 429.646872 -61.957049) (xy 429.717452 -61.769639)
			(xy 429.780478 -61.579556) (xy 429.835849 -61.387102) (xy 429.883475 -61.192588) (xy 429.92328 -60.996323)
			(xy 429.955201 -60.798624) (xy 429.979187 -60.599805) (xy 429.995199 -60.400186) (xy 430.003211 -60.200086)
		)
		(stroke
			(width 0)
			(type solid)
		)
		(fill yes)
		(layer "B.Cu")
		(net "GND")
	)
	(gr_poly
		(pts
			(xy 77.249782 -169.49928) (xy 77.259845 -169.498841) (xy 77.278426 -169.491104) (xy 77.28585 -169.484294)
			(xy 77.639672 -169.130472) (xy 77.646517 -169.123073) (xy 77.654246 -169.104475) (xy 77.654658 -169.094404)
			(xy 77.654658 -164.60978) (xy 77.65423 -164.599712) (xy 77.646506 -164.581117) (xy 77.639672 -164.573712)
			(xy 77.333602 -164.267642) (xy 77.326206 -164.260791) (xy 77.307607 -164.253049) (xy 77.297534 -164.252656)
			(xy 42.630852 -164.252656) (xy 42.620787 -164.252223) (xy 42.602199 -164.244491) (xy 42.594784 -164.23767)
			(xy 42.22496 -163.867846) (xy 42.218115 -163.860448) (xy 42.210391 -163.841849) (xy 42.209974 -163.831778)
			(xy 42.209974 -152.53335) (xy 42.209541 -152.523284) (xy 42.201811 -152.504696) (xy 42.194988 -152.497282)
			(xy 41.937178 -152.239472) (xy 41.929782 -152.232621) (xy 41.911183 -152.224883) (xy 41.90111 -152.224486)
			(xy 39.46398 -152.224486) (xy 39.453911 -152.224912) (xy 39.435311 -152.23263) (xy 39.427912 -152.239472)
			(xy 39.322756 -152.344628) (xy 39.31539 -152.36825) (xy 39.317676 -152.38095) (xy 39.330723 -152.455077)
			(xy 39.348907 -152.604504) (xy 39.358009 -152.754757) (xy 39.35857 -152.830022) (xy 39.357998 -152.906623)
			(xy 39.348573 -153.059534) (xy 39.32974 -153.211574) (xy 39.301572 -153.362164) (xy 39.264175 -153.510731)
			(xy 39.241476 -153.583894) (xy 39.240008 -153.589028) (xy 39.23899 -153.599655) (xy 39.239444 -153.604976)
			(xy 39.245535 -153.661037) (xy 39.252032 -153.77363) (xy 39.252031 -153.88641) (xy 39.245532 -153.999002)
			(xy 39.239444 -154.055064) (xy 39.238958 -154.060384) (xy 39.239983 -154.071017) (xy 39.241476 -154.076146)
			(xy 39.264166 -154.149311) (xy 39.301564 -154.297878) (xy 39.329734 -154.448467) (xy 39.348566 -154.600506)
			(xy 39.357991 -154.753417) (xy 39.35857 -154.830018) (xy 39.357998 -154.906619) (xy 39.348573 -155.05953)
			(xy 39.32974 -155.21157) (xy 39.301572 -155.36216) (xy 39.264176 -155.510728) (xy 39.241476 -155.58389)
			(xy 39.240008 -155.589024) (xy 39.238989 -155.599651) (xy 39.239444 -155.604972) (xy 39.245535 -155.661033)
			(xy 39.252033 -155.773626) (xy 39.252032 -155.886406) (xy 39.245532 -155.998998) (xy 39.239444 -156.05506)
			(xy 39.238958 -156.06038) (xy 39.239981 -156.071013) (xy 39.241476 -156.076142) (xy 39.264166 -156.149307)
			(xy 39.301565 -156.297874) (xy 39.329734 -156.448463) (xy 39.348567 -156.600502) (xy 39.357992 -156.753413)
			(xy 39.35857 -156.830014) (xy 39.357999 -156.906615) (xy 39.348573 -157.059527) (xy 39.329741 -157.211566)
			(xy 39.301573 -157.362156) (xy 39.264177 -157.510724) (xy 39.241476 -157.583886) (xy 39.240008 -157.58902)
			(xy 39.238988 -157.599647) (xy 39.239444 -157.604968) (xy 39.245535 -157.661029) (xy 39.252033 -157.773622)
			(xy 39.252032 -157.886402) (xy 39.245533 -157.998994) (xy 39.239444 -158.055056) (xy 39.238957 -158.060376)
			(xy 39.23998 -158.071009) (xy 39.241476 -158.076138) (xy 39.264166 -158.149303) (xy 39.301565 -158.29787)
			(xy 39.329735 -158.448459) (xy 39.348568 -158.600498) (xy 39.357993 -158.753409) (xy 39.35857 -158.83001)
			(xy 39.357999 -158.906611) (xy 39.348574 -159.059523) (xy 39.329742 -159.211563) (xy 39.301574 -159.362153)
			(xy 39.264178 -159.51072) (xy 39.241476 -159.583882) (xy 39.240007 -159.589016) (xy 39.238986 -159.599643)
			(xy 39.239444 -159.604964) (xy 39.245535 -159.661025) (xy 39.252033 -159.773618) (xy 39.252033 -159.886398)
			(xy 39.245534 -159.99899) (xy 39.239444 -160.055052) (xy 39.238957 -160.060372) (xy 39.239979 -160.071005)
			(xy 39.241476 -160.076134) (xy 39.264166 -160.149299) (xy 39.301565 -160.297866) (xy 39.329735 -160.448455)
			(xy 39.348569 -160.600494) (xy 39.357994 -160.753405) (xy 39.35857 -160.830006) (xy 39.357999 -160.906607)
			(xy 39.348574 -161.059519) (xy 39.329742 -161.211559) (xy 39.301575 -161.362149) (xy 39.264179 -161.510717)
			(xy 39.241476 -161.583878) (xy 39.240007 -161.589012) (xy 39.238985 -161.59964) (xy 39.239444 -161.60496)
			(xy 39.245535 -161.661021) (xy 39.252034 -161.773614) (xy 39.252034 -161.886394) (xy 39.245535 -161.998987)
			(xy 39.239444 -162.055048) (xy 39.238957 -162.060369) (xy 39.239978 -162.071002) (xy 39.241476 -162.07613)
			(xy 39.264166 -162.149295) (xy 39.301566 -162.297862) (xy 39.329736 -162.448451) (xy 39.34857 -162.60049)
			(xy 39.357995 -162.753401) (xy 39.35857 -162.830002) (xy 39.357996 -162.906603) (xy 39.348565 -163.059513)
			(xy 39.329728 -163.211551) (xy 39.301555 -163.36214) (xy 39.264154 -163.510705) (xy 39.241476 -163.583874)
			(xy 39.240006 -163.589008) (xy 39.238984 -163.599636) (xy 39.239444 -163.604956) (xy 39.245536 -163.661017)
			(xy 39.252034 -163.77361) (xy 39.252034 -163.88639) (xy 39.245536 -163.998983) (xy 39.239444 -164.055044)
			(xy 39.238956 -164.060365) (xy 39.239976 -164.070998) (xy 39.241476 -164.076126) (xy 39.264166 -164.149291)
			(xy 39.301566 -164.297857) (xy 39.329737 -164.448447) (xy 39.34857 -164.600486) (xy 39.357996 -164.753397)
			(xy 39.35857 -164.829998) (xy 39.357996 -164.906599) (xy 39.348566 -165.059509) (xy 39.329728 -165.211547)
			(xy 39.301556 -165.362136) (xy 39.264155 -165.510701) (xy 39.241476 -165.58387) (xy 39.240006 -165.589004)
			(xy 39.238983 -165.599632) (xy 39.239444 -165.604952) (xy 39.245536 -165.661013) (xy 39.252034 -165.773606)
			(xy 39.252035 -165.886386) (xy 39.245536 -165.998979) (xy 39.239444 -166.05504) (xy 39.238956 -166.060361)
			(xy 39.239975 -166.070994) (xy 39.241476 -166.076122) (xy 39.264167 -166.149287) (xy 39.301567 -166.297853)
			(xy 39.329737 -166.448443) (xy 39.348571 -166.600482) (xy 39.357997 -166.753393) (xy 39.35857 -166.829994)
			(xy 39.357996 -166.906595) (xy 39.348566 -167.059505) (xy 39.329729 -167.211544) (xy 39.301557 -167.362132)
			(xy 39.264156 -167.510698) (xy 39.241476 -167.583866) (xy 39.240005 -167.589) (xy 39.238981 -167.599628)
			(xy 39.239444 -167.604948) (xy 39.245536 -167.661009) (xy 39.246887 -167.684408) (xy 65.513954 -167.684408)
			(xy 65.513954 -167.57578) (xy 65.521883 -167.467442) (xy 65.5377 -167.359971) (xy 65.561319 -167.253942)
			(xy 65.592615 -167.14992) (xy 65.63142 -167.048459) (xy 65.677528 -166.950102) (xy 65.730692 -166.855373)
			(xy 65.79063 -166.764778) (xy 65.85702 -166.678799) (xy 65.92951 -166.597896) (xy 66.007711 -166.5225)
			(xy 66.091208 -166.453014) (xy 66.179554 -166.389807) (xy 66.272278 -166.333219) (xy 66.368886 -166.283549)
			(xy 66.468861 -166.241064) (xy 66.571671 -166.205991) (xy 66.676767 -166.178515) (xy 66.783588 -166.158784)
			(xy 66.891564 -166.146903) (xy 67.00012 -166.142936) (xy 67.108676 -166.146903) (xy 67.216652 -166.158784)
			(xy 67.323473 -166.178515) (xy 67.428569 -166.205991) (xy 67.531379 -166.241064) (xy 67.631354 -166.283549)
			(xy 67.727962 -166.333219) (xy 67.820686 -166.389807) (xy 67.909032 -166.453014) (xy 67.992529 -166.5225)
			(xy 68.07073 -166.597896) (xy 68.14322 -166.678799) (xy 68.20961 -166.764778) (xy 68.269548 -166.855373)
			(xy 68.322712 -166.950102) (xy 68.36882 -167.048459) (xy 68.407625 -167.14992) (xy 68.438921 -167.253942)
			(xy 68.46254 -167.359971) (xy 68.478357 -167.467442) (xy 68.486286 -167.57578) (xy 68.486782 -167.630094)
			(xy 68.486286 -167.684408) (xy 68.478357 -167.792746) (xy 68.46254 -167.900217) (xy 68.438921 -168.006246)
			(xy 68.407625 -168.110268) (xy 68.36882 -168.211729) (xy 68.322712 -168.310086) (xy 68.269548 -168.404815)
			(xy 68.20961 -168.49541) (xy 68.14322 -168.581389) (xy 68.07073 -168.662292) (xy 67.992529 -168.737688)
			(xy 67.909032 -168.807174) (xy 67.820686 -168.870381) (xy 67.727962 -168.926969) (xy 67.631354 -168.976639)
			(xy 67.531379 -169.019124) (xy 67.428569 -169.054197) (xy 67.323473 -169.081673) (xy 67.216652 -169.101404)
			(xy 67.108676 -169.113285) (xy 67.00012 -169.117252) (xy 66.891564 -169.113285) (xy 66.783588 -169.101404)
			(xy 66.676767 -169.081673) (xy 66.571671 -169.054197) (xy 66.468861 -169.019124) (xy 66.368886 -168.976639)
			(xy 66.272278 -168.926969) (xy 66.179554 -168.870381) (xy 66.091208 -168.807174) (xy 66.007711 -168.737688)
			(xy 65.92951 -168.662292) (xy 65.85702 -168.581389) (xy 65.79063 -168.49541) (xy 65.730692 -168.404815)
			(xy 65.677528 -168.310086) (xy 65.63142 -168.211729) (xy 65.592615 -168.110268) (xy 65.561319 -168.006246)
			(xy 65.5377 -167.900217) (xy 65.521883 -167.792746) (xy 65.513954 -167.684408) (xy 39.246887 -167.684408)
			(xy 39.252035 -167.773602) (xy 39.252035 -167.886382) (xy 39.245537 -167.998975) (xy 39.239444 -168.055036)
			(xy 39.238955 -168.060357) (xy 39.239974 -168.070991) (xy 39.241476 -168.076118) (xy 39.264167 -168.149283)
			(xy 39.301567 -168.297849) (xy 39.329738 -168.448439) (xy 39.348572 -168.600478) (xy 39.357998 -168.753389)
			(xy 39.35857 -168.82999) (xy 39.35814 -168.894693) (xy 39.351374 -169.023921) (xy 39.337887 -169.152622)
			(xy 39.317715 -169.280446) (xy 39.304722 -169.343832) (xy 39.302182 -169.356532) (xy 39.309294 -169.380916)
			(xy 39.412672 -169.484294) (xy 39.420074 -169.49113) (xy 39.438672 -169.498839) (xy 39.44874 -169.49928)
		)
		(stroke
			(width 0)
			(type solid)
		)
		(fill yes)
		(layer "B.Cu")
		(net "GND")
	)
	(gr_poly
		(pts
			(xy 178.581304 -86.163658) (xy 178.58891 -86.162145) (xy 178.602748 -86.155163) (xy 178.608482 -86.149942)
			(xy 179.886864 -84.87156) (xy 179.893708 -84.864161) (xy 179.901433 -84.845562) (xy 179.90185 -84.835492)
			(xy 179.90185 -76.85405) (xy 177.376836 -74.329036) (xy 177.376836 -73.637902) (xy 177.369216 -73.619106)
			(xy 177.36185 -73.611994) (xy 176.98847 -73.238614) (xy 176.98163 -73.231214) (xy 176.973915 -73.212615)
			(xy 176.973484 -73.202546) (xy 176.973484 -67.847464) (xy 176.97299 -67.837462) (xy 176.965323 -67.818986)
			(xy 176.951171 -67.804848) (xy 176.932686 -67.7972) (xy 176.922684 -67.796664) (xy 174.206408 -67.796664)
			(xy 174.196397 -67.79715) (xy 174.177896 -67.804807) (xy 174.163732 -67.818959) (xy 174.156059 -67.837453)
			(xy 174.155608 -67.847464) (xy 174.155608 -73.372218) (xy 174.156099 -73.382223) (xy 174.163762 -73.400707)
			(xy 174.177915 -73.414852) (xy 174.196403 -73.422506) (xy 174.206408 -73.423018) (xy 176.80686 -73.423018)
			(xy 176.816925 -73.423453) (xy 176.835512 -73.431184) (xy 176.842928 -73.438004) (xy 177.046128 -73.641204)
			(xy 177.052981 -73.648599) (xy 177.060726 -73.667198) (xy 177.061114 -73.677272) (xy 177.061114 -74.660506)
			(xy 177.061539 -74.670575) (xy 177.069256 -74.689177) (xy 177.0761 -74.696574) (xy 177.694082 -75.314556)
			(xy 177.700921 -75.321957) (xy 177.708638 -75.340555) (xy 177.709068 -75.350624) (xy 177.709068 -78.0542)
			(xy 177.709556 -78.06421) (xy 177.717214 -78.082707) (xy 177.731366 -78.096868) (xy 177.749858 -78.104538)
			(xy 177.759868 -78.105) (xy 178.289712 -78.105) (xy 178.299781 -78.105425) (xy 178.318382 -78.113143)
			(xy 178.32578 -78.119986) (xy 179.026566 -78.820772) (xy 179.033405 -78.828173) (xy 179.041118 -78.846771)
			(xy 179.041552 -78.85684) (xy 179.041552 -82.994754) (xy 179.041118 -83.004819) (xy 179.033384 -83.023404)
			(xy 179.026566 -83.030822) (xy 178.535584 -83.521804) (xy 178.528184 -83.528647) (xy 178.509586 -83.536375)
			(xy 178.499516 -83.53679) (xy 174.006256 -83.53679) (xy 173.99619 -83.536359) (xy 173.977598 -83.528632)
			(xy 173.970188 -83.521804) (xy 173.69917 -83.250786) (xy 173.692318 -83.24339) (xy 173.684578 -83.224791)
			(xy 173.684184 -83.214718) (xy 173.684184 -78.474316) (xy 173.684622 -78.464252) (xy 173.692356 -78.445668)
			(xy 173.69917 -78.438248) (xy 173.991778 -78.14564) (xy 173.999179 -78.138801) (xy 174.017778 -78.131089)
			(xy 174.027846 -78.130654) (xy 175.124872 -78.130654) (xy 175.133254 -78.129892) (xy 175.140862 -78.128383)
			(xy 175.154704 -78.121405) (xy 175.160432 -78.116176) (xy 175.21682 -78.059788) (xy 175.223673 -78.052393)
			(xy 175.231416 -78.033794) (xy 175.231806 -78.02372) (xy 175.231806 -76.95946) (xy 175.224186 -76.940664)
			(xy 175.21682 -76.933552) (xy 175.13935 -76.856082) (xy 175.131953 -76.849234) (xy 175.113354 -76.841505)
			(xy 175.103282 -76.841096) (xy 172.846238 -76.841096) (xy 172.827442 -76.848716) (xy 172.82033 -76.856082)
			(xy 170.954192 -78.72222) (xy 170.94735 -78.72962) (xy 170.939624 -78.748218) (xy 170.939206 -78.758288)
			(xy 170.939206 -80.372712) (xy 170.938781 -80.382781) (xy 170.931064 -80.401383) (xy 170.92422 -80.40878)
			(xy 170.702986 -80.630014) (xy 170.695591 -80.636868) (xy 170.676992 -80.64461) (xy 170.666918 -80.645)
			(xy 168.71823 -80.645) (xy 168.708165 -80.644564) (xy 168.68958 -80.636832) (xy 168.682162 -80.630014)
			(xy 167.154352 -79.102204) (xy 167.147499 -79.094808) (xy 167.139755 -79.07621) (xy 167.139366 -79.066136)
			(xy 167.139366 -76.829666) (xy 167.139797 -76.8196) (xy 167.147528 -76.801011) (xy 167.154352 -76.793598)
			(xy 167.296084 -76.651866) (xy 167.303484 -76.645026) (xy 167.322083 -76.637312) (xy 167.332152 -76.63688)
			(xy 169.074084 -76.63688) (xy 169.082466 -76.636118) (xy 169.090074 -76.634608) (xy 169.103916 -76.62763)
			(xy 169.109644 -76.622402) (xy 169.123106 -76.60894) (xy 169.129942 -76.601538) (xy 169.137654 -76.58294)
			(xy 169.138092 -76.572872) (xy 169.138092 -76.131674) (xy 169.130472 -76.112878) (xy 169.123106 -76.105766)
			(xy 169.099484 -76.082144) (xy 169.092087 -76.075295) (xy 169.073488 -76.06756) (xy 169.063416 -76.067158)
			(xy 167.342312 -76.067158) (xy 167.332242 -76.066736) (xy 167.313638 -76.05902) (xy 167.306244 -76.052172)
			(xy 167.185848 -75.931776) (xy 167.179 -75.924379) (xy 167.171267 -75.90578) (xy 167.170862 -75.895708)
			(xy 167.170862 -72.62749) (xy 167.170478 -72.618354) (xy 167.164058 -72.601246) (xy 167.15204 -72.587482)
			(xy 167.144192 -72.582786) (xy 167.116171 -72.56706) (xy 167.063968 -72.529593) (xy 167.016906 -72.485843)
			(xy 166.975737 -72.436507) (xy 166.941117 -72.382373) (xy 166.913601 -72.324306) (xy 166.893626 -72.263233)
			(xy 166.881512 -72.200128) (xy 166.877453 -72.136) (xy 166.881512 -72.071872) (xy 166.893626 -72.008767)
			(xy 166.913601 -71.947694) (xy 166.941117 -71.889627) (xy 166.975737 -71.835493) (xy 167.016906 -71.786157)
			(xy 167.063968 -71.742407) (xy 167.116171 -71.70494) (xy 167.144192 -71.689214) (xy 167.152059 -71.684541)
			(xy 167.164084 -71.670769) (xy 167.170507 -71.653652) (xy 167.170862 -71.64451) (xy 167.170862 -70.145148)
			(xy 167.171296 -70.135083) (xy 167.179031 -70.116498) (xy 167.185848 -70.10908) (xy 167.295576 -69.999352)
			(xy 167.302976 -69.992512) (xy 167.321575 -69.984797) (xy 167.331644 -69.984366) (xy 169.395902 -69.984366)
			(xy 169.404284 -69.983604) (xy 169.41189 -69.982092) (xy 169.425727 -69.975108) (xy 169.431462 -69.969888)
			(xy 169.444924 -69.956426) (xy 169.451767 -69.949027) (xy 169.459486 -69.930428) (xy 169.45991 -69.920358)
			(xy 169.45991 -69.253608) (xy 169.45229 -69.234812) (xy 169.444924 -69.2277) (xy 169.399712 -69.182488)
			(xy 169.392318 -69.17563) (xy 169.373719 -69.167878) (xy 169.363644 -69.167502) (xy 168.37406 -69.167502)
			(xy 168.363993 -69.167071) (xy 168.345399 -69.159347) (xy 168.337992 -69.152516) (xy 168.249854 -69.064378)
			(xy 168.243005 -69.056981) (xy 168.23527 -69.038382) (xy 168.234868 -69.02831) (xy 168.234868 -67.598798)
			(xy 168.227248 -67.580002) (xy 168.219882 -67.57289) (xy 168.217342 -67.57035) (xy 168.21023 -67.562984)
			(xy 168.191434 -67.555364) (xy 165.899846 -67.555364) (xy 165.889781 -67.55493) (xy 165.871194 -67.547198)
			(xy 165.863778 -67.540378) (xy 165.775386 -67.451986) (xy 165.768532 -67.444591) (xy 165.76079 -67.425992)
			(xy 165.7604 -67.415918) (xy 165.7604 -66.061082) (xy 165.760827 -66.051013) (xy 165.768546 -66.032414)
			(xy 165.775386 -66.025014) (xy 165.863524 -65.936876) (xy 165.87092 -65.930025) (xy 165.889519 -65.922287)
			(xy 165.899592 -65.92189) (xy 168.643046 -65.92189) (xy 168.704768 -65.860168) (xy 168.704768 -64.425576)
			(xy 168.684448 -64.405256) (xy 168.677049 -64.398412) (xy 168.658451 -64.390687) (xy 168.64838 -64.39027)
			(xy 166.352982 -64.39027) (xy 166.342914 -64.389843) (xy 166.324317 -64.382121) (xy 166.316914 -64.375284)
			(xy 165.551358 -63.609728) (xy 165.543959 -63.602885) (xy 165.52536 -63.595161) (xy 165.51529 -63.594742)
			(xy 162.710114 -63.594742) (xy 162.691318 -63.602362) (xy 162.684206 -63.609728) (xy 162.606736 -63.687198)
			(xy 162.599885 -63.694595) (xy 162.592145 -63.713193) (xy 162.59175 -63.723266) (xy 162.59175 -64.643)
			(xy 164.514528 -64.643) (xy 164.518601 -64.587341) (xy 164.530736 -64.532868) (xy 164.550672 -64.480742)
			(xy 164.577986 -64.432074) (xy 164.612094 -64.387902) (xy 164.652271 -64.349167) (xy 164.697659 -64.316695)
			(xy 164.747291 -64.291177) (xy 164.800111 -64.273158) (xy 164.85499 -64.263021) (xy 164.910761 -64.260983)
			(xy 164.966235 -64.267086) (xy 165.020228 -64.281202) (xy 165.071591 -64.303029) (xy 165.119229 -64.332102)
			(xy 165.162125 -64.367801) (xy 165.199367 -64.409365) (xy 165.230161 -64.455909) (xy 165.253849 -64.50644)
			(xy 165.269927 -64.559882) (xy 165.278053 -64.615096) (xy 165.278562 -64.643) (xy 165.278053 -64.670904)
			(xy 165.269927 -64.726118) (xy 165.253849 -64.77956) (xy 165.230161 -64.830091) (xy 165.199367 -64.876635)
			(xy 165.162125 -64.918199) (xy 165.119229 -64.953898) (xy 165.071591 -64.982971) (xy 165.020228 -65.004798)
			(xy 164.966235 -65.018914) (xy 164.910761 -65.025017) (xy 164.85499 -65.022979) (xy 164.800111 -65.012842)
			(xy 164.747291 -64.994823) (xy 164.697659 -64.969305) (xy 164.652271 -64.936833) (xy 164.612094 -64.898098)
			(xy 164.577986 -64.853926) (xy 164.550672 -64.805258) (xy 164.530736 -64.753132) (xy 164.518601 -64.698659)
			(xy 164.514528 -64.643) (xy 162.59175 -64.643) (xy 162.59175 -65.110614) (xy 162.592177 -65.120682)
			(xy 162.599901 -65.139278) (xy 162.606736 -65.146682) (xy 163.296854 -65.8368) (xy 163.303705 -65.844196)
			(xy 163.311447 -65.862795) (xy 163.31184 -65.872868) (xy 163.31184 -68.678298) (xy 163.311416 -68.688367)
			(xy 163.303695 -68.706966) (xy 163.296854 -68.714366) (xy 162.823144 -69.188076) (xy 162.815743 -69.194916)
			(xy 162.797145 -69.202634) (xy 162.787076 -69.203062) (xy 161.88436 -69.203062) (xy 161.865564 -69.210682)
			(xy 161.858452 -69.218048) (xy 161.839148 -69.237352) (xy 161.832305 -69.244751) (xy 161.824582 -69.26335)
			(xy 161.824162 -69.27342) (xy 161.824162 -69.632576) (xy 161.824601 -69.642639) (xy 161.832341 -69.661217)
			(xy 161.839148 -69.668644) (xy 161.883598 -69.713094) (xy 161.890996 -69.719942) (xy 161.909594 -69.727678)
			(xy 161.919666 -69.72808) (xy 162.72129 -69.72808) (xy 162.731361 -69.728501) (xy 162.74997 -69.73621)
			(xy 162.757358 -69.743066) (xy 162.841686 -69.827394) (xy 162.848535 -69.834791) (xy 162.856274 -69.85339)
			(xy 162.856672 -69.863462) (xy 162.856672 -71.793608) (xy 162.856247 -71.803677) (xy 162.848527 -71.822277)
			(xy 162.841686 -71.829676) (xy 162.674554 -71.996808) (xy 162.667153 -72.003646) (xy 162.648555 -72.011363)
			(xy 162.638486 -72.011794) (xy 161.880804 -72.011794) (xy 161.862008 -72.019414) (xy 161.854896 -72.02678)
			(xy 161.852102 -72.029574) (xy 161.844736 -72.036686) (xy 161.837116 -72.055482) (xy 161.837116 -73.78827)
			(xy 161.837552 -73.798334) (xy 161.845286 -73.816919) (xy 161.852102 -73.824338) (xy 161.89071 -73.862946)
			(xy 161.898106 -73.869797) (xy 161.916705 -73.877536) (xy 161.926778 -73.877932) (xy 162.756596 -73.877932)
			(xy 162.766666 -73.878355) (xy 162.785268 -73.886072) (xy 162.792664 -73.892918) (xy 162.969956 -74.07021)
			(xy 162.976806 -74.077607) (xy 162.984543 -74.096205) (xy 162.984942 -74.106278) (xy 162.984942 -75.981306)
			(xy 162.985368 -75.991375) (xy 162.993088 -76.009974) (xy 162.999928 -76.017374) (xy 163.680394 -76.69784)
			(xy 163.687235 -76.70524) (xy 163.694956 -76.723839) (xy 163.69538 -76.733908) (xy 163.69538 -77.940916)
			(xy 163.694953 -77.950984) (xy 163.687233 -77.969583) (xy 163.680394 -77.976984) (xy 163.509452 -78.147926)
			(xy 163.502604 -78.155324) (xy 163.494871 -78.173922) (xy 163.494466 -78.183994) (xy 163.494466 -79.015336)
			(xy 163.494036 -79.025403) (xy 163.486308 -79.043994) (xy 163.47948 -79.051404) (xy 163.056316 -79.474568)
			(xy 163.048915 -79.481405) (xy 163.030316 -79.489114) (xy 163.020248 -79.489554) (xy 154.94254 -79.489554)
			(xy 154.932476 -79.489119) (xy 154.913891 -79.481384) (xy 154.906472 -79.474568) (xy 154.667712 -79.235808)
			(xy 154.660863 -79.228411) (xy 154.653124 -79.209813) (xy 154.652726 -79.19974) (xy 154.652726 -78.592426)
			(xy 154.645106 -78.57363) (xy 154.63774 -78.566518) (xy 154.001216 -77.929994) (xy 153.994369 -77.922596)
			(xy 153.986634 -77.903998) (xy 153.98623 -77.893926) (xy 153.98623 -75.674474) (xy 153.986659 -75.664407)
			(xy 153.994383 -75.645812) (xy 154.001216 -75.638406) (xy 154.997404 -74.642218) (xy 155.004237 -74.634815)
			(xy 155.011941 -74.616217) (xy 155.01239 -74.60615) (xy 155.01239 -72.8853) (xy 155.012813 -72.87523)
			(xy 155.020526 -72.856624) (xy 155.027376 -72.849232) (xy 155.039568 -72.83704) (xy 155.046968 -72.8302)
			(xy 155.065567 -72.822484) (xy 155.075636 -72.822054) (xy 156.783532 -72.822054) (xy 156.793546 -72.821628)
			(xy 156.812044 -72.813951) (xy 156.826195 -72.799778) (xy 156.833844 -72.781268) (xy 156.834332 -72.771254)
			(xy 156.834332 -67.434206) (xy 156.826712 -67.41541) (xy 156.819346 -67.408298) (xy 156.79674 -67.385692)
			(xy 156.789338 -67.378856) (xy 156.77074 -67.371144) (xy 156.760672 -67.370706) (xy 156.069284 -67.370706)
			(xy 156.059215 -67.37028) (xy 156.040614 -67.362563) (xy 156.033216 -67.35572) (xy 156.023818 -67.346322)
			(xy 156.016982 -67.33892) (xy 156.009273 -67.320322) (xy 156.008832 -67.310254) (xy 156.008832 -64.26073)
			(xy 156.001212 -64.241934) (xy 155.993846 -64.234822) (xy 154.850084 -63.09106) (xy 154.843235 -63.083663)
			(xy 154.835501 -63.065064) (xy 154.835098 -63.054992) (xy 154.835098 -60.544964) (xy 154.827478 -60.526168)
			(xy 154.820112 -60.519056) (xy 154.812238 -60.511182) (xy 154.80484 -60.504337) (xy 154.786241 -60.496612)
			(xy 154.77617 -60.496196) (xy 154.036522 -60.496196) (xy 154.026498 -60.496612) (xy 154.007972 -60.504278)
			(xy 153.993792 -60.51845) (xy 153.986117 -60.536972) (xy 153.985722 -60.546996) (xy 153.985722 -61.381894)
			(xy 153.986145 -61.391964) (xy 153.99386 -61.410568) (xy 154.000708 -61.417962) (xy 154.067256 -61.48451)
			(xy 154.074106 -61.491907) (xy 154.081843 -61.510505) (xy 154.082242 -61.520578) (xy 154.082242 -63.592202)
			(xy 154.082667 -63.602271) (xy 154.090386 -63.620871) (xy 154.097228 -63.62827) (xy 154.104848 -63.63589)
			(xy 154.112249 -63.64273) (xy 154.130847 -63.650449) (xy 154.140916 -63.650876) (xy 154.609292 -63.650876)
			(xy 154.619363 -63.651297) (xy 154.637972 -63.659007) (xy 154.64536 -63.665862) (xy 155.41625 -64.436752)
			(xy 155.423094 -64.444151) (xy 155.430817 -64.46275) (xy 155.431236 -64.47282) (xy 155.431236 -65.725548)
			(xy 155.430802 -65.735613) (xy 155.423069 -65.754199) (xy 155.41625 -65.761616) (xy 155.20035 -65.977516)
			(xy 155.193501 -65.984913) (xy 155.185764 -66.003512) (xy 155.185364 -66.013584) (xy 155.185364 -67.300348)
			(xy 155.184931 -67.310414) (xy 155.177201 -67.329002) (xy 155.170378 -67.336416) (xy 155.144216 -67.362578)
			(xy 155.136814 -67.369414) (xy 155.118215 -67.377121) (xy 155.108148 -67.377564) (xy 153.497788 -67.377564)
			(xy 153.478992 -67.385184) (xy 153.47188 -67.39255) (xy 153.150062 -67.714368) (xy 153.143219 -67.721767)
			(xy 153.1355 -67.740366) (xy 153.135076 -67.750436) (xy 153.135076 -72.77227) (xy 153.13549 -72.782297)
			(xy 153.143154 -72.800828) (xy 153.157326 -72.815016) (xy 153.175849 -72.822699) (xy 153.185876 -72.82307)
			(xy 154.608784 -72.82307) (xy 154.618834 -72.823576) (xy 154.637394 -72.831298) (xy 154.644852 -72.838056)
			(xy 154.67584 -72.869044) (xy 154.682686 -72.876442) (xy 154.690414 -72.895041) (xy 154.690826 -72.905112)
			(xy 154.690826 -74.350118) (xy 154.6904 -74.360187) (xy 154.682684 -74.37879) (xy 154.67584 -74.386186)
			(xy 154.187652 -74.874374) (xy 154.180252 -74.881215) (xy 154.161654 -74.888937) (xy 154.151584 -74.88936)
			(xy 153.844752 -74.88936) (xy 153.825956 -74.89698) (xy 153.818844 -74.904346) (xy 153.287222 -75.435968)
			(xy 153.280384 -75.443369) (xy 153.272671 -75.461968) (xy 153.272236 -75.472036) (xy 153.272236 -78.219554)
			(xy 153.27267 -78.229619) (xy 153.280402 -78.248206) (xy 153.287222 -78.255622) (xy 153.44775 -78.41615)
			(xy 153.454594 -78.423549) (xy 153.462318 -78.442148) (xy 153.462736 -78.452218) (xy 153.462736 -79.756)
			(xy 164.478714 -79.756) (xy 164.482787 -79.700341) (xy 164.494922 -79.645868) (xy 164.514858 -79.593742)
			(xy 164.542172 -79.545074) (xy 164.57628 -79.500902) (xy 164.616457 -79.462167) (xy 164.661845 -79.429695)
			(xy 164.711477 -79.404177) (xy 164.764297 -79.386158) (xy 164.819176 -79.376021) (xy 164.874947 -79.373983)
			(xy 164.930421 -79.380086) (xy 164.984414 -79.394202) (xy 165.035777 -79.416029) (xy 165.083415 -79.445102)
			(xy 165.126311 -79.480801) (xy 165.163553 -79.522365) (xy 165.194347 -79.568909) (xy 165.218035 -79.61944)
			(xy 165.234113 -79.672882) (xy 165.242239 -79.728096) (xy 165.242748 -79.756) (xy 165.242239 -79.783904)
			(xy 165.234113 -79.839118) (xy 165.218035 -79.89256) (xy 165.194347 -79.943091) (xy 165.163553 -79.989635)
			(xy 165.126311 -80.031199) (xy 165.083415 -80.066898) (xy 165.035777 -80.095971) (xy 164.984414 -80.117798)
			(xy 164.930421 -80.131914) (xy 164.874947 -80.138017) (xy 164.819176 -80.135979) (xy 164.764297 -80.125842)
			(xy 164.711477 -80.107823) (xy 164.661845 -80.082305) (xy 164.616457 -80.049833) (xy 164.57628 -80.011098)
			(xy 164.542172 -79.966926) (xy 164.514858 -79.918258) (xy 164.494922 -79.866132) (xy 164.482787 -79.811659)
			(xy 164.478714 -79.756) (xy 153.462736 -79.756) (xy 153.462736 -81.28) (xy 166.984678 -81.28) (xy 166.988751 -81.224341)
			(xy 167.000886 -81.169868) (xy 167.020822 -81.117742) (xy 167.048136 -81.069074) (xy 167.082244 -81.024902)
			(xy 167.122421 -80.986167) (xy 167.167809 -80.953695) (xy 167.217441 -80.928177) (xy 167.270261 -80.910158)
			(xy 167.32514 -80.900021) (xy 167.380911 -80.897983) (xy 167.436385 -80.904086) (xy 167.490378 -80.918202)
			(xy 167.541741 -80.940029) (xy 167.589379 -80.969102) (xy 167.632275 -81.004801) (xy 167.669517 -81.046365)
			(xy 167.700311 -81.092909) (xy 167.723999 -81.14344) (xy 167.740077 -81.196882) (xy 167.748203 -81.252096)
			(xy 167.748712 -81.28) (xy 167.784778 -81.28) (xy 167.788851 -81.224341) (xy 167.800986 -81.169868)
			(xy 167.820922 -81.117742) (xy 167.848236 -81.069074) (xy 167.882344 -81.024902) (xy 167.922521 -80.986167)
			(xy 167.967909 -80.953695) (xy 168.017541 -80.928177) (xy 168.070361 -80.910158) (xy 168.12524 -80.900021)
			(xy 168.181011 -80.897983) (xy 168.236485 -80.904086) (xy 168.290478 -80.918202) (xy 168.341841 -80.940029)
			(xy 168.389479 -80.969102) (xy 168.432375 -81.004801) (xy 168.469617 -81.046365) (xy 168.500411 -81.092909)
			(xy 168.524099 -81.14344) (xy 168.540177 -81.196882) (xy 168.548303 -81.252096) (xy 168.548812 -81.28)
			(xy 168.548303 -81.307904) (xy 168.540177 -81.363118) (xy 168.524099 -81.41656) (xy 168.500411 -81.467091)
			(xy 168.469617 -81.513635) (xy 168.432375 -81.555199) (xy 168.389479 -81.590898) (xy 168.341841 -81.619971)
			(xy 168.290478 -81.641798) (xy 168.236485 -81.655914) (xy 168.181011 -81.662017) (xy 168.12524 -81.659979)
			(xy 168.070361 -81.649842) (xy 168.017541 -81.631823) (xy 167.967909 -81.606305) (xy 167.922521 -81.573833)
			(xy 167.882344 -81.535098) (xy 167.848236 -81.490926) (xy 167.820922 -81.442258) (xy 167.800986 -81.390132)
			(xy 167.788851 -81.335659) (xy 167.784778 -81.28) (xy 167.748712 -81.28) (xy 167.748203 -81.307904)
			(xy 167.740077 -81.363118) (xy 167.723999 -81.41656) (xy 167.700311 -81.467091) (xy 167.669517 -81.513635)
			(xy 167.632275 -81.555199) (xy 167.589379 -81.590898) (xy 167.541741 -81.619971) (xy 167.490378 -81.641798)
			(xy 167.436385 -81.655914) (xy 167.380911 -81.662017) (xy 167.32514 -81.659979) (xy 167.270261 -81.649842)
			(xy 167.217441 -81.631823) (xy 167.167809 -81.606305) (xy 167.122421 -81.573833) (xy 167.082244 -81.535098)
			(xy 167.048136 -81.490926) (xy 167.020822 -81.442258) (xy 167.000886 -81.390132) (xy 166.988751 -81.335659)
			(xy 166.984678 -81.28) (xy 153.462736 -81.28) (xy 153.462736 -82.04581) (xy 153.463162 -82.055879)
			(xy 153.470883 -82.074477) (xy 153.477722 -82.081878) (xy 157.278578 -85.882734) (xy 157.283986 -85.802494)
			(xy 157.30163 -85.642623) (xy 157.327035 -85.483801) (xy 157.360141 -85.326404) (xy 157.40087 -85.170804)
			(xy 157.449125 -85.017372) (xy 157.504791 -84.866471) (xy 157.567737 -84.718458) (xy 157.637813 -84.573685)
			(xy 157.714853 -84.432495) (xy 157.798675 -84.295222) (xy 157.88908 -84.162192) (xy 157.985853 -84.033721)
			(xy 158.088766 -83.910112) (xy 158.197573 -83.79166) (xy 158.312017 -83.678645) (xy 158.431827 -83.571335)
			(xy 158.556719 -83.469984) (xy 158.686396 -83.374833) (xy 158.820552 -83.286107) (xy 158.958867 -83.204016)
			(xy 159.101014 -83.128756) (xy 159.246656 -83.060505) (xy 159.395448 -82.999424) (xy 159.547037 -82.945658)
			(xy 159.701064 -82.899335) (xy 159.857163 -82.860565) (xy 160.014963 -82.82944) (xy 160.174092 -82.806032)
			(xy 160.334172 -82.790399) (xy 160.494823 -82.782576) (xy 160.575244 -82.782156) (xy 160.656309 -82.782654)
			(xy 160.818244 -82.790612) (xy 160.979594 -82.806506) (xy 161.139969 -82.830297) (xy 161.298984 -82.861929)
			(xy 161.456255 -82.901325) (xy 161.611403 -82.948391) (xy 161.764056 -83.003013) (xy 161.913844 -83.065059)
			(xy 162.060407 -83.134381) (xy 162.203393 -83.21081) (xy 162.342456 -83.294163) (xy 162.477261 -83.384239)
			(xy 162.607485 -83.480822) (xy 162.732812 -83.583677) (xy 162.852942 -83.692559) (xy 162.967584 -83.807203)
			(xy 162.996448 -83.83905) (xy 166.623238 -83.83905) (xy 166.623685 -83.81246) (xy 166.631079 -83.759796)
			(xy 166.645703 -83.708666) (xy 166.667274 -83.660057) (xy 166.695377 -83.614908) (xy 166.729467 -83.574092)
			(xy 166.768887 -83.538396) (xy 166.790624 -83.523074) (xy 166.802102 -83.514738) (xy 166.820301 -83.492993)
			(xy 166.831815 -83.467081) (xy 166.835754 -83.439) (xy 166.831815 -83.410919) (xy 166.820301 -83.385007)
			(xy 166.802102 -83.363262) (xy 166.790624 -83.354926) (xy 166.768875 -83.33962) (xy 166.729444 -83.303931)
			(xy 166.695347 -83.263116) (xy 166.667244 -83.217964) (xy 166.645678 -83.169349) (xy 166.631068 -83.118212)
			(xy 166.623694 -83.065542) (xy 166.623238 -83.03895) (xy 166.623724 -83.011681) (xy 166.631486 -82.957697)
			(xy 166.646851 -82.905367) (xy 166.669508 -82.855757) (xy 166.698994 -82.809876) (xy 166.734709 -82.768659)
			(xy 166.775926 -82.732944) (xy 166.821807 -82.703458) (xy 166.871417 -82.680801) (xy 166.923747 -82.665436)
			(xy 166.977731 -82.657674) (xy 167.032269 -82.657674) (xy 167.086253 -82.665436) (xy 167.138583 -82.680801)
			(xy 167.188193 -82.703458) (xy 167.234074 -82.732944) (xy 167.275291 -82.768659) (xy 167.311006 -82.809876)
			(xy 167.340492 -82.855757) (xy 167.363149 -82.905367) (xy 167.378514 -82.957697) (xy 167.386276 -83.011681)
			(xy 167.386762 -83.03895) (xy 167.386315 -83.06554) (xy 167.378921 -83.118204) (xy 167.364297 -83.169334)
			(xy 167.342726 -83.217943) (xy 167.314623 -83.263092) (xy 167.280533 -83.303908) (xy 167.241113 -83.339604)
			(xy 167.219376 -83.354926) (xy 167.207898 -83.363262) (xy 167.189699 -83.385007) (xy 167.178185 -83.410919)
			(xy 167.174246 -83.439) (xy 167.178185 -83.467081) (xy 167.189699 -83.492993) (xy 167.207898 -83.514738)
			(xy 167.219376 -83.523074) (xy 167.241125 -83.53838) (xy 167.280556 -83.574069) (xy 167.314653 -83.614884)
			(xy 167.342756 -83.660036) (xy 167.364322 -83.708651) (xy 167.378932 -83.759788) (xy 167.386306 -83.812458)
			(xy 167.386762 -83.83905) (xy 167.386276 -83.866319) (xy 167.378514 -83.920303) (xy 167.363149 -83.972633)
			(xy 167.340492 -84.022243) (xy 167.311006 -84.068124) (xy 167.275291 -84.109341) (xy 167.234074 -84.145056)
			(xy 167.188193 -84.174542) (xy 167.138583 -84.197199) (xy 167.086253 -84.212564) (xy 167.032269 -84.220326)
			(xy 166.977731 -84.220326) (xy 166.923747 -84.212564) (xy 166.871417 -84.197199) (xy 166.821807 -84.174542)
			(xy 166.775926 -84.145056) (xy 166.734709 -84.109341) (xy 166.698994 -84.068124) (xy 166.669508 -84.022243)
			(xy 166.646851 -83.972633) (xy 166.631486 -83.920303) (xy 166.623724 -83.866319) (xy 166.623238 -83.83905)
			(xy 162.996448 -83.83905) (xy 163.076463 -83.927335) (xy 163.179316 -84.052664) (xy 163.275896 -84.18289)
			(xy 163.36597 -84.317697) (xy 163.449321 -84.456761) (xy 163.525747 -84.599748) (xy 163.595066 -84.746313)
			(xy 163.657109 -84.896102) (xy 163.711728 -85.048756) (xy 163.758791 -85.203905) (xy 163.798185 -85.361177)
			(xy 163.829814 -85.520192) (xy 163.853602 -85.680568) (xy 163.869493 -85.841918) (xy 163.877447 -86.003853)
			(xy 163.878006 -86.084918) (xy 163.87699 -86.16442) (xy 178.572922 -86.16442)
		)
		(stroke
			(width 0)
			(type solid)
		)
		(fill yes)
		(layer "B.Cu")
		(net "GND1_FIELD_SIGNAL")
	)
	(gr_poly
		(pts
			(xy 29.442918 -155.575) (xy 29.452987 -155.574573) (xy 29.471586 -155.566854) (xy 29.478986 -155.560014)
			(xy 30.338014 -154.700986) (xy 30.344868 -154.693591) (xy 30.35261 -154.674992) (xy 30.353 -154.664918)
			(xy 30.353 -38.629082) (xy 30.353427 -38.619013) (xy 30.361146 -38.600414) (xy 30.367986 -38.593014)
			(xy 34.294826 -34.666174) (xy 34.301805 -34.658577) (xy 34.309522 -34.639468) (xy 34.309055 -34.618864)
			(xy 34.30524 -34.609278) (xy 34.259774 -34.507932) (xy 34.23285 -34.49193) (xy 34.216848 -34.492946)
			(xy 34.1884 -34.493708) (xy 34.158432 -34.493218) (xy 34.09901 -34.485395) (xy 34.041117 -34.469882)
			(xy 33.985744 -34.446946) (xy 33.933838 -34.416979) (xy 33.886288 -34.380492) (xy 33.843908 -34.338112)
			(xy 33.807421 -34.290562) (xy 33.777454 -34.238656) (xy 33.754518 -34.183283) (xy 33.739005 -34.12539)
			(xy 33.731182 -34.065968) (xy 33.731182 -34.006032) (xy 33.739005 -33.94661) (xy 33.754518 -33.888717)
			(xy 33.777454 -33.833344) (xy 33.807421 -33.781438) (xy 33.843908 -33.733888) (xy 33.886288 -33.691508)
			(xy 33.933838 -33.655021) (xy 33.985744 -33.625054) (xy 34.041117 -33.602118) (xy 34.09901 -33.586605)
			(xy 34.158432 -33.578782) (xy 34.218368 -33.578782) (xy 34.27779 -33.586605) (xy 34.335683 -33.602118)
			(xy 34.391056 -33.625054) (xy 34.442962 -33.655021) (xy 34.490512 -33.691508) (xy 34.532892 -33.733888)
			(xy 34.569379 -33.781438) (xy 34.599346 -33.833344) (xy 34.622282 -33.888717) (xy 34.637795 -33.94661)
			(xy 34.645618 -34.006032) (xy 34.646108 -34.036) (xy 34.645346 -34.064448) (xy 34.64433 -34.08045)
			(xy 34.660332 -34.107374) (xy 34.761678 -34.15284) (xy 34.771261 -34.15661) (xy 34.791833 -34.156997)
			(xy 34.810923 -34.149323) (xy 34.818574 -34.142426) (xy 37.669216 -31.291784) (xy 37.676611 -31.284931)
			(xy 37.69521 -31.277189) (xy 37.705284 -31.276798) (xy 54.780688 -31.276798) (xy 54.790759 -31.276377)
			(xy 54.809366 -31.268665) (xy 54.816756 -31.261812) (xy 59.6265 -26.452068) (xy 59.633895 -26.445214)
			(xy 59.652494 -26.437469) (xy 59.662568 -26.437082) (xy 73.291446 -26.437082) (xy 73.301512 -26.43665)
			(xy 73.320103 -26.428922) (xy 73.327514 -26.422096) (xy 78.319376 -21.430234) (xy 78.326777 -21.423396)
			(xy 78.345376 -21.415684) (xy 78.355444 -21.415248) (xy 88.965278 -21.415248) (xy 88.975341 -21.414809)
			(xy 88.99392 -21.407069) (xy 89.001346 -21.400262) (xy 99.095306 -11.306302) (xy 99.102705 -11.299456)
			(xy 99.121303 -11.291724) (xy 99.131374 -11.291316) (xy 144.88414 -11.291316) (xy 145.276824 -11.684)
			(xy 160.122616 -11.684) (xy 162.97529 -14.536674) (xy 162.97529 -25.344882) (xy 162.975728 -25.354946)
			(xy 162.983462 -25.37353) (xy 162.990276 -25.38095) (xy 163.33597 -25.726644) (xy 163.343369 -25.733486)
			(xy 163.361968 -25.741203) (xy 163.372038 -25.74163) (xy 206.004414 -25.74163) (xy 206.014686 -25.741158)
			(xy 206.033586 -25.733108) (xy 206.047823 -25.718298) (xy 206.051912 -25.708864) (xy 206.091282 -25.604978)
			(xy 206.083916 -25.574752) (xy 206.071724 -25.564084) (xy 206.003329 -25.502767) (xy 205.871422 -25.374901)
			(xy 205.745333 -25.241294) (xy 205.625312 -25.10221) (xy 205.511597 -24.957925) (xy 205.404413 -24.808724)
			(xy 205.303972 -24.654904) (xy 205.210473 -24.496767) (xy 205.124101 -24.334628) (xy 205.045027 -24.168807)
			(xy 204.973407 -23.999632) (xy 204.909384 -23.82744) (xy 204.853084 -23.652569) (xy 204.804619 -23.475368)
			(xy 204.764084 -23.296186) (xy 204.73156 -23.115378) (xy 204.707111 -22.933302) (xy 204.690786 -22.750319)
			(xy 204.682617 -22.566791) (xy 204.68209 -22.474936) (xy 204.682595 -22.383605) (xy 204.690675 -22.201121)
			(xy 204.706819 -22.019173) (xy 204.730995 -21.838117) (xy 204.763156 -21.658308) (xy 204.803239 -21.480098)
			(xy 204.851166 -21.303835) (xy 204.906843 -21.129864) (xy 204.97016 -20.958527) (xy 205.040995 -20.790158)
			(xy 205.119207 -20.625086) (xy 205.204645 -20.463637) (xy 205.29714 -20.306124) (xy 205.396512 -20.152857)
			(xy 205.502567 -20.004135) (xy 205.615096 -19.86025) (xy 205.733879 -19.721484) (xy 205.858685 -19.588108)
			(xy 205.989267 -19.460382) (xy 206.125372 -19.338558) (xy 206.266732 -19.222873) (xy 206.413071 -19.113555)
			(xy 206.564103 -19.010816) (xy 206.719531 -18.914859) (xy 206.879051 -18.825871) (xy 207.042351 -18.744026)
			(xy 207.209112 -18.669484) (xy 207.379007 -18.602392) (xy 207.551703 -18.54288) (xy 207.726863 -18.491066)
			(xy 207.904143 -18.44705) (xy 208.083197 -18.410919) (xy 208.263673 -18.382743) (xy 208.44522 -18.362579)
			(xy 208.62748 -18.350464) (xy 208.810098 -18.346423) (xy 208.992716 -18.350464) (xy 209.174976 -18.362579)
			(xy 209.356523 -18.382743) (xy 209.536999 -18.410919) (xy 209.716053 -18.44705) (xy 209.893333 -18.491066)
			(xy 210.068493 -18.54288) (xy 210.241189 -18.602392) (xy 210.411084 -18.669484) (xy 210.577845 -18.744026)
			(xy 210.741145 -18.825871) (xy 210.900665 -18.914859) (xy 211.056093 -19.010816) (xy 211.207125 -19.113555)
			(xy 211.353464 -19.222873) (xy 211.494824 -19.338558) (xy 211.630929 -19.460382) (xy 211.761511 -19.588108)
			(xy 211.886317 -19.721484) (xy 212.0051 -19.86025) (xy 212.117629 -20.004135) (xy 212.223684 -20.152857)
			(xy 212.323056 -20.306124) (xy 212.415551 -20.463637) (xy 212.500989 -20.625086) (xy 212.579201 -20.790158)
			(xy 212.650036 -20.958527) (xy 212.713353 -21.129864) (xy 212.76903 -21.303835) (xy 212.816957 -21.480098)
			(xy 212.85704 -21.658308) (xy 212.889201 -21.838117) (xy 212.913377 -22.019173) (xy 212.929521 -22.201121)
			(xy 212.937601 -22.383605) (xy 212.938106 -22.474936) (xy 212.937605 -22.566792) (xy 212.929447 -22.750324)
			(xy 212.913132 -22.933311) (xy 212.888693 -23.115391) (xy 212.856176 -23.296204) (xy 212.815648 -23.47539)
			(xy 212.767187 -23.652596) (xy 212.71089 -23.827471) (xy 212.646869 -23.999667) (xy 212.57525 -24.168845)
			(xy 212.496175 -24.334669) (xy 212.4098 -24.496811) (xy 212.316298 -24.654949) (xy 212.215852 -24.80877)
			(xy 212.108662 -24.957971) (xy 211.99494 -25.102255) (xy 211.874912 -25.241336) (xy 211.748815 -25.374939)
			(xy 211.616898 -25.5028) (xy 211.548472 -25.564084) (xy 211.53628 -25.574752) (xy 211.528914 -25.604978)
			(xy 211.568284 -25.708864) (xy 211.572372 -25.718299) (xy 211.58661 -25.733109) (xy 211.60551 -25.741161)
			(xy 211.615782 -25.74163) (xy 218.198954 -25.74163) (xy 218.209021 -25.741198) (xy 218.227614 -25.733473)
			(xy 218.235022 -25.726644) (xy 218.679014 -25.282652) (xy 218.685862 -25.275255) (xy 218.693593 -25.256656)
			(xy 218.694 -25.246584) (xy 218.694 -9.56056) (xy 218.693569 -9.550493) (xy 218.685845 -9.531899)
			(xy 218.679014 -9.524492) (xy 218.399868 -9.245346) (xy 218.39247 -9.2385) (xy 218.373871 -9.23077)
			(xy 218.3638 -9.23036) (xy 90.071448 -9.23036) (xy 85.428582 -9.23036) (xy 61.067442 -9.23036) (xy 61.057377 -9.229925)
			(xy 61.038792 -9.222191) (xy 61.031374 -9.215374) (xy 53.989986 -2.173986) (xy 53.982591 -2.167132)
			(xy 53.963992 -2.15939) (xy 53.953918 -2.159) (xy 4.466082 -2.159) (xy 4.456013 -2.159427) (xy 4.437414 -2.167146)
			(xy 4.430014 -2.173986) (xy 2.173986 -4.430014) (xy 2.167132 -4.437409) (xy 2.15939 -4.456008) (xy 2.159 -4.466082)
			(xy 2.159 -14.761968) (xy 80.060782 -14.761968) (xy 80.060782 -14.702032) (xy 80.068605 -14.64261)
			(xy 80.084118 -14.584717) (xy 80.107054 -14.529344) (xy 80.137021 -14.477438) (xy 80.173508 -14.429888)
			(xy 80.215888 -14.387508) (xy 80.263438 -14.351021) (xy 80.315344 -14.321054) (xy 80.370717 -14.298118)
			(xy 80.42861 -14.282605) (xy 80.488032 -14.274782) (xy 80.547968 -14.274782) (xy 80.60739 -14.282605)
			(xy 80.665283 -14.298118) (xy 80.720656 -14.321054) (xy 80.772562 -14.351021) (xy 80.820112 -14.387508)
			(xy 80.862492 -14.429888) (xy 80.898979 -14.477438) (xy 80.928946 -14.529344) (xy 80.951882 -14.584717)
			(xy 80.967395 -14.64261) (xy 80.975218 -14.702032) (xy 80.975708 -14.732) (xy 80.975218 -14.761968)
			(xy 80.967395 -14.82139) (xy 80.951882 -14.879283) (xy 80.928946 -14.934656) (xy 80.898979 -14.986562)
			(xy 80.862492 -15.034112) (xy 80.820112 -15.076492) (xy 80.772562 -15.112979) (xy 80.720656 -15.142946)
			(xy 80.665283 -15.165882) (xy 80.60739 -15.181395) (xy 80.547968 -15.189218) (xy 80.488032 -15.189218)
			(xy 80.42861 -15.181395) (xy 80.370717 -15.165882) (xy 80.315344 -15.142946) (xy 80.263438 -15.112979)
			(xy 80.215888 -15.076492) (xy 80.173508 -15.034112) (xy 80.137021 -14.986562) (xy 80.107054 -14.934656)
			(xy 80.084118 -14.879283) (xy 80.068605 -14.82139) (xy 80.060782 -14.761968) (xy 2.159 -14.761968)
			(xy 2.159 -16.383) (xy 80.135982 -16.383) (xy 80.140053 -16.327378) (xy 80.152179 -16.272941) (xy 80.172102 -16.22085)
			(xy 80.199398 -16.172215) (xy 80.233484 -16.128072) (xy 80.273633 -16.089363) (xy 80.318991 -16.056912)
			(xy 80.368591 -16.031411) (xy 80.421375 -16.013404) (xy 80.476218 -16.003274) (xy 80.531952 -16.001237)
			(xy 80.587389 -16.007337) (xy 80.641346 -16.021443) (xy 80.692675 -16.043255) (xy 80.740281 -16.072309)
			(xy 80.783149 -16.107984) (xy 80.820366 -16.149521) (xy 80.851139 -16.196034) (xy 80.874811 -16.246531)
			(xy 80.87766 -16.256) (xy 82.193382 -16.256) (xy 82.197453 -16.200378) (xy 82.209579 -16.145941)
			(xy 82.229502 -16.09385) (xy 82.256798 -16.045215) (xy 82.290884 -16.001072) (xy 82.331033 -15.962363)
			(xy 82.376391 -15.929912) (xy 82.425991 -15.904411) (xy 82.478775 -15.886404) (xy 82.533618 -15.876274)
			(xy 82.589352 -15.874237) (xy 82.644789 -15.880337) (xy 82.698746 -15.894443) (xy 82.750075 -15.916255)
			(xy 82.797681 -15.945309) (xy 82.840549 -15.980984) (xy 82.877766 -16.022521) (xy 82.908539 -16.069034)
			(xy 82.926884 -16.108168) (xy 83.997782 -16.108168) (xy 83.997782 -16.048232) (xy 84.005605 -15.98881)
			(xy 84.021118 -15.930917) (xy 84.044054 -15.875544) (xy 84.074021 -15.823638) (xy 84.110508 -15.776088)
			(xy 84.152888 -15.733708) (xy 84.200438 -15.697221) (xy 84.252344 -15.667254) (xy 84.307717 -15.644318)
			(xy 84.36561 -15.628805) (xy 84.425032 -15.620982) (xy 84.484968 -15.620982) (xy 84.54439 -15.628805)
			(xy 84.602283 -15.644318) (xy 84.657656 -15.667254) (xy 84.709562 -15.697221) (xy 84.757112 -15.733708)
			(xy 84.799492 -15.776088) (xy 84.835979 -15.823638) (xy 84.865946 -15.875544) (xy 84.888882 -15.930917)
			(xy 84.904395 -15.98881) (xy 84.912218 -16.048232) (xy 84.912708 -16.0782) (xy 84.912218 -16.108168)
			(xy 84.904395 -16.16759) (xy 84.888882 -16.225483) (xy 84.865946 -16.280856) (xy 84.835979 -16.332762)
			(xy 84.799492 -16.380312) (xy 84.757112 -16.422692) (xy 84.709562 -16.459179) (xy 84.657656 -16.489146)
			(xy 84.602283 -16.512082) (xy 84.54439 -16.527595) (xy 84.484968 -16.535418) (xy 84.425032 -16.535418)
			(xy 84.36561 -16.527595) (xy 84.307717 -16.512082) (xy 84.252344 -16.489146) (xy 84.200438 -16.459179)
			(xy 84.152888 -16.422692) (xy 84.110508 -16.380312) (xy 84.074021 -16.332762) (xy 84.044054 -16.280856)
			(xy 84.021118 -16.225483) (xy 84.005605 -16.16759) (xy 83.997782 -16.108168) (xy 82.926884 -16.108168)
			(xy 82.932211 -16.119531) (xy 82.948279 -16.172938) (xy 82.956399 -16.228114) (xy 82.956908 -16.256)
			(xy 82.956399 -16.283886) (xy 82.948279 -16.339062) (xy 82.932211 -16.392469) (xy 82.908539 -16.442966)
			(xy 82.877766 -16.489479) (xy 82.840549 -16.531016) (xy 82.797681 -16.566691) (xy 82.750075 -16.595745)
			(xy 82.698746 -16.617557) (xy 82.644789 -16.631663) (xy 82.589352 -16.637763) (xy 82.533618 -16.635726)
			(xy 82.478775 -16.625596) (xy 82.425991 -16.607589) (xy 82.376391 -16.582088) (xy 82.331033 -16.549637)
			(xy 82.290884 -16.510928) (xy 82.256798 -16.466785) (xy 82.229502 -16.41815) (xy 82.209579 -16.366059)
			(xy 82.197453 -16.311622) (xy 82.193382 -16.256) (xy 80.87766 -16.256) (xy 80.890879 -16.299938)
			(xy 80.898999 -16.355114) (xy 80.899508 -16.383) (xy 80.898999 -16.410886) (xy 80.890879 -16.466062)
			(xy 80.874811 -16.519469) (xy 80.851139 -16.569966) (xy 80.820366 -16.616479) (xy 80.783149 -16.658016)
			(xy 80.740281 -16.693691) (xy 80.692675 -16.722745) (xy 80.641346 -16.744557) (xy 80.587389 -16.758663)
			(xy 80.531952 -16.764763) (xy 80.476218 -16.762726) (xy 80.421375 -16.752596) (xy 80.368591 -16.734589)
			(xy 80.318991 -16.709088) (xy 80.273633 -16.676637) (xy 80.233484 -16.637928) (xy 80.199398 -16.593785)
			(xy 80.172102 -16.54515) (xy 80.152179 -16.493059) (xy 80.140053 -16.438622) (xy 80.135982 -16.383)
			(xy 2.159 -16.383) (xy 2.159 -16.920968) (xy 81.203782 -16.920968) (xy 81.203782 -16.861032) (xy 81.211605 -16.80161)
			(xy 81.227118 -16.743717) (xy 81.250054 -16.688344) (xy 81.280021 -16.636438) (xy 81.316508 -16.588888)
			(xy 81.358888 -16.546508) (xy 81.406438 -16.510021) (xy 81.458344 -16.480054) (xy 81.513717 -16.457118)
			(xy 81.57161 -16.441605) (xy 81.631032 -16.433782) (xy 81.690968 -16.433782) (xy 81.75039 -16.441605)
			(xy 81.808283 -16.457118) (xy 81.863656 -16.480054) (xy 81.915562 -16.510021) (xy 81.963112 -16.546508)
			(xy 82.005492 -16.588888) (xy 82.041979 -16.636438) (xy 82.071946 -16.688344) (xy 82.094882 -16.743717)
			(xy 82.110395 -16.80161) (xy 82.118218 -16.861032) (xy 82.118708 -16.891) (xy 82.118218 -16.920968)
			(xy 82.110395 -16.98039) (xy 82.094882 -17.038283) (xy 82.071946 -17.093656) (xy 82.041979 -17.145562)
			(xy 82.005492 -17.193112) (xy 81.963112 -17.235492) (xy 81.915562 -17.271979) (xy 81.863656 -17.301946)
			(xy 81.808283 -17.324882) (xy 81.75039 -17.340395) (xy 81.690968 -17.348218) (xy 81.631032 -17.348218)
			(xy 81.57161 -17.340395) (xy 81.513717 -17.324882) (xy 81.458344 -17.301946) (xy 81.406438 -17.271979)
			(xy 81.358888 -17.235492) (xy 81.316508 -17.193112) (xy 81.280021 -17.145562) (xy 81.250054 -17.093656)
			(xy 81.227118 -17.038283) (xy 81.211605 -16.98039) (xy 81.203782 -16.920968) (xy 2.159 -16.920968)
			(xy 2.159 -20.63857) (xy 56.730635 -20.63857) (xy 56.730635 -20.50943) (xy 56.738585 -20.380535)
			(xy 56.754455 -20.252375) (xy 56.778184 -20.125434) (xy 56.809683 -20.000195) (xy 56.848832 -19.877132)
			(xy 56.895483 -19.756713) (xy 56.949458 -19.639394) (xy 57.010553 -19.52562) (xy 57.078536 -19.415823)
			(xy 57.15315 -19.31042) (xy 57.234111 -19.20981) (xy 57.321111 -19.114375) (xy 57.413822 -19.024476)
			(xy 57.511892 -18.940455) (xy 57.614947 -18.862631) (xy 57.722598 -18.791299) (xy 57.834437 -18.726729)
			(xy 57.950038 -18.669167) (xy 58.068963 -18.61883) (xy 58.190762 -18.57591) (xy 58.314972 -18.540569)
			(xy 58.441121 -18.512942) (xy 58.568733 -18.493133) (xy 58.697322 -18.481217) (xy 58.8264 -18.477241)
			(xy 58.955478 -18.481217) (xy 59.084067 -18.493133) (xy 59.211679 -18.512942) (xy 59.337828 -18.540569)
			(xy 59.462038 -18.57591) (xy 59.583837 -18.61883) (xy 59.702762 -18.669167) (xy 59.818363 -18.726729)
			(xy 59.930202 -18.791299) (xy 60.037853 -18.862631) (xy 60.109385 -18.91665) (xy 80.135982 -18.91665)
			(xy 80.140053 -18.861028) (xy 80.152179 -18.806591) (xy 80.172102 -18.7545) (xy 80.199398 -18.705865)
			(xy 80.233484 -18.661722) (xy 80.273633 -18.623013) (xy 80.318991 -18.590562) (xy 80.368591 -18.565061)
			(xy 80.421375 -18.547054) (xy 80.476218 -18.536924) (xy 80.531952 -18.534887) (xy 80.587389 -18.540987)
			(xy 80.641346 -18.555093) (xy 80.692675 -18.576905) (xy 80.740281 -18.605959) (xy 80.783149 -18.641634)
			(xy 80.820366 -18.683171) (xy 80.851139 -18.729684) (xy 80.874811 -18.780181) (xy 80.890879 -18.833588)
			(xy 80.898999 -18.888764) (xy 80.899508 -18.91665) (xy 81.278982 -18.91665) (xy 81.283053 -18.861028)
			(xy 81.295179 -18.806591) (xy 81.315102 -18.7545) (xy 81.342398 -18.705865) (xy 81.376484 -18.661722)
			(xy 81.416633 -18.623013) (xy 81.461991 -18.590562) (xy 81.511591 -18.565061) (xy 81.564375 -18.547054)
			(xy 81.619218 -18.536924) (xy 81.674952 -18.534887) (xy 81.730389 -18.540987) (xy 81.784346 -18.555093)
			(xy 81.835675 -18.576905) (xy 81.883281 -18.605959) (xy 81.926149 -18.641634) (xy 81.963366 -18.683171)
			(xy 81.994139 -18.729684) (xy 82.017811 -18.780181) (xy 82.033879 -18.833588) (xy 82.041999 -18.888764)
			(xy 82.042508 -18.91665) (xy 82.042503 -18.916904) (xy 82.421982 -18.916904) (xy 82.426053 -18.861282)
			(xy 82.438179 -18.806845) (xy 82.458102 -18.754754) (xy 82.485398 -18.706119) (xy 82.519484 -18.661976)
			(xy 82.559633 -18.623267) (xy 82.604991 -18.590816) (xy 82.654591 -18.565315) (xy 82.707375 -18.547308)
			(xy 82.762218 -18.537178) (xy 82.817952 -18.535141) (xy 82.873389 -18.541241) (xy 82.927346 -18.555347)
			(xy 82.978675 -18.577159) (xy 83.026281 -18.606213) (xy 83.069149 -18.641888) (xy 83.106366 -18.683425)
			(xy 83.137139 -18.729938) (xy 83.160811 -18.780435) (xy 83.176879 -18.833842) (xy 83.184999 -18.889018)
			(xy 83.185508 -18.916904) (xy 83.564982 -18.916904) (xy 83.569053 -18.861282) (xy 83.581179 -18.806845)
			(xy 83.601102 -18.754754) (xy 83.628398 -18.706119) (xy 83.662484 -18.661976) (xy 83.702633 -18.623267)
			(xy 83.747991 -18.590816) (xy 83.797591 -18.565315) (xy 83.850375 -18.547308) (xy 83.905218 -18.537178)
			(xy 83.960952 -18.535141) (xy 84.016389 -18.541241) (xy 84.070346 -18.555347) (xy 84.121675 -18.577159)
			(xy 84.169281 -18.606213) (xy 84.212149 -18.641888) (xy 84.249366 -18.683425) (xy 84.280139 -18.729938)
			(xy 84.303811 -18.780435) (xy 84.319879 -18.833842) (xy 84.327999 -18.889018) (xy 84.328508 -18.916904)
			(xy 84.327999 -18.94479) (xy 84.319879 -18.999966) (xy 84.303811 -19.053373) (xy 84.280139 -19.10387)
			(xy 84.249366 -19.150383) (xy 84.212149 -19.19192) (xy 84.169281 -19.227595) (xy 84.121675 -19.256649)
			(xy 84.070346 -19.278461) (xy 84.016389 -19.292567) (xy 83.960952 -19.298667) (xy 83.905218 -19.29663)
			(xy 83.850375 -19.2865) (xy 83.797591 -19.268493) (xy 83.747991 -19.242992) (xy 83.702633 -19.210541)
			(xy 83.662484 -19.171832) (xy 83.628398 -19.127689) (xy 83.601102 -19.079054) (xy 83.581179 -19.026963)
			(xy 83.569053 -18.972526) (xy 83.564982 -18.916904) (xy 83.185508 -18.916904) (xy 83.184999 -18.94479)
			(xy 83.176879 -18.999966) (xy 83.160811 -19.053373) (xy 83.137139 -19.10387) (xy 83.106366 -19.150383)
			(xy 83.069149 -19.19192) (xy 83.026281 -19.227595) (xy 82.978675 -19.256649) (xy 82.927346 -19.278461)
			(xy 82.873389 -19.292567) (xy 82.817952 -19.298667) (xy 82.762218 -19.29663) (xy 82.707375 -19.2865)
			(xy 82.654591 -19.268493) (xy 82.604991 -19.242992) (xy 82.559633 -19.210541) (xy 82.519484 -19.171832)
			(xy 82.485398 -19.127689) (xy 82.458102 -19.079054) (xy 82.438179 -19.026963) (xy 82.426053 -18.972526)
			(xy 82.421982 -18.916904) (xy 82.042503 -18.916904) (xy 82.041999 -18.944536) (xy 82.033879 -18.999712)
			(xy 82.017811 -19.053119) (xy 81.994139 -19.103616) (xy 81.963366 -19.150129) (xy 81.926149 -19.191666)
			(xy 81.883281 -19.227341) (xy 81.835675 -19.256395) (xy 81.784346 -19.278207) (xy 81.730389 -19.292313)
			(xy 81.674952 -19.298413) (xy 81.619218 -19.296376) (xy 81.564375 -19.286246) (xy 81.511591 -19.268239)
			(xy 81.461991 -19.242738) (xy 81.416633 -19.210287) (xy 81.376484 -19.171578) (xy 81.342398 -19.127435)
			(xy 81.315102 -19.0788) (xy 81.295179 -19.026709) (xy 81.283053 -18.972272) (xy 81.278982 -18.91665)
			(xy 80.899508 -18.91665) (xy 80.898999 -18.944536) (xy 80.890879 -18.999712) (xy 80.874811 -19.053119)
			(xy 80.851139 -19.103616) (xy 80.820366 -19.150129) (xy 80.783149 -19.191666) (xy 80.740281 -19.227341)
			(xy 80.692675 -19.256395) (xy 80.641346 -19.278207) (xy 80.587389 -19.292313) (xy 80.531952 -19.298413)
			(xy 80.476218 -19.296376) (xy 80.421375 -19.286246) (xy 80.368591 -19.268239) (xy 80.318991 -19.242738)
			(xy 80.273633 -19.210287) (xy 80.233484 -19.171578) (xy 80.199398 -19.127435) (xy 80.172102 -19.0788)
			(xy 80.152179 -19.026709) (xy 80.140053 -18.972272) (xy 80.135982 -18.91665) (xy 60.109385 -18.91665)
			(xy 60.140908 -18.940455) (xy 60.238978 -19.024476) (xy 60.331689 -19.114375) (xy 60.418689 -19.20981)
			(xy 60.49965 -19.31042) (xy 60.574264 -19.415823) (xy 60.642247 -19.52562) (xy 60.703342 -19.639394)
			(xy 60.757317 -19.756713) (xy 60.803968 -19.877132) (xy 60.843117 -20.000195) (xy 60.874616 -20.125434)
			(xy 60.898345 -20.252375) (xy 60.914215 -20.380535) (xy 60.922165 -20.50943) (xy 60.922662 -20.574)
			(xy 60.922165 -20.63857) (xy 60.914215 -20.767465) (xy 60.898345 -20.895625) (xy 60.874616 -21.022566)
			(xy 60.843117 -21.147805) (xy 60.803968 -21.270868) (xy 60.757317 -21.391287) (xy 60.703342 -21.508606)
			(xy 60.642247 -21.62238) (xy 60.574264 -21.732177) (xy 60.49965 -21.83758) (xy 60.418689 -21.93819)
			(xy 60.331689 -22.033625) (xy 60.238978 -22.123524) (xy 60.140908 -22.207545) (xy 60.037853 -22.285369)
			(xy 59.930202 -22.356701) (xy 59.818363 -22.421271) (xy 59.702762 -22.478833) (xy 59.583837 -22.52917)
			(xy 59.462038 -22.57209) (xy 59.337828 -22.607431) (xy 59.211679 -22.635058) (xy 59.084067 -22.654867)
			(xy 58.955478 -22.666783) (xy 58.8264 -22.67076) (xy 58.697322 -22.666783) (xy 58.568733 -22.654867)
			(xy 58.441121 -22.635058) (xy 58.314972 -22.607431) (xy 58.190762 -22.57209) (xy 58.068963 -22.52917)
			(xy 57.950038 -22.478833) (xy 57.834437 -22.421271) (xy 57.722598 -22.356701) (xy 57.614947 -22.285369)
			(xy 57.511892 -22.207545) (xy 57.413822 -22.123524) (xy 57.321111 -22.033625) (xy 57.234111 -21.93819)
			(xy 57.15315 -21.83758) (xy 57.078536 -21.732177) (xy 57.010553 -21.62238) (xy 56.949458 -21.508606)
			(xy 56.895483 -21.391287) (xy 56.848832 -21.270868) (xy 56.809683 -21.147805) (xy 56.778184 -21.022566)
			(xy 56.754455 -20.895625) (xy 56.738585 -20.767465) (xy 56.730635 -20.63857) (xy 2.159 -20.63857)
			(xy 2.159 -25.756358) (xy 39.366172 -25.756358) (xy 39.366172 -25.696422) (xy 39.373995 -25.637)
			(xy 39.389508 -25.579107) (xy 39.412444 -25.523734) (xy 39.442411 -25.471828) (xy 39.478898 -25.424278)
			(xy 39.521278 -25.381898) (xy 39.568828 -25.345411) (xy 39.620734 -25.315444) (xy 39.676107 -25.292508)
			(xy 39.734 -25.276995) (xy 39.793422 -25.269172) (xy 39.853358 -25.269172) (xy 39.91278 -25.276995)
			(xy 39.970673 -25.292508) (xy 40.026046 -25.315444) (xy 40.077952 -25.345411) (xy 40.125502 -25.381898)
			(xy 40.167882 -25.424278) (xy 40.204369 -25.471828) (xy 40.234336 -25.523734) (xy 40.257272 -25.579107)
			(xy 40.272785 -25.637) (xy 40.280608 -25.696422) (xy 40.281098 -25.72639) (xy 40.280608 -25.756358)
			(xy 40.272785 -25.81578) (xy 40.257272 -25.873673) (xy 40.243053 -25.908) (xy 44.521372 -25.908)
			(xy 44.525443 -25.852378) (xy 44.537569 -25.797941) (xy 44.557492 -25.74585) (xy 44.584788 -25.697215)
			(xy 44.618874 -25.653072) (xy 44.659023 -25.614363) (xy 44.704381 -25.581912) (xy 44.753981 -25.556411)
			(xy 44.806765 -25.538404) (xy 44.861608 -25.528274) (xy 44.917342 -25.526237) (xy 44.972779 -25.532337)
			(xy 45.026736 -25.546443) (xy 45.078065 -25.568255) (xy 45.125671 -25.597309) (xy 45.168539 -25.632984)
			(xy 45.205756 -25.674521) (xy 45.236529 -25.721034) (xy 45.260201 -25.771531) (xy 45.276269 -25.824938)
			(xy 45.284389 -25.880114) (xy 45.284898 -25.908) (xy 45.284389 -25.935886) (xy 45.276269 -25.991062)
			(xy 45.260201 -26.044469) (xy 45.236529 -26.094966) (xy 45.205756 -26.141479) (xy 45.168539 -26.183016)
			(xy 45.125671 -26.218691) (xy 45.078065 -26.247745) (xy 45.026736 -26.269557) (xy 44.972779 -26.283663)
			(xy 44.917342 -26.289763) (xy 44.861608 -26.287726) (xy 44.806765 -26.277596) (xy 44.753981 -26.259589)
			(xy 44.704381 -26.234088) (xy 44.659023 -26.201637) (xy 44.618874 -26.162928) (xy 44.584788 -26.118785)
			(xy 44.557492 -26.07015) (xy 44.537569 -26.018059) (xy 44.525443 -25.963622) (xy 44.521372 -25.908)
			(xy 40.243053 -25.908) (xy 40.234336 -25.929046) (xy 40.204369 -25.980952) (xy 40.167882 -26.028502)
			(xy 40.125502 -26.070882) (xy 40.077952 -26.107369) (xy 40.026046 -26.137336) (xy 39.970673 -26.160272)
			(xy 39.91278 -26.175785) (xy 39.853358 -26.183608) (xy 39.793422 -26.183608) (xy 39.734 -26.175785)
			(xy 39.676107 -26.160272) (xy 39.620734 -26.137336) (xy 39.568828 -26.107369) (xy 39.521278 -26.070882)
			(xy 39.478898 -26.028502) (xy 39.442411 -25.980952) (xy 39.412444 -25.929046) (xy 39.389508 -25.873673)
			(xy 39.373995 -25.81578) (xy 39.366172 -25.756358) (xy 2.159 -25.756358) (xy 2.159 -27.051) (xy 47.268382 -27.051)
			(xy 47.272453 -26.995378) (xy 47.284579 -26.940941) (xy 47.304502 -26.88885) (xy 47.331798 -26.840215)
			(xy 47.365884 -26.796072) (xy 47.406033 -26.757363) (xy 47.451391 -26.724912) (xy 47.500991 -26.699411)
			(xy 47.553775 -26.681404) (xy 47.608618 -26.671274) (xy 47.664352 -26.669237) (xy 47.719789 -26.675337)
			(xy 47.773746 -26.689443) (xy 47.825075 -26.711255) (xy 47.872681 -26.740309) (xy 47.915549 -26.775984)
			(xy 47.952766 -26.817521) (xy 47.983539 -26.864034) (xy 48.007211 -26.914531) (xy 48.023279 -26.967938)
			(xy 48.024027 -26.973018) (xy 53.244732 -26.973018) (xy 53.244732 -26.913082) (xy 53.252555 -26.85366)
			(xy 53.268068 -26.795767) (xy 53.291004 -26.740394) (xy 53.320971 -26.688488) (xy 53.357458 -26.640938)
			(xy 53.399838 -26.598558) (xy 53.447388 -26.562071) (xy 53.499294 -26.532104) (xy 53.554667 -26.509168)
			(xy 53.61256 -26.493655) (xy 53.671982 -26.485832) (xy 53.731918 -26.485832) (xy 53.79134 -26.493655)
			(xy 53.849233 -26.509168) (xy 53.904606 -26.532104) (xy 53.956512 -26.562071) (xy 54.004062 -26.598558)
			(xy 54.046442 -26.640938) (xy 54.082929 -26.688488) (xy 54.112896 -26.740394) (xy 54.135832 -26.795767)
			(xy 54.151345 -26.85366) (xy 54.159168 -26.913082) (xy 54.159658 -26.94305) (xy 54.159168 -26.973018)
			(xy 54.151345 -27.03244) (xy 54.135832 -27.090333) (xy 54.112896 -27.145706) (xy 54.082929 -27.197612)
			(xy 54.046442 -27.245162) (xy 54.004062 -27.287542) (xy 53.956512 -27.324029) (xy 53.904606 -27.353996)
			(xy 53.849233 -27.376932) (xy 53.79134 -27.392445) (xy 53.731918 -27.400268) (xy 53.671982 -27.400268)
			(xy 53.61256 -27.392445) (xy 53.554667 -27.376932) (xy 53.499294 -27.353996) (xy 53.447388 -27.324029)
			(xy 53.399838 -27.287542) (xy 53.357458 -27.245162) (xy 53.320971 -27.197612) (xy 53.291004 -27.145706)
			(xy 53.268068 -27.090333) (xy 53.252555 -27.03244) (xy 53.244732 -26.973018) (xy 48.024027 -26.973018)
			(xy 48.031399 -27.023114) (xy 48.031908 -27.051) (xy 48.031399 -27.078886) (xy 48.023279 -27.134062)
			(xy 48.007211 -27.187469) (xy 47.983539 -27.237966) (xy 47.952766 -27.284479) (xy 47.915549 -27.326016)
			(xy 47.872681 -27.361691) (xy 47.825075 -27.390745) (xy 47.773746 -27.412557) (xy 47.719789 -27.426663)
			(xy 47.664352 -27.432763) (xy 47.608618 -27.430726) (xy 47.553775 -27.420596) (xy 47.500991 -27.402589)
			(xy 47.451391 -27.377088) (xy 47.406033 -27.344637) (xy 47.365884 -27.305928) (xy 47.331798 -27.261785)
			(xy 47.304502 -27.21315) (xy 47.284579 -27.161059) (xy 47.272453 -27.106622) (xy 47.268382 -27.051)
			(xy 2.159 -27.051) (xy 2.159 -29.386018) (xy 53.117732 -29.386018) (xy 53.117732 -29.326082) (xy 53.125555 -29.26666)
			(xy 53.141068 -29.208767) (xy 53.164004 -29.153394) (xy 53.193971 -29.101488) (xy 53.230458 -29.053938)
			(xy 53.272838 -29.011558) (xy 53.320388 -28.975071) (xy 53.372294 -28.945104) (xy 53.427667 -28.922168)
			(xy 53.48556 -28.906655) (xy 53.544982 -28.898832) (xy 53.604918 -28.898832) (xy 53.66434 -28.906655)
			(xy 53.722233 -28.922168) (xy 53.777606 -28.945104) (xy 53.829512 -28.975071) (xy 53.877062 -29.011558)
			(xy 53.919442 -29.053938) (xy 53.955929 -29.101488) (xy 53.985896 -29.153394) (xy 54.008832 -29.208767)
			(xy 54.024345 -29.26666) (xy 54.032168 -29.326082) (xy 54.032658 -29.35605) (xy 54.032168 -29.386018)
			(xy 54.024345 -29.44544) (xy 54.008832 -29.503333) (xy 53.985896 -29.558706) (xy 53.955929 -29.610612)
			(xy 53.919442 -29.658162) (xy 53.877062 -29.700542) (xy 53.829512 -29.737029) (xy 53.777606 -29.766996)
			(xy 53.722233 -29.789932) (xy 53.66434 -29.805445) (xy 53.604918 -29.813268) (xy 53.544982 -29.813268)
			(xy 53.48556 -29.805445) (xy 53.427667 -29.789932) (xy 53.372294 -29.766996) (xy 53.320388 -29.737029)
			(xy 53.272838 -29.700542) (xy 53.230458 -29.658162) (xy 53.193971 -29.610612) (xy 53.164004 -29.558706)
			(xy 53.141068 -29.503333) (xy 53.125555 -29.44544) (xy 53.117732 -29.386018) (xy 2.159 -29.386018)
			(xy 2.159 -60.099956) (xy 12.484104 -60.099956) (xy 12.488134 -59.957621) (xy 12.500209 -59.815741)
			(xy 12.520292 -59.674773) (xy 12.548319 -59.535166) (xy 12.584199 -59.397368) (xy 12.627817 -59.261821)
			(xy 12.679034 -59.128959) (xy 12.737685 -58.999207) (xy 12.803583 -58.872981) (xy 12.876517 -58.750685)
			(xy 12.956254 -58.632712) (xy 13.042536 -58.519439) (xy 13.135089 -58.411228) (xy 13.233616 -58.308427)
			(xy 13.337801 -58.211365) (xy 13.44731 -58.120353) (xy 13.561793 -58.035681) (xy 13.680883 -57.957623)
			(xy 13.804198 -57.886427) (xy 13.931344 -57.822321) (xy 14.061913 -57.765512) (xy 14.195487 -57.71618)
			(xy 14.331638 -57.674484) (xy 14.469929 -57.640558) (xy 14.609919 -57.61451) (xy 14.751158 -57.596424)
			(xy 14.893194 -57.586357) (xy 15.035572 -57.584342) (xy 15.177836 -57.590385) (xy 15.31953 -57.604467)
			(xy 15.4602 -57.626543) (xy 15.599397 -57.656543) (xy 15.736673 -57.694369) (xy 15.871589 -57.739901)
			(xy 16.003713 -57.792992) (xy 16.132622 -57.853474) (xy 16.257903 -57.921152) (xy 16.379154 -57.995809)
			(xy 16.495987 -58.077207) (xy 16.608028 -58.165084) (xy 16.714918 -58.259159) (xy 16.816315 -58.359131)
			(xy 16.911893 -58.464679) (xy 17.001347 -58.575465) (xy 17.084389 -58.691134) (xy 17.160755 -58.811317)
			(xy 17.230199 -58.935627) (xy 17.292499 -59.063668) (xy 17.347455 -59.195027) (xy 17.394892 -59.329286)
			(xy 17.434656 -59.466013) (xy 17.466622 -59.604771) (xy 17.490687 -59.745115) (xy 17.506773 -59.886596)
			(xy 17.514828 -60.02876) (xy 17.515332 -60.099956) (xy 17.514828 -60.171152) (xy 17.506773 -60.313316)
			(xy 17.490687 -60.454797) (xy 17.466622 -60.595141) (xy 17.434656 -60.733899) (xy 17.394892 -60.870626)
			(xy 17.347455 -61.004885) (xy 17.292499 -61.136244) (xy 17.230199 -61.264285) (xy 17.160755 -61.388595)
			(xy 17.084389 -61.508778) (xy 17.001347 -61.624447) (xy 16.911893 -61.735233) (xy 16.816315 -61.840781)
			(xy 16.714918 -61.940753) (xy 16.608028 -62.034828) (xy 16.495987 -62.122705) (xy 16.379154 -62.204103)
			(xy 16.257903 -62.27876) (xy 16.132622 -62.346438) (xy 16.003713 -62.40692) (xy 15.871589 -62.460011)
			(xy 15.736673 -62.505543) (xy 15.599397 -62.543369) (xy 15.4602 -62.573369) (xy 15.31953 -62.595445)
			(xy 15.177836 -62.609527) (xy 15.035572 -62.61557) (xy 14.893194 -62.613555) (xy 14.751158 -62.603488)
			(xy 14.609919 -62.585402) (xy 14.469929 -62.559354) (xy 14.331638 -62.525428) (xy 14.195487 -62.483732)
			(xy 14.061913 -62.4344) (xy 13.931344 -62.377591) (xy 13.804198 -62.313485) (xy 13.680883 -62.242289)
			(xy 13.561793 -62.164231) (xy 13.44731 -62.079559) (xy 13.337801 -61.988547) (xy 13.233616 -61.891485)
			(xy 13.135089 -61.788684) (xy 13.042536 -61.680473) (xy 12.956254 -61.5672) (xy 12.876517 -61.449227)
			(xy 12.803583 -61.326931) (xy 12.737685 -61.200705) (xy 12.679034 -61.070953) (xy 12.627817 -60.938091)
			(xy 12.584199 -60.802544) (xy 12.548319 -60.664746) (xy 12.520292 -60.525139) (xy 12.500209 -60.384171)
			(xy 12.488134 -60.242291) (xy 12.484104 -60.099956) (xy 2.159 -60.099956) (xy 2.159 -104.544876)
			(xy 12.484104 -104.544876) (xy 12.488134 -104.402541) (xy 12.500209 -104.260661) (xy 12.520292 -104.119693)
			(xy 12.548319 -103.980086) (xy 12.584199 -103.842288) (xy 12.627817 -103.706741) (xy 12.679034 -103.573879)
			(xy 12.737685 -103.444127) (xy 12.803583 -103.317901) (xy 12.876517 -103.195605) (xy 12.956254 -103.077632)
			(xy 13.042536 -102.964359) (xy 13.135089 -102.856148) (xy 13.233616 -102.753347) (xy 13.337801 -102.656285)
			(xy 13.44731 -102.565273) (xy 13.561793 -102.480601) (xy 13.680883 -102.402543) (xy 13.804198 -102.331347)
			(xy 13.931344 -102.267241) (xy 14.061913 -102.210432) (xy 14.195487 -102.1611) (xy 14.331638 -102.119404)
			(xy 14.469929 -102.085478) (xy 14.609919 -102.05943) (xy 14.751158 -102.041344) (xy 14.893194 -102.031277)
			(xy 15.035572 -102.029262) (xy 15.177836 -102.035305) (xy 15.31953 -102.049387) (xy 15.4602 -102.071463)
			(xy 15.599397 -102.101463) (xy 15.736673 -102.139289) (xy 15.871589 -102.184821) (xy 16.003713 -102.237912)
			(xy 16.132622 -102.298394) (xy 16.257903 -102.366072) (xy 16.379154 -102.440729) (xy 16.495987 -102.522127)
			(xy 16.608028 -102.610004) (xy 16.714918 -102.704079) (xy 16.816315 -102.804051) (xy 16.911893 -102.909599)
			(xy 17.001347 -103.020385) (xy 17.084389 -103.136054) (xy 17.160755 -103.256237) (xy 17.230199 -103.380547)
			(xy 17.292499 -103.508588) (xy 17.347455 -103.639947) (xy 17.394892 -103.774206) (xy 17.434656 -103.910933)
			(xy 17.466622 -104.049691) (xy 17.490687 -104.190035) (xy 17.506773 -104.331516) (xy 17.514828 -104.47368)
			(xy 17.515332 -104.544876) (xy 17.514828 -104.616072) (xy 17.506773 -104.758236) (xy 17.490687 -104.899717)
			(xy 17.466622 -105.040061) (xy 17.434656 -105.178819) (xy 17.394892 -105.315546) (xy 17.347455 -105.449805)
			(xy 17.292499 -105.581164) (xy 17.230199 -105.709205) (xy 17.160755 -105.833515) (xy 17.084389 -105.953698)
			(xy 17.001347 -106.069367) (xy 16.911893 -106.180153) (xy 16.816315 -106.285701) (xy 16.714918 -106.385673)
			(xy 16.608028 -106.479748) (xy 16.495987 -106.567625) (xy 16.379154 -106.649023) (xy 16.257903 -106.72368)
			(xy 16.132622 -106.791358) (xy 16.003713 -106.85184) (xy 15.871589 -106.904931) (xy 15.736673 -106.950463)
			(xy 15.599397 -106.988289) (xy 15.4602 -107.018289) (xy 15.31953 -107.040365) (xy 15.177836 -107.054447)
			(xy 15.035572 -107.06049) (xy 14.893194 -107.058475) (xy 14.751158 -107.048408) (xy 14.609919 -107.030322)
			(xy 14.469929 -107.004274) (xy 14.331638 -106.970348) (xy 14.195487 -106.928652) (xy 14.061913 -106.87932)
			(xy 13.931344 -106.822511) (xy 13.804198 -106.758405) (xy 13.680883 -106.687209) (xy 13.561793 -106.609151)
			(xy 13.44731 -106.524479) (xy 13.337801 -106.433467) (xy 13.233616 -106.336405) (xy 13.135089 -106.233604)
			(xy 13.042536 -106.125393) (xy 12.956254 -106.01212) (xy 12.876517 -105.894147) (xy 12.803583 -105.771851)
			(xy 12.737685 -105.645625) (xy 12.679034 -105.515873) (xy 12.627817 -105.383011) (xy 12.584199 -105.247464)
			(xy 12.548319 -105.109666) (xy 12.520292 -104.970059) (xy 12.500209 -104.829091) (xy 12.488134 -104.687211)
			(xy 12.484104 -104.544876) (xy 2.159 -104.544876) (xy 2.159 -153.558121) (xy 24.389322 -153.558121)
			(xy 24.389322 -153.444567) (xy 24.397243 -153.331291) (xy 24.413046 -153.218843) (xy 24.436655 -153.107772)
			(xy 24.467955 -152.998617) (xy 24.506792 -152.891912) (xy 24.552978 -152.788177) (xy 24.606288 -152.687915)
			(xy 24.666462 -152.591617) (xy 24.733207 -152.499751) (xy 24.806197 -152.412764) (xy 24.885078 -152.331081)
			(xy 24.969464 -152.255099) (xy 25.058945 -152.185189) (xy 25.153085 -152.121691) (xy 25.251425 -152.064914)
			(xy 25.353485 -152.015136) (xy 25.45877 -151.972598) (xy 25.566765 -151.937508) (xy 25.676945 -151.910037)
			(xy 25.788773 -151.890319) (xy 25.901704 -151.878449) (xy 26.015188 -151.874487) (xy 26.128672 -151.878449)
			(xy 26.241603 -151.890319) (xy 26.353431 -151.910037) (xy 26.463611 -151.937508) (xy 26.571606 -151.972598)
			(xy 26.676891 -152.015136) (xy 26.778951 -152.064914) (xy 26.877291 -152.121691) (xy 26.971431 -152.185189)
			(xy 27.060912 -152.255099) (xy 27.145298 -152.331081) (xy 27.224179 -152.412764) (xy 27.297169 -152.499751)
			(xy 27.363914 -152.591617) (xy 27.424088 -152.687915) (xy 27.477398 -152.788177) (xy 27.523584 -152.891912)
			(xy 27.562421 -152.998617) (xy 27.593721 -153.107772) (xy 27.61733 -153.218843) (xy 27.633133 -153.331291)
			(xy 27.641054 -153.444567) (xy 27.64155 -153.501344) (xy 27.641054 -153.558121) (xy 27.633133 -153.671397)
			(xy 27.61733 -153.783845) (xy 27.593721 -153.894916) (xy 27.562421 -154.004071) (xy 27.523584 -154.110776)
			(xy 27.477398 -154.214511) (xy 27.424088 -154.314773) (xy 27.363914 -154.411071) (xy 27.297169 -154.502937)
			(xy 27.224179 -154.589924) (xy 27.145298 -154.671607) (xy 27.060912 -154.747589) (xy 26.971431 -154.817499)
			(xy 26.877291 -154.880997) (xy 26.778951 -154.937774) (xy 26.676891 -154.987552) (xy 26.571606 -155.03009)
			(xy 26.463611 -155.06518) (xy 26.353431 -155.092651) (xy 26.241603 -155.112369) (xy 26.128672 -155.124239)
			(xy 26.015188 -155.128202) (xy 25.901704 -155.124239) (xy 25.788773 -155.112369) (xy 25.676945 -155.092651)
			(xy 25.566765 -155.06518) (xy 25.45877 -155.03009) (xy 25.353485 -154.987552) (xy 25.251425 -154.937774)
			(xy 25.153085 -154.880997) (xy 25.058945 -154.817499) (xy 24.969464 -154.747589) (xy 24.885078 -154.671607)
			(xy 24.806197 -154.589924) (xy 24.733207 -154.502937) (xy 24.666462 -154.411071) (xy 24.606288 -154.314773)
			(xy 24.552978 -154.214511) (xy 24.506792 -154.110776) (xy 24.467955 -154.004071) (xy 24.436655 -153.894916)
			(xy 24.413046 -153.783845) (xy 24.397243 -153.671397) (xy 24.389322 -153.558121) (xy 2.159 -153.558121)
			(xy 2.159 -154.410918) (xy 2.159427 -154.420987) (xy 2.167146 -154.439586) (xy 2.173986 -154.446986)
			(xy 3.287014 -155.560014) (xy 3.294409 -155.566868) (xy 3.313008 -155.57461) (xy 3.323082 -155.575)
		)
		(stroke
			(width 0)
			(type solid)
		)
		(fill yes)
		(layer "B.Cu")
		(net "GND")
	)
	(gr_poly
		(pts
			(arc
				(start 75.000104 -171.141898)
				(mid 78.176421 -169.826225)
				(end 79.492094 -166.649908)
			)
			(arc
				(start 79.492094 -161.299906)
				(mid 80.519562 -158.81938)
				(end 83.000088 -157.791912)
			)
			(arc
				(start 83.49996 -157.791912)
				(mid 86.676277 -156.476239)
				(end 87.99195 -153.299922)
			)
			(arc
				(start 87.99195 -110.499906)
				(mid 90.337472 -104.83757)
				(end 95.999808 -102.492048)
			)
			(arc
				(start 344.000074 -102.492048)
				(mid 349.662485 -104.837495)
				(end 352.007932 -110.499906)
			)
			(arc
				(start 352.007932 -153.299922)
				(mid 353.323605 -156.476239)
				(end 356.499922 -157.791912)
			)
			(arc
				(start 357.000048 -157.791912)
				(mid 359.480574 -158.81938)
				(end 360.508042 -161.299906)
			)
			(arc
				(start 360.508042 -166.649908)
				(mid 361.823715 -169.826225)
				(end 365.000032 -171.141898)
			)
			(arc
				(start 403.999954 -171.141898)
				(mid 407.176271 -169.826225)
				(end 408.491944 -166.649908)
			)
			(arc
				(start 408.491944 -163.299902)
				(mid 410.105197 -159.405165)
				(end 413.999934 -157.791912)
			)
			(arc
				(start 434.999892 -157.791912)
				(mid 438.176209 -156.476239)
				(end 439.491882 -153.299922)
			)
			(arc
				(start 439.491882 -136.77011)
				(mid 441.105209 -132.875447)
				(end 444.999872 -131.26212)
			)
			(arc
				(start 471.000074 -131.26212)
				(mid 474.176391 -129.946447)
				(end 475.492064 -126.77013)
			)
			(arc
				(start 475.492064 -21.770086)
				(mid 474.176391 -18.593769)
				(end 471.000074 -17.278096)
			)
			(arc
				(start 444.999872 -17.278096)
				(mid 441.105209 -15.664769)
				(end 439.491882 -11.770106)
			)
			(arc
				(start 439.491882 -4.99999)
				(mid 438.176209 -1.823673)
				(end 434.999892 -0.508)
			)
			(xy 380.474728 -0.508) (xy 380.474728 -1.015746)
			(arc
				(start 434.999892 -1.015746)
				(mid 437.817178 -2.182704)
				(end 438.984136 -4.99999)
			)
			(arc
				(start 438.984136 -11.770106)
				(mid 440.746179 -16.023799)
				(end 444.999872 -17.785842)
			)
			(arc
				(start 471.000074 -17.785842)
				(mid 473.81736 -18.9528)
				(end 474.984318 -21.770086)
			)
			(arc
				(start 474.984318 -126.77013)
				(mid 473.81736 -129.587416)
				(end 471.000074 -130.754374)
			)
			(arc
				(start 444.999872 -130.754374)
				(mid 440.746179 -132.516417)
				(end 438.984136 -136.77011)
			)
			(arc
				(start 438.984136 -153.299922)
				(mid 437.817178 -156.117208)
				(end 434.999892 -157.284166)
			)
			(arc
				(start 413.999934 -157.284166)
				(mid 409.746166 -159.046134)
				(end 407.984198 -163.299902)
			)
			(arc
				(start 407.984198 -166.649908)
				(mid 406.81724 -169.467194)
				(end 403.999954 -170.634152)
			)
			(arc
				(start 365.000032 -170.634152)
				(mid 362.182746 -169.467194)
				(end 361.015788 -166.649908)
			)
			(arc
				(start 361.015788 -161.299906)
				(mid 359.839605 -158.460349)
				(end 357.000048 -157.284166)
			)
			(arc
				(start 356.499922 -157.284166)
				(mid 353.682636 -156.117208)
				(end 352.515678 -153.299922)
			)
			(arc
				(start 352.515678 -110.499906)
				(mid 350.021515 -104.478465)
				(end 344.000074 -101.984302)
			)
			(arc
				(start 95.999808 -101.984302)
				(mid 89.978441 -104.478539)
				(end 87.484204 -110.499906)
			)
			(arc
				(start 87.484204 -153.299922)
				(mid 86.317246 -156.117208)
				(end 83.49996 -157.284166)
			)
			(arc
				(start 83.000088 -157.284166)
				(mid 80.160531 -158.460349)
				(end 78.984348 -161.299906)
			)
			(arc
				(start 78.984348 -166.649908)
				(mid 77.81739 -169.467194)
				(end 75.000104 -170.634152)
			)
			(arc
				(start 35.999928 -170.634152)
				(mid 33.182642 -169.467194)
				(end 32.015684 -166.649908)
			)
			(arc
				(start 32.015684 -163.299902)
				(mid 30.253716 -159.046134)
				(end 25.999948 -157.284166)
			)
			(arc
				(start 4.99999 -157.284166)
				(mid 2.182704 -156.117208)
				(end 1.015746 -153.299922)
			)
			(arc
				(start 1.015746 -4.99999)
				(mid 2.182704 -2.182704)
				(end 4.99999 -1.015746)
			)
			(xy 57.549034 -1.015746) (xy 57.549034 -0.508)
			(arc
				(start 4.99999 -0.508)
				(mid 1.823673 -1.823673)
				(end 0.508 -4.99999)
			)
			(arc
				(start 0.508 -153.299922)
				(mid 1.823673 -156.476239)
				(end 4.99999 -157.791912)
			)
			(arc
				(start 25.999948 -157.791912)
				(mid 29.894685 -159.405165)
				(end 31.507938 -163.299902)
			)
			(arc
				(start 31.507938 -166.649908)
				(mid 32.823611 -169.826225)
				(end 35.999928 -171.141898)
			)
		)
		(stroke
			(width 0)
			(type solid)
		)
		(fill yes)
		(layer "B.Cu")
		(net "GND")
	)
	(gr_poly
		(pts
			(xy 37.078666 -169.378884) (xy 37.089866 -169.378303) (xy 37.110164 -169.368825) (xy 37.117782 -169.360596)
			(xy 37.175186 -169.29227) (xy 37.180774 -169.270934) (xy 37.178742 -169.259504) (xy 37.166823 -169.188545)
			(xy 37.150214 -169.045604) (xy 37.141907 -168.901941) (xy 37.141404 -168.82999) (xy 37.141913 -168.758034)
			(xy 37.150232 -168.614363) (xy 37.16686 -168.471415) (xy 37.191741 -168.329671) (xy 37.224791 -168.189605)
			(xy 37.265899 -168.05169) (xy 37.314926 -167.916387) (xy 37.342826 -167.850058) (xy 37.34689 -167.829992)
			(xy 37.342826 -167.809926) (xy 37.314919 -167.743601) (xy 37.265907 -167.608293) (xy 37.224809 -167.470375)
			(xy 37.191765 -167.330309) (xy 37.166884 -167.188566) (xy 37.150251 -167.045619) (xy 37.14192 -166.901949)
			(xy 37.141404 -166.829994) (xy 37.141913 -166.758038) (xy 37.150232 -166.614367) (xy 37.16686 -166.471419)
			(xy 37.19174 -166.329674) (xy 37.22479 -166.189609) (xy 37.265897 -166.051693) (xy 37.314925 -165.91639)
			(xy 37.342826 -165.850062) (xy 37.34689 -165.829996) (xy 37.342826 -165.80993) (xy 37.314919 -165.743605)
			(xy 37.265906 -165.608297) (xy 37.224809 -165.470379) (xy 37.191764 -165.330313) (xy 37.166883 -165.18857)
			(xy 37.150249 -165.045623) (xy 37.141919 -164.901953) (xy 37.141404 -164.829998) (xy 37.141913 -164.758042)
			(xy 37.150232 -164.614371) (xy 37.166859 -164.471423) (xy 37.19174 -164.329678) (xy 37.224789 -164.189613)
			(xy 37.265896 -164.051697) (xy 37.314924 -163.916394) (xy 37.342826 -163.850066) (xy 37.34689 -163.83)
			(xy 37.342826 -163.809934) (xy 37.314919 -163.743609) (xy 37.265906 -163.608301) (xy 37.224808 -163.470383)
			(xy 37.191763 -163.330317) (xy 37.166882 -163.188574) (xy 37.150248 -163.045627) (xy 37.141917 -162.901958)
			(xy 37.141404 -162.830002) (xy 37.141912 -162.758046) (xy 37.150231 -162.614375) (xy 37.166859 -162.471427)
			(xy 37.191739 -162.329682) (xy 37.224788 -162.189616) (xy 37.265895 -162.0517) (xy 37.314922 -161.916397)
			(xy 37.342826 -161.85007) (xy 37.34689 -161.830004) (xy 37.342826 -161.809938) (xy 37.314919 -161.743613)
			(xy 37.265906 -161.608305) (xy 37.224808 -161.470387) (xy 37.191763 -161.330322) (xy 37.166881 -161.188578)
			(xy 37.150247 -161.045631) (xy 37.141916 -160.901962) (xy 37.141404 -160.830006) (xy 37.141912 -160.75805)
			(xy 37.150231 -160.614379) (xy 37.166858 -160.471431) (xy 37.191738 -160.329686) (xy 37.224787 -160.18962)
			(xy 37.265894 -160.051704) (xy 37.314921 -159.916401) (xy 37.342826 -159.850074) (xy 37.34689 -159.830008)
			(xy 37.342826 -159.809942) (xy 37.314919 -159.743617) (xy 37.265905 -159.608309) (xy 37.224807 -159.470391)
			(xy 37.191762 -159.330326) (xy 37.16688 -159.188582) (xy 37.150246 -159.045635) (xy 37.141914 -158.901966)
			(xy 37.141404 -158.83001) (xy 37.141912 -158.758054) (xy 37.150231 -158.614383) (xy 37.166858 -158.471435)
			(xy 37.191737 -158.32969) (xy 37.224786 -158.189624) (xy 37.265893 -158.051708) (xy 37.314919 -157.916404)
			(xy 37.342826 -157.850078) (xy 37.34689 -157.830012) (xy 37.342826 -157.809946) (xy 37.314919 -157.743621)
			(xy 37.265905 -157.608313) (xy 37.224807 -157.470395) (xy 37.191761 -157.33033) (xy 37.166879 -157.188586)
			(xy 37.150244 -157.045639) (xy 37.141913 -156.90197) (xy 37.141404 -156.830014) (xy 37.141912 -156.758058)
			(xy 37.15023 -156.614387) (xy 37.166857 -156.471438) (xy 37.191736 -156.329693) (xy 37.224785 -156.189627)
			(xy 37.265891 -156.051711) (xy 37.314918 -155.916408) (xy 37.342826 -155.850082) (xy 37.34689 -155.830016)
			(xy 37.342826 -155.80995) (xy 37.314918 -155.743625) (xy 37.265905 -155.608317) (xy 37.224806 -155.470399)
			(xy 37.19176 -155.330334) (xy 37.166878 -155.18859) (xy 37.150243 -155.045643) (xy 37.141911 -154.901974)
			(xy 37.141404 -154.830018) (xy 37.141912 -154.758062) (xy 37.15023 -154.614391) (xy 37.166856 -154.471442)
			(xy 37.191736 -154.329697) (xy 37.224784 -154.189631) (xy 37.26589 -154.051715) (xy 37.314917 -153.916411)
			(xy 37.342826 -153.850086) (xy 37.34689 -153.83002) (xy 37.342826 -153.809954) (xy 37.314925 -153.743646)
			(xy 37.265921 -153.608373) (xy 37.224829 -153.470491) (xy 37.191785 -153.330462) (xy 37.166901 -153.188756)
			(xy 37.150259 -153.045846) (xy 37.141917 -152.902213) (xy 37.141404 -152.830276) (xy 37.141404 -152.830022)
			(xy 37.141875 -152.760878) (xy 37.149566 -152.622804) (xy 37.164931 -152.485372) (xy 37.187923 -152.349008)
			(xy 37.21847 -152.214136) (xy 37.256477 -152.081173) (xy 37.301827 -151.950532) (xy 37.354379 -151.822619)
			(xy 37.41397 -151.697829) (xy 37.480415 -151.576549) (xy 37.516562 -151.517604) (xy 37.520372 -151.511508)
			(xy 37.524182 -151.497792) (xy 37.524182 -150.404576) (xy 37.524609 -150.394507) (xy 37.532327 -150.375907)
			(xy 37.539168 -150.368508) (xy 37.972238 -149.935438) (xy 37.979637 -149.928594) (xy 37.998235 -149.920867)
			(xy 38.008306 -149.920452) (xy 45.323506 -149.920452) (xy 45.333575 -149.920878) (xy 45.352173 -149.928599)
			(xy 45.359574 -149.935438) (xy 45.698664 -150.274528) (xy 45.70551 -150.281926) (xy 45.71324 -150.300525)
			(xy 45.71365 -150.310596) (xy 45.71365 -159.684424) (xy 71.513942 -159.684424) (xy 71.513942 -159.575796)
			(xy 71.521871 -159.467458) (xy 71.537688 -159.359987) (xy 71.561307 -159.253958) (xy 71.592603 -159.149936)
			(xy 71.631408 -159.048475) (xy 71.677516 -158.950118) (xy 71.73068 -158.855389) (xy 71.790618 -158.764794)
			(xy 71.857008 -158.678815) (xy 71.929498 -158.597912) (xy 72.007699 -158.522516) (xy 72.091196 -158.45303)
			(xy 72.179542 -158.389823) (xy 72.272266 -158.333235) (xy 72.368874 -158.283565) (xy 72.468849 -158.24108)
			(xy 72.571659 -158.206007) (xy 72.676755 -158.178531) (xy 72.783576 -158.1588) (xy 72.891552 -158.146919)
			(xy 73.000108 -158.142952) (xy 73.108664 -158.146919) (xy 73.21664 -158.1588) (xy 73.323461 -158.178531)
			(xy 73.428557 -158.206007) (xy 73.531367 -158.24108) (xy 73.631342 -158.283565) (xy 73.72795 -158.333235)
			(xy 73.820674 -158.389823) (xy 73.90902 -158.45303) (xy 73.992517 -158.522516) (xy 74.070718 -158.597912)
			(xy 74.143208 -158.678815) (xy 74.209598 -158.764794) (xy 74.269536 -158.855389) (xy 74.3227 -158.950118)
			(xy 74.368808 -159.048475) (xy 74.407613 -159.149936) (xy 74.438909 -159.253958) (xy 74.462528 -159.359987)
			(xy 74.478345 -159.467458) (xy 74.486274 -159.575796) (xy 74.48677 -159.63011) (xy 74.486274 -159.684424)
			(xy 74.478345 -159.792762) (xy 74.462528 -159.900233) (xy 74.438909 -160.006262) (xy 74.407613 -160.110284)
			(xy 74.368808 -160.211745) (xy 74.3227 -160.310102) (xy 74.269536 -160.404831) (xy 74.209598 -160.495426)
			(xy 74.143208 -160.581405) (xy 74.070718 -160.662308) (xy 73.992517 -160.737704) (xy 73.90902 -160.80719)
			(xy 73.820674 -160.870397) (xy 73.72795 -160.926985) (xy 73.631342 -160.976655) (xy 73.531367 -161.01914)
			(xy 73.428557 -161.054213) (xy 73.323461 -161.081689) (xy 73.21664 -161.10142) (xy 73.108664 -161.113301)
			(xy 73.000108 -161.117268) (xy 72.891552 -161.113301) (xy 72.783576 -161.10142) (xy 72.676755 -161.081689)
			(xy 72.571659 -161.054213) (xy 72.468849 -161.01914) (xy 72.368874 -160.976655) (xy 72.272266 -160.926985)
			(xy 72.179542 -160.870397) (xy 72.091196 -160.80719) (xy 72.007699 -160.737704) (xy 71.929498 -160.662308)
			(xy 71.857008 -160.581405) (xy 71.790618 -160.495426) (xy 71.73068 -160.404831) (xy 71.677516 -160.310102)
			(xy 71.631408 -160.211745) (xy 71.592603 -160.110284) (xy 71.561307 -160.006262) (xy 71.537688 -159.900233)
			(xy 71.521871 -159.792762) (xy 71.513942 -159.684424) (xy 45.71365 -159.684424) (xy 45.71365 -160.818576)
			(xy 45.714088 -160.828639) (xy 45.721828 -160.847219) (xy 45.728636 -160.854644) (xy 46.530006 -161.656014)
			(xy 46.537401 -161.662869) (xy 46.556 -161.670615) (xy 46.566074 -161.671) (xy 51.465226 -161.671)
			(xy 51.474385 -161.670566) (xy 51.491513 -161.66406) (xy 51.505291 -161.651983) (xy 51.50993 -161.644076)
			(xy 51.535978 -161.596174) (xy 51.594215 -161.503979) (xy 51.659163 -161.416382) (xy 51.730462 -161.333872)
			(xy 51.807713 -161.256906) (xy 51.890488 -161.185914) (xy 51.978324 -161.121291) (xy 52.070735 -161.063397)
			(xy 52.167204 -161.012553) (xy 52.267196 -160.969042) (xy 52.370153 -160.933108) (xy 52.475503 -160.90495)
			(xy 52.582658 -160.884724) (xy 52.691024 -160.872543) (xy 52.799996 -160.868475) (xy 52.908968 -160.872543)
			(xy 53.017334 -160.884724) (xy 53.124489 -160.90495) (xy 53.229839 -160.933108) (xy 53.332796 -160.969042)
			(xy 53.432788 -161.012553) (xy 53.529257 -161.063397) (xy 53.621668 -161.121291) (xy 53.709504 -161.185914)
			(xy 53.792279 -161.256906) (xy 53.86953 -161.333872) (xy 53.940829 -161.416382) (xy 54.005777 -161.503979)
			(xy 54.064014 -161.596174) (xy 54.090062 -161.644076) (xy 54.094693 -161.651998) (xy 54.108443 -161.664126)
			(xy 54.125598 -161.670598) (xy 54.134766 -161.671) (xy 77.02804 -161.671) (xy 77.038042 -161.670505)
			(xy 77.05652 -161.662838) (xy 77.070661 -161.648687) (xy 77.078313 -161.630203) (xy 77.07884 -161.6202)
			(xy 77.07884 -161.299906) (xy 77.079332 -161.192871) (xy 77.087097 -160.978941) (xy 77.102591 -160.765432)
			(xy 77.125795 -160.552623) (xy 77.156678 -160.340792) (xy 77.195199 -160.130216) (xy 77.217778 -160.025588)
			(xy 77.218032 -160.023556) (xy 77.230516 -159.956866) (xy 77.262801 -159.825069) (xy 77.282548 -159.760158)
			(xy 77.283056 -159.75838) (xy 77.31542 -159.640765) (xy 77.388594 -159.408026) (xy 77.42936 -159.293052)
			(xy 77.432408 -159.276034) (xy 77.432408 -154.55519) (xy 77.431984 -154.54512) (xy 77.424267 -154.526518)
			(xy 77.417422 -154.519122) (xy 73.201784 -150.303484) (xy 73.194931 -150.296089) (xy 73.187189 -150.27749)
			(xy 73.186798 -150.267416) (xy 73.186798 -139.100052) (xy 73.18723 -139.089986) (xy 73.194956 -139.071394)
			(xy 73.201784 -139.063984) (xy 76.423266 -135.842502) (xy 76.430668 -135.835666) (xy 76.449266 -135.827955)
			(xy 76.459334 -135.827516) (xy 83.6676 -135.827516) (xy 83.677671 -135.827093) (xy 83.696277 -135.819381)
			(xy 83.703668 -135.81253) (xy 85.075014 -134.441184) (xy 85.081867 -134.433789) (xy 85.089609 -134.41519)
			(xy 85.09 -134.405116) (xy 85.09 -91.613482) (xy 85.090427 -91.603413) (xy 85.098146 -91.584814)
			(xy 85.104986 -91.577414) (xy 102.068122 -74.614278) (xy 111.866172 -74.614278) (xy 111.873571 -74.607435)
			(xy 111.89217 -74.599714) (xy 111.90224 -74.599292) (xy 118.751096 -74.599292) (xy 118.957852 -74.392536)
			(xy 118.957852 -69.97319) (xy 118.68277 -69.698108) (xy 108.331508 -69.698108) (xy 108.077 -69.4436)
			(xy 108.077 -63.7032) (xy 108.443522 -63.336678) (xy 110.323122 -63.336678) (xy 110.338108 -63.321692)
			(xy 118.751096 -63.321692) (xy 118.957852 -63.114936) (xy 118.957852 -58.69559) (xy 118.68277 -58.420508)
			(xy 108.152692 -58.420508) (xy 107.396026 -59.177174) (xy 106.667046 -59.177174) (xy 106.605712 -59.210954)
			(xy 106.479841 -59.272331) (xy 106.350693 -59.326475) (xy 106.218684 -59.373211) (xy 106.084238 -59.41239)
			(xy 105.947787 -59.443886) (xy 105.809771 -59.467597) (xy 105.670632 -59.483446) (xy 105.530819 -59.491384)
			(xy 105.390781 -59.491384) (xy 105.250968 -59.483446) (xy 105.111829 -59.467597) (xy 104.973813 -59.443886)
			(xy 104.837362 -59.41239) (xy 104.702916 -59.373211) (xy 104.570907 -59.326475) (xy 104.441759 -59.272331)
			(xy 104.315888 -59.210954) (xy 104.254554 -59.177174) (xy 103.8098 -59.177174) (xy 103.77213 -59.179661)
			(xy 103.696675 -59.182329) (xy 103.658924 -59.182508) (xy 103.6574 -59.182508) (xy 103.592161 -59.182016)
			(xy 103.461922 -59.174138) (xy 103.332397 -59.15841) (xy 103.204057 -59.134891) (xy 103.077371 -59.103666)
			(xy 102.952802 -59.064849) (xy 102.830803 -59.018581) (xy 102.711821 -58.965031) (xy 102.59629 -58.904395)
			(xy 102.48463 -58.836895) (xy 102.377249 -58.762775) (xy 102.27454 -58.682308) (xy 102.176876 -58.595785)
			(xy 102.084615 -58.503524) (xy 101.998092 -58.40586) (xy 101.917625 -58.303151) (xy 101.843505 -58.19577)
			(xy 101.776005 -58.08411) (xy 101.715369 -57.968579) (xy 101.661819 -57.849597) (xy 101.615551 -57.727598)
			(xy 101.576734 -57.603029) (xy 101.545509 -57.476343) (xy 101.52199 -57.348003) (xy 101.506262 -57.218478)
			(xy 101.498384 -57.088239) (xy 101.497892 -57.023) (xy 101.498381 -56.957552) (xy 101.506309 -56.826895)
			(xy 101.522136 -56.696959) (xy 101.545803 -56.56822) (xy 101.577225 -56.441151) (xy 101.616285 -56.316218)
			(xy 101.662839 -56.19388) (xy 101.716718 -56.074587) (xy 101.777724 -55.958775) (xy 101.845631 -55.846871)
			(xy 101.920192 -55.739286) (xy 102.001131 -55.636414) (xy 102.088153 -55.538633) (xy 102.180937 -55.446302)
			(xy 102.279143 -55.35976) (xy 102.382411 -55.279325) (xy 102.49036 -55.205293) (xy 102.602595 -55.137934)
			(xy 102.66045 -55.107332) (xy 103.056182 -54.7116) (xy 103.6828 -54.7116) (xy 103.6828 -52.4383)
			(xy 103.783384 -52.337716) (xy 104.062276 -52.059078) (xy 111.866172 -52.059078) (xy 111.873571 -52.052235)
			(xy 111.89217 -52.044514) (xy 111.90224 -52.044092) (xy 118.751096 -52.044092) (xy 118.957852 -51.837336)
			(xy 118.957852 -47.41799) (xy 118.68277 -47.142908) (xy 107.54487 -47.142908) (xy 107.504157 -47.202704)
			(xy 107.416791 -47.318023) (xy 107.322925 -47.428116) (xy 107.222871 -47.532617) (xy 107.116963 -47.63118)
			(xy 107.005551 -47.723477) (xy 106.889006 -47.8092) (xy 106.767715 -47.888066) (xy 106.642081 -47.959811)
			(xy 106.512522 -48.024199) (xy 106.379468 -48.081014) (xy 106.243361 -48.130068) (xy 106.104654 -48.171197)
			(xy 105.963808 -48.204266) (xy 105.82129 -48.229165) (xy 105.677574 -48.24581) (xy 105.533138 -48.254146)
			(xy 105.4608 -48.254666) (xy 105.386256 -48.254123) (xy 105.237432 -48.245275) (xy 105.089396 -48.227604)
			(xy 104.942671 -48.201172) (xy 104.797775 -48.166073) (xy 104.655218 -48.122431) (xy 104.515506 -48.070399)
			(xy 104.37913 -48.010162) (xy 104.246572 -47.941932) (xy 104.182164 -47.9044) (xy 103.704136 -47.9044)
			(xy 103.6574 -47.904908) (xy 103.610664 -47.9044) (xy 103.5558 -47.9044) (xy 103.5558 -47.902622)
			(xy 103.490078 -47.899028) (xy 103.359208 -47.884842) (xy 103.229446 -47.862711) (xy 103.101272 -47.832715)
			(xy 102.975164 -47.794968) (xy 102.85159 -47.749608) (xy 102.731008 -47.696805) (xy 102.613867 -47.636754)
			(xy 102.500601 -47.569679) (xy 102.391632 -47.495829) (xy 102.287364 -47.415478) (xy 102.188184 -47.328924)
			(xy 102.094461 -47.23649) (xy 102.006543 -47.138517) (xy 101.924757 -47.035371) (xy 101.849405 -46.927435)
			(xy 101.780769 -46.815108) (xy 101.719103 -46.698809) (xy 101.664636 -46.57897) (xy 101.61757 -46.456035)
			(xy 101.578081 -46.330462) (xy 101.546314 -46.202716) (xy 101.522388 -46.073272) (xy 101.506392 -45.942611)
			(xy 101.498386 -45.811218) (xy 101.497892 -45.7454) (xy 101.498355 -45.681382) (xy 101.505935 -45.553571)
			(xy 101.521076 -45.426434) (xy 101.543724 -45.300418) (xy 101.5738 -45.175964) (xy 101.611197 -45.053512)
			(xy 101.655784 -44.933491) (xy 101.707405 -44.816323) (xy 101.765878 -44.702419) (xy 101.830998 -44.592181)
			(xy 101.902535 -44.485995) (xy 101.980239 -44.384234) (xy 102.063836 -44.287257) (xy 102.153033 -44.195403)
			(xy 102.247516 -44.108997) (xy 102.346952 -44.02834) (xy 102.450994 -43.953718) (xy 102.559274 -43.885392)
			(xy 102.671413 -43.823602) (xy 102.72903 -43.795696) (xy 103.116126 -43.4086) (xy 103.679752 -43.4086)
			(xy 103.679752 -41.371266) (xy 104.26954 -40.781478) (xy 111.866172 -40.781478) (xy 111.873571 -40.774635)
			(xy 111.89217 -40.766914) (xy 111.90224 -40.766492) (xy 118.751096 -40.766492) (xy 118.957852 -40.559736)
			(xy 118.957852 -36.14039) (xy 118.68277 -35.865308) (xy 108.483908 -35.865308) (xy 108.0516 -35.433)
			(xy 108.0516 -29.9212) (xy 108.468922 -29.503878) (xy 111.866172 -29.503878) (xy 111.873571 -29.497035)
			(xy 111.89217 -29.489314) (xy 111.90224 -29.488892) (xy 118.751096 -29.488892) (xy 118.957852 -29.282136)
			(xy 118.957852 -24.86279) (xy 118.68277 -24.587708) (xy 108.560108 -24.587708) (xy 108.0516 -24.0792)
			(xy 108.0516 -18.542) (xy 108.4072 -18.1864) (xy 111.826294 -18.1864) (xy 111.866172 -18.226278)
			(xy 111.873571 -18.219435) (xy 111.89217 -18.211714) (xy 111.90224 -18.211292) (xy 118.751096 -18.211292)
			(xy 118.957852 -18.004536) (xy 118.957852 -13.58519) (xy 118.68277 -13.310108) (xy 102.379272 -13.310108)
			(xy 102.337142 -13.36155) (xy 102.247639 -13.459901) (xy 102.15245 -13.552759) (xy 102.051911 -13.639797)
			(xy 101.946378 -13.720707) (xy 101.836222 -13.795202) (xy 101.721835 -13.863019) (xy 101.60362 -13.92392)
			(xy 101.481995 -13.977688) (xy 101.357389 -14.024133) (xy 101.230244 -14.063092) (xy 101.101008 -14.094426)
			(xy 100.970139 -14.118025) (xy 100.838099 -14.133805) (xy 100.705354 -14.141711) (xy 100.638864 -14.142212)
			(xy 100.614734 -14.141958) (xy 99.23399 -15.522702) (xy 99.23399 -15.53591) (xy 90.521028 -24.248872)
			(xy 90.513627 -24.25571) (xy 90.495028 -24.263423) (xy 90.48496 -24.263858) (xy 81.922874 -24.263858)
			(xy 81.912807 -24.264287) (xy 81.894215 -24.272015) (xy 81.886806 -24.278844) (xy 77.404468 -28.761182)
			(xy 77.397069 -28.768025) (xy 77.37847 -28.775751) (xy 77.3684 -28.776168) (xy 60.872624 -28.776168)
			(xy 60.862573 -28.776673) (xy 60.844011 -28.784393) (xy 60.836556 -28.791154) (xy 55.606696 -34.021014)
			(xy 55.599301 -34.027869) (xy 55.580702 -34.035616) (xy 55.570628 -34.036) (xy 40.301164 -34.036)
			(xy 40.291097 -34.03643) (xy 40.272502 -34.044153) (xy 40.265096 -34.050986) (xy 36.423854 -37.892228)
			(xy 36.416234 -37.912802) (xy 36.41725 -37.923978) (xy 36.420447 -37.967405) (xy 36.423876 -38.054424)
			(xy 36.424108 -38.097968) (xy 36.424108 -38.1) (xy 36.423598 -38.167541) (xy 36.415442 -38.302375)
			(xy 36.39916 -38.436471) (xy 36.374811 -38.56934) (xy 36.342484 -38.700496) (xy 36.302296 -38.829461)
			(xy 36.254396 -38.955764) (xy 36.198957 -39.078944) (xy 36.136182 -39.198552) (xy 36.066299 -39.314152)
			(xy 35.989564 -39.425322) (xy 35.906257 -39.531655) (xy 35.816682 -39.632765) (xy 35.721165 -39.728282)
			(xy 35.620055 -39.817857) (xy 35.513722 -39.901164) (xy 35.402552 -39.977899) (xy 35.286952 -40.047782)
			(xy 35.167344 -40.110557) (xy 35.044164 -40.165996) (xy 34.917861 -40.213896) (xy 34.788896 -40.254084)
			(xy 34.65774 -40.286411) (xy 34.524871 -40.31076) (xy 34.390775 -40.327042) (xy 34.255941 -40.335198)
			(xy 34.1884 -40.335708) (xy 34.145728 -40.3352) (xy 34.135314 -40.3352) (xy 34.116518 -40.342566)
			(xy 34.057336 -40.400732) (xy 34.050426 -40.408105) (xy 34.042577 -40.426706) (xy 34.042096 -40.4368)
			(xy 34.042096 -50.919888) (xy 39.568378 -50.919888) (xy 39.572407 -50.769861) (xy 39.584484 -50.620267)
			(xy 39.604573 -50.471537) (xy 39.632616 -50.324099) (xy 39.668533 -50.178379) (xy 39.712219 -50.034797)
			(xy 39.76355 -49.893767) (xy 39.822377 -49.755696) (xy 39.88853 -49.620981) (xy 39.961819 -49.490012)
			(xy 40.042032 -49.363165) (xy 40.128938 -49.240806) (xy 40.222287 -49.123289) (xy 40.321809 -49.010952)
			(xy 40.427217 -48.904119) (xy 40.538208 -48.803097) (xy 40.654462 -48.708179) (xy 40.775642 -48.619638)
			(xy 40.901401 -48.537729) (xy 41.031375 -48.462689) (xy 41.165189 -48.394733) (xy 41.302458 -48.334058)
			(xy 41.442786 -48.280839) (xy 41.585769 -48.235228) (xy 41.730993 -48.197359) (xy 41.878041 -48.167339)
			(xy 42.026489 -48.145255) (xy 42.175907 -48.131171) (xy 42.325866 -48.125128) (xy 42.475934 -48.127143)
			(xy 42.625677 -48.13721) (xy 42.774663 -48.1553) (xy 42.922464 -48.181361) (xy 43.068653 -48.215319)
			(xy 43.212809 -48.257074) (xy 43.354515 -48.306506) (xy 43.493364 -48.363474) (xy 43.628954 -48.427813)
			(xy 43.760896 -48.499337) (xy 43.888808 -48.57784) (xy 44.012323 -48.663095) (xy 44.131082 -48.754858)
			(xy 44.244746 -48.852863) (xy 44.352984 -48.956827) (xy 44.455487 -49.066452) (xy 44.551957 -49.181421)
			(xy 44.642117 -49.301402) (xy 44.725706 -49.42605) (xy 44.802485 -49.555004) (xy 44.872231 -49.687894)
			(xy 44.934744 -49.824337) (xy 44.989842 -49.963938) (xy 45.037368 -50.106295) (xy 45.077184 -50.250998)
			(xy 45.109176 -50.397629) (xy 45.13325 -50.545767) (xy 45.149339 -50.694983) (xy 45.157394 -50.844848)
			(xy 45.157898 -50.919888) (xy 59.126378 -50.919888) (xy 59.130407 -50.769861) (xy 59.142484 -50.620267)
			(xy 59.162573 -50.471537) (xy 59.190616 -50.324099) (xy 59.226533 -50.178379) (xy 59.270219 -50.034797)
			(xy 59.32155 -49.893767) (xy 59.380377 -49.755696) (xy 59.44653 -49.620981) (xy 59.519819 -49.490012)
			(xy 59.600032 -49.363165) (xy 59.686938 -49.240806) (xy 59.780287 -49.123289) (xy 59.879809 -49.010952)
			(xy 59.985217 -48.904119) (xy 60.096208 -48.803097) (xy 60.212462 -48.708179) (xy 60.333642 -48.619638)
			(xy 60.459401 -48.537729) (xy 60.589375 -48.462689) (xy 60.723189 -48.394733) (xy 60.860458 -48.334058)
			(xy 61.000786 -48.280839) (xy 61.143769 -48.235228) (xy 61.288993 -48.197359) (xy 61.436041 -48.167339)
			(xy 61.584489 -48.145255) (xy 61.733907 -48.131171) (xy 61.883866 -48.125128) (xy 62.033934 -48.127143)
			(xy 62.183677 -48.13721) (xy 62.332663 -48.1553) (xy 62.480464 -48.181361) (xy 62.626653 -48.215319)
			(xy 62.770809 -48.257074) (xy 62.912515 -48.306506) (xy 63.051364 -48.363474) (xy 63.186954 -48.427813)
			(xy 63.318896 -48.499337) (xy 63.446808 -48.57784) (xy 63.570323 -48.663095) (xy 63.689082 -48.754858)
			(xy 63.802746 -48.852863) (xy 63.910984 -48.956827) (xy 64.013487 -49.066452) (xy 64.109957 -49.181421)
			(xy 64.200117 -49.301402) (xy 64.283706 -49.42605) (xy 64.360485 -49.555004) (xy 64.430231 -49.687894)
			(xy 64.492744 -49.824337) (xy 64.547842 -49.963938) (xy 64.595368 -50.106295) (xy 64.635184 -50.250998)
			(xy 64.667176 -50.397629) (xy 64.69125 -50.545767) (xy 64.707339 -50.694983) (xy 64.715394 -50.844848)
			(xy 64.715898 -50.919888) (xy 64.715394 -50.994928) (xy 64.707339 -51.144793) (xy 64.69125 -51.294009)
			(xy 64.667176 -51.442147) (xy 64.635184 -51.588778) (xy 64.595368 -51.733481) (xy 64.547842 -51.875838)
			(xy 64.492744 -52.015439) (xy 64.430231 -52.151882) (xy 64.360485 -52.284772) (xy 64.283706 -52.413726)
			(xy 64.200117 -52.538374) (xy 64.109957 -52.658355) (xy 64.013487 -52.773324) (xy 63.910984 -52.882949)
			(xy 63.802746 -52.986913) (xy 63.689082 -53.084918) (xy 63.570323 -53.176681) (xy 63.446808 -53.261936)
			(xy 63.318896 -53.340439) (xy 63.186954 -53.411963) (xy 63.051364 -53.476302) (xy 62.912515 -53.53327)
			(xy 62.770809 -53.582702) (xy 62.626653 -53.624457) (xy 62.480464 -53.658415) (xy 62.332663 -53.684476)
			(xy 62.183677 -53.702566) (xy 62.033934 -53.712633) (xy 61.883866 -53.714648) (xy 61.733907 -53.708605)
			(xy 61.584489 -53.694521) (xy 61.436041 -53.672437) (xy 61.288993 -53.642417) (xy 61.143769 -53.604548)
			(xy 61.000786 -53.558937) (xy 60.860458 -53.505718) (xy 60.723189 -53.445043) (xy 60.589375 -53.377087)
			(xy 60.459401 -53.302047) (xy 60.333642 -53.220138) (xy 60.212462 -53.131597) (xy 60.096208 -53.036679)
			(xy 59.985217 -52.935657) (xy 59.879809 -52.828824) (xy 59.780287 -52.716487) (xy 59.686938 -52.59897)
			(xy 59.600032 -52.476611) (xy 59.519819 -52.349764) (xy 59.44653 -52.218795) (xy 59.380377 -52.08408)
			(xy 59.32155 -51.946009) (xy 59.270219 -51.804979) (xy 59.226533 -51.661397) (xy 59.190616 -51.515677)
			(xy 59.162573 -51.368239) (xy 59.142484 -51.219509) (xy 59.130407 -51.069915) (xy 59.126378 -50.919888)
			(xy 45.157898 -50.919888) (xy 45.157394 -50.994928) (xy 45.149339 -51.144793) (xy 45.13325 -51.294009)
			(xy 45.109176 -51.442147) (xy 45.077184 -51.588778) (xy 45.037368 -51.733481) (xy 44.989842 -51.875838)
			(xy 44.934744 -52.015439) (xy 44.872231 -52.151882) (xy 44.802485 -52.284772) (xy 44.725706 -52.413726)
			(xy 44.642117 -52.538374) (xy 44.551957 -52.658355) (xy 44.455487 -52.773324) (xy 44.352984 -52.882949)
			(xy 44.244746 -52.986913) (xy 44.131082 -53.084918) (xy 44.012323 -53.176681) (xy 43.888808 -53.261936)
			(xy 43.760896 -53.340439) (xy 43.628954 -53.411963) (xy 43.493364 -53.476302) (xy 43.354515 -53.53327)
			(xy 43.212809 -53.582702) (xy 43.068653 -53.624457) (xy 42.922464 -53.658415) (xy 42.774663 -53.684476)
			(xy 42.625677 -53.702566) (xy 42.475934 -53.712633) (xy 42.325866 -53.714648) (xy 42.175907 -53.708605)
			(xy 42.026489 -53.694521) (xy 41.878041 -53.672437) (xy 41.730993 -53.642417) (xy 41.585769 -53.604548)
			(xy 41.442786 -53.558937) (xy 41.302458 -53.505718) (xy 41.165189 -53.445043) (xy 41.031375 -53.377087)
			(xy 40.901401 -53.302047) (xy 40.775642 -53.220138) (xy 40.654462 -53.131597) (xy 40.538208 -53.036679)
			(xy 40.427217 -52.935657) (xy 40.321809 -52.828824) (xy 40.222287 -52.716487) (xy 40.128938 -52.59897)
			(xy 40.042032 -52.476611) (xy 39.961819 -52.349764) (xy 39.88853 -52.218795) (xy 39.822377 -52.08408)
			(xy 39.76355 -51.946009) (xy 39.712219 -51.804979) (xy 39.668533 -51.661397) (xy 39.632616 -51.515677)
			(xy 39.604573 -51.368239) (xy 39.584484 -51.219509) (xy 39.572407 -51.069915) (xy 39.568378 -50.919888)
			(xy 34.042096 -50.919888) (xy 34.042096 -59.309508) (xy 41.347136 -59.309508) (xy 41.347136 -57.531)
			(xy 41.347635 -57.514302) (xy 41.35627 -57.482043) (xy 41.372951 -57.453113) (xy 41.396546 -57.42948)
			(xy 41.425448 -57.41275) (xy 41.457693 -57.404063) (xy 41.47439 -57.403492) (xy 43.25239 -57.403492)
			(xy 43.269054 -57.403997) (xy 43.301249 -57.412612) (xy 43.330122 -57.429258) (xy 43.353708 -57.452804)
			(xy 43.370404 -57.481649) (xy 43.379075 -57.513829) (xy 43.379644 -57.530492) (xy 43.379644 -59.309)
			(xy 43.379626 -59.309508) (xy 60.905136 -59.309508) (xy 60.905136 -57.531) (xy 60.905635 -57.514302)
			(xy 60.91427 -57.482043) (xy 60.930951 -57.453113) (xy 60.954546 -57.42948) (xy 60.983448 -57.41275)
			(xy 61.015693 -57.404063) (xy 61.03239 -57.403492) (xy 62.81039 -57.403492) (xy 62.827054 -57.403997)
			(xy 62.859249 -57.412612) (xy 62.888122 -57.429258) (xy 62.911708 -57.452804) (xy 62.928404 -57.481649)
			(xy 62.937075 -57.513829) (xy 62.937644 -57.530492) (xy 62.937644 -59.309) (xy 62.937066 -59.325691)
			(xy 62.928438 -59.357939) (xy 62.911769 -59.386861) (xy 62.888192 -59.410492) (xy 62.859308 -59.427227)
			(xy 62.82708 -59.435928) (xy 62.81039 -59.436508) (xy 61.03239 -59.436508) (xy 61.015725 -59.436021)
			(xy 60.983529 -59.427401) (xy 60.954657 -59.41075) (xy 60.931071 -59.387201) (xy 60.914375 -59.358354)
			(xy 60.905705 -59.326172) (xy 60.905136 -59.309508) (xy 43.379626 -59.309508) (xy 43.379066 -59.325691)
			(xy 43.370438 -59.357939) (xy 43.353769 -59.386861) (xy 43.330192 -59.410492) (xy 43.301308 -59.427227)
			(xy 43.26908 -59.435928) (xy 43.25239 -59.436508) (xy 41.47439 -59.436508) (xy 41.457725 -59.436021)
			(xy 41.425529 -59.427401) (xy 41.396657 -59.41075) (xy 41.373071 -59.387201) (xy 41.356375 -59.358354)
			(xy 41.347705 -59.326172) (xy 41.347136 -59.309508) (xy 34.042096 -59.309508) (xy 34.042096 -71.239888)
			(xy 39.568378 -71.239888) (xy 39.572407 -71.089861) (xy 39.584484 -70.940267) (xy 39.604573 -70.791537)
			(xy 39.632616 -70.644099) (xy 39.668533 -70.498379) (xy 39.712219 -70.354797) (xy 39.76355 -70.213767)
			(xy 39.822377 -70.075696) (xy 39.88853 -69.940981) (xy 39.961819 -69.810012) (xy 40.042032 -69.683165)
			(xy 40.128938 -69.560806) (xy 40.222287 -69.443289) (xy 40.321809 -69.330952) (xy 40.427217 -69.224119)
			(xy 40.538208 -69.123097) (xy 40.654462 -69.028179) (xy 40.775642 -68.939638) (xy 40.901401 -68.857729)
			(xy 41.031375 -68.782689) (xy 41.165189 -68.714733) (xy 41.302458 -68.654058) (xy 41.442786 -68.600839)
			(xy 41.585769 -68.555228) (xy 41.730993 -68.517359) (xy 41.878041 -68.487339) (xy 42.026489 -68.465255)
			(xy 42.175907 -68.451171) (xy 42.325866 -68.445128) (xy 42.475934 -68.447143) (xy 42.625677 -68.45721)
			(xy 42.774663 -68.4753) (xy 42.922464 -68.501361) (xy 43.068653 -68.535319) (xy 43.212809 -68.577074)
			(xy 43.354515 -68.626506) (xy 43.493364 -68.683474) (xy 43.628954 -68.747813) (xy 43.760896 -68.819337)
			(xy 43.888808 -68.89784) (xy 44.012323 -68.983095) (xy 44.131082 -69.074858) (xy 44.244746 -69.172863)
			(xy 44.352984 -69.276827) (xy 44.455487 -69.386452) (xy 44.551957 -69.501421) (xy 44.642117 -69.621402)
			(xy 44.725706 -69.74605) (xy 44.802485 -69.875004) (xy 44.872231 -70.007894) (xy 44.934744 -70.144337)
			(xy 44.989842 -70.283938) (xy 45.037368 -70.426295) (xy 45.077184 -70.570998) (xy 45.109176 -70.717629)
			(xy 45.13325 -70.865767) (xy 45.149339 -71.014983) (xy 45.157394 -71.164848) (xy 45.157898 -71.239888)
			(xy 59.126378 -71.239888) (xy 59.130407 -71.089861) (xy 59.142484 -70.940267) (xy 59.162573 -70.791537)
			(xy 59.190616 -70.644099) (xy 59.226533 -70.498379) (xy 59.270219 -70.354797) (xy 59.32155 -70.213767)
			(xy 59.380377 -70.075696) (xy 59.44653 -69.940981) (xy 59.519819 -69.810012) (xy 59.600032 -69.683165)
			(xy 59.686938 -69.560806) (xy 59.780287 -69.443289) (xy 59.879809 -69.330952) (xy 59.985217 -69.224119)
			(xy 60.096208 -69.123097) (xy 60.212462 -69.028179) (xy 60.333642 -68.939638) (xy 60.459401 -68.857729)
			(xy 60.589375 -68.782689) (xy 60.723189 -68.714733) (xy 60.860458 -68.654058) (xy 61.000786 -68.600839)
			(xy 61.143769 -68.555228) (xy 61.288993 -68.517359) (xy 61.436041 -68.487339) (xy 61.584489 -68.465255)
			(xy 61.733907 -68.451171) (xy 61.883866 -68.445128) (xy 62.033934 -68.447143) (xy 62.183677 -68.45721)
			(xy 62.332663 -68.4753) (xy 62.480464 -68.501361) (xy 62.626653 -68.535319) (xy 62.770809 -68.577074)
			(xy 62.912515 -68.626506) (xy 63.051364 -68.683474) (xy 63.186954 -68.747813) (xy 63.318896 -68.819337)
			(xy 63.446808 -68.89784) (xy 63.570323 -68.983095) (xy 63.689082 -69.074858) (xy 63.802746 -69.172863)
			(xy 63.910984 -69.276827) (xy 64.013487 -69.386452) (xy 64.109957 -69.501421) (xy 64.200117 -69.621402)
			(xy 64.283706 -69.74605) (xy 64.360485 -69.875004) (xy 64.430231 -70.007894) (xy 64.492744 -70.144337)
			(xy 64.547842 -70.283938) (xy 64.595368 -70.426295) (xy 64.635184 -70.570998) (xy 64.667176 -70.717629)
			(xy 64.69125 -70.865767) (xy 64.707339 -71.014983) (xy 64.715394 -71.164848) (xy 64.715898 -71.239888)
			(xy 64.715394 -71.314928) (xy 64.707339 -71.464793) (xy 64.69125 -71.614009) (xy 64.667176 -71.762147)
			(xy 64.635184 -71.908778) (xy 64.595368 -72.053481) (xy 64.547842 -72.195838) (xy 64.492744 -72.335439)
			(xy 64.430231 -72.471882) (xy 64.360485 -72.604772) (xy 64.283706 -72.733726) (xy 64.200117 -72.858374)
			(xy 64.109957 -72.978355) (xy 64.013487 -73.093324) (xy 63.910984 -73.202949) (xy 63.802746 -73.306913)
			(xy 63.689082 -73.404918) (xy 63.570323 -73.496681) (xy 63.446808 -73.581936) (xy 63.318896 -73.660439)
			(xy 63.186954 -73.731963) (xy 63.051364 -73.796302) (xy 62.912515 -73.85327) (xy 62.770809 -73.902702)
			(xy 62.626653 -73.944457) (xy 62.480464 -73.978415) (xy 62.332663 -74.004476) (xy 62.183677 -74.022566)
			(xy 62.033934 -74.032633) (xy 61.883866 -74.034648) (xy 61.733907 -74.028605) (xy 61.584489 -74.014521)
			(xy 61.436041 -73.992437) (xy 61.288993 -73.962417) (xy 61.143769 -73.924548) (xy 61.000786 -73.878937)
			(xy 60.860458 -73.825718) (xy 60.723189 -73.765043) (xy 60.589375 -73.697087) (xy 60.459401 -73.622047)
			(xy 60.333642 -73.540138) (xy 60.212462 -73.451597) (xy 60.096208 -73.356679) (xy 59.985217 -73.255657)
			(xy 59.879809 -73.148824) (xy 59.780287 -73.036487) (xy 59.686938 -72.91897) (xy 59.600032 -72.796611)
			(xy 59.519819 -72.669764) (xy 59.44653 -72.538795) (xy 59.380377 -72.40408) (xy 59.32155 -72.266009)
			(xy 59.270219 -72.124979) (xy 59.226533 -71.981397) (xy 59.190616 -71.835677) (xy 59.162573 -71.688239)
			(xy 59.142484 -71.539509) (xy 59.130407 -71.389915) (xy 59.126378 -71.239888) (xy 45.157898 -71.239888)
			(xy 45.157394 -71.314928) (xy 45.149339 -71.464793) (xy 45.13325 -71.614009) (xy 45.109176 -71.762147)
			(xy 45.077184 -71.908778) (xy 45.037368 -72.053481) (xy 44.989842 -72.195838) (xy 44.934744 -72.335439)
			(xy 44.872231 -72.471882) (xy 44.802485 -72.604772) (xy 44.725706 -72.733726) (xy 44.642117 -72.858374)
			(xy 44.551957 -72.978355) (xy 44.455487 -73.093324) (xy 44.352984 -73.202949) (xy 44.244746 -73.306913)
			(xy 44.131082 -73.404918) (xy 44.012323 -73.496681) (xy 43.888808 -73.581936) (xy 43.760896 -73.660439)
			(xy 43.628954 -73.731963) (xy 43.493364 -73.796302) (xy 43.354515 -73.85327) (xy 43.212809 -73.902702)
			(xy 43.068653 -73.944457) (xy 42.922464 -73.978415) (xy 42.774663 -74.004476) (xy 42.625677 -74.022566)
			(xy 42.475934 -74.032633) (xy 42.325866 -74.034648) (xy 42.175907 -74.028605) (xy 42.026489 -74.014521)
			(xy 41.878041 -73.992437) (xy 41.730993 -73.962417) (xy 41.585769 -73.924548) (xy 41.442786 -73.878937)
			(xy 41.302458 -73.825718) (xy 41.165189 -73.765043) (xy 41.031375 -73.697087) (xy 40.901401 -73.622047)
			(xy 40.775642 -73.540138) (xy 40.654462 -73.451597) (xy 40.538208 -73.356679) (xy 40.427217 -73.255657)
			(xy 40.321809 -73.148824) (xy 40.222287 -73.036487) (xy 40.128938 -72.91897) (xy 40.042032 -72.796611)
			(xy 39.961819 -72.669764) (xy 39.88853 -72.538795) (xy 39.822377 -72.40408) (xy 39.76355 -72.266009)
			(xy 39.712219 -72.124979) (xy 39.668533 -71.981397) (xy 39.632616 -71.835677) (xy 39.604573 -71.688239)
			(xy 39.584484 -71.539509) (xy 39.572407 -71.389915) (xy 39.568378 -71.239888) (xy 34.042096 -71.239888)
			(xy 34.042096 -79.629508) (xy 41.347136 -79.629508) (xy 41.347136 -77.851) (xy 41.347635 -77.834302)
			(xy 41.35627 -77.802043) (xy 41.372951 -77.773113) (xy 41.396546 -77.74948) (xy 41.425448 -77.73275)
			(xy 41.457693 -77.724063) (xy 41.47439 -77.723492) (xy 43.25239 -77.723492) (xy 43.269054 -77.723997)
			(xy 43.301249 -77.732612) (xy 43.330122 -77.749258) (xy 43.353708 -77.772804) (xy 43.370404 -77.801649)
			(xy 43.379075 -77.833829) (xy 43.379644 -77.850492) (xy 43.379644 -79.629) (xy 43.379626 -79.629508)
			(xy 60.905136 -79.629508) (xy 60.905136 -77.851) (xy 60.905635 -77.834302) (xy 60.91427 -77.802043)
			(xy 60.930951 -77.773113) (xy 60.954546 -77.74948) (xy 60.983448 -77.73275) (xy 61.015693 -77.724063)
			(xy 61.03239 -77.723492) (xy 62.81039 -77.723492) (xy 62.827054 -77.723997) (xy 62.859249 -77.732612)
			(xy 62.888122 -77.749258) (xy 62.911708 -77.772804) (xy 62.928404 -77.801649) (xy 62.937075 -77.833829)
			(xy 62.937644 -77.850492) (xy 62.937644 -79.629) (xy 62.937066 -79.645691) (xy 62.928438 -79.677939)
			(xy 62.911769 -79.706861) (xy 62.888192 -79.730492) (xy 62.859308 -79.747227) (xy 62.82708 -79.755928)
			(xy 62.81039 -79.756508) (xy 61.03239 -79.756508) (xy 61.015725 -79.756021) (xy 60.983529 -79.747401)
			(xy 60.954657 -79.73075) (xy 60.931071 -79.707201) (xy 60.914375 -79.678354) (xy 60.905705 -79.646172)
			(xy 60.905136 -79.629508) (xy 43.379626 -79.629508) (xy 43.379066 -79.645691) (xy 43.370438 -79.677939)
			(xy 43.353769 -79.706861) (xy 43.330192 -79.730492) (xy 43.301308 -79.747227) (xy 43.26908 -79.755928)
			(xy 43.25239 -79.756508) (xy 41.47439 -79.756508) (xy 41.457725 -79.756021) (xy 41.425529 -79.747401)
			(xy 41.396657 -79.73075) (xy 41.373071 -79.707201) (xy 41.356375 -79.678354) (xy 41.347705 -79.646172)
			(xy 41.347136 -79.629508) (xy 34.042096 -79.629508) (xy 34.042096 -91.559888) (xy 39.568378 -91.559888)
			(xy 39.572407 -91.409861) (xy 39.584484 -91.260267) (xy 39.604573 -91.111537) (xy 39.632616 -90.964099)
			(xy 39.668533 -90.818379) (xy 39.712219 -90.674797) (xy 39.76355 -90.533767) (xy 39.822377 -90.395696)
			(xy 39.88853 -90.260981) (xy 39.961819 -90.130012) (xy 40.042032 -90.003165) (xy 40.128938 -89.880806)
			(xy 40.222287 -89.763289) (xy 40.321809 -89.650952) (xy 40.427217 -89.544119) (xy 40.538208 -89.443097)
			(xy 40.654462 -89.348179) (xy 40.775642 -89.259638) (xy 40.901401 -89.177729) (xy 41.031375 -89.102689)
			(xy 41.165189 -89.034733) (xy 41.302458 -88.974058) (xy 41.442786 -88.920839) (xy 41.585769 -88.875228)
			(xy 41.730993 -88.837359) (xy 41.878041 -88.807339) (xy 42.026489 -88.785255) (xy 42.175907 -88.771171)
			(xy 42.325866 -88.765128) (xy 42.475934 -88.767143) (xy 42.625677 -88.77721) (xy 42.774663 -88.7953)
			(xy 42.922464 -88.821361) (xy 43.068653 -88.855319) (xy 43.212809 -88.897074) (xy 43.354515 -88.946506)
			(xy 43.493364 -89.003474) (xy 43.628954 -89.067813) (xy 43.760896 -89.139337) (xy 43.888808 -89.21784)
			(xy 44.012323 -89.303095) (xy 44.131082 -89.394858) (xy 44.244746 -89.492863) (xy 44.352984 -89.596827)
			(xy 44.455487 -89.706452) (xy 44.551957 -89.821421) (xy 44.642117 -89.941402) (xy 44.725706 -90.06605)
			(xy 44.802485 -90.195004) (xy 44.872231 -90.327894) (xy 44.934744 -90.464337) (xy 44.989842 -90.603938)
			(xy 45.037368 -90.746295) (xy 45.077184 -90.890998) (xy 45.109176 -91.037629) (xy 45.13325 -91.185767)
			(xy 45.149339 -91.334983) (xy 45.157394 -91.484848) (xy 45.157898 -91.559888) (xy 59.126378 -91.559888)
			(xy 59.130407 -91.409861) (xy 59.142484 -91.260267) (xy 59.162573 -91.111537) (xy 59.190616 -90.964099)
			(xy 59.226533 -90.818379) (xy 59.270219 -90.674797) (xy 59.32155 -90.533767) (xy 59.380377 -90.395696)
			(xy 59.44653 -90.260981) (xy 59.519819 -90.130012) (xy 59.600032 -90.003165) (xy 59.686938 -89.880806)
			(xy 59.780287 -89.763289) (xy 59.879809 -89.650952) (xy 59.985217 -89.544119) (xy 60.096208 -89.443097)
			(xy 60.212462 -89.348179) (xy 60.333642 -89.259638) (xy 60.459401 -89.177729) (xy 60.589375 -89.102689)
			(xy 60.723189 -89.034733) (xy 60.860458 -88.974058) (xy 61.000786 -88.920839) (xy 61.143769 -88.875228)
			(xy 61.288993 -88.837359) (xy 61.436041 -88.807339) (xy 61.584489 -88.785255) (xy 61.733907 -88.771171)
			(xy 61.883866 -88.765128) (xy 62.033934 -88.767143) (xy 62.183677 -88.77721) (xy 62.332663 -88.7953)
			(xy 62.480464 -88.821361) (xy 62.626653 -88.855319) (xy 62.770809 -88.897074) (xy 62.912515 -88.946506)
			(xy 63.051364 -89.003474) (xy 63.186954 -89.067813) (xy 63.318896 -89.139337) (xy 63.446808 -89.21784)
			(xy 63.570323 -89.303095) (xy 63.689082 -89.394858) (xy 63.802746 -89.492863) (xy 63.910984 -89.596827)
			(xy 64.013487 -89.706452) (xy 64.109957 -89.821421) (xy 64.200117 -89.941402) (xy 64.283706 -90.06605)
			(xy 64.360485 -90.195004) (xy 64.430231 -90.327894) (xy 64.492744 -90.464337) (xy 64.547842 -90.603938)
			(xy 64.595368 -90.746295) (xy 64.635184 -90.890998) (xy 64.667176 -91.037629) (xy 64.69125 -91.185767)
			(xy 64.707339 -91.334983) (xy 64.715394 -91.484848) (xy 64.715898 -91.559888) (xy 64.715394 -91.634928)
			(xy 64.707339 -91.784793) (xy 64.69125 -91.934009) (xy 64.667176 -92.082147) (xy 64.635184 -92.228778)
			(xy 64.595368 -92.373481) (xy 64.547842 -92.515838) (xy 64.492744 -92.655439) (xy 64.430231 -92.791882)
			(xy 64.360485 -92.924772) (xy 64.283706 -93.053726) (xy 64.200117 -93.178374) (xy 64.109957 -93.298355)
			(xy 64.013487 -93.413324) (xy 63.910984 -93.522949) (xy 63.802746 -93.626913) (xy 63.689082 -93.724918)
			(xy 63.570323 -93.816681) (xy 63.446808 -93.901936) (xy 63.318896 -93.980439) (xy 63.186954 -94.051963)
			(xy 63.051364 -94.116302) (xy 62.912515 -94.17327) (xy 62.770809 -94.222702) (xy 62.626653 -94.264457)
			(xy 62.480464 -94.298415) (xy 62.332663 -94.324476) (xy 62.183677 -94.342566) (xy 62.033934 -94.352633)
			(xy 61.883866 -94.354648) (xy 61.733907 -94.348605) (xy 61.584489 -94.334521) (xy 61.436041 -94.312437)
			(xy 61.288993 -94.282417) (xy 61.143769 -94.244548) (xy 61.000786 -94.198937) (xy 60.860458 -94.145718)
			(xy 60.723189 -94.085043) (xy 60.589375 -94.017087) (xy 60.459401 -93.942047) (xy 60.333642 -93.860138)
			(xy 60.212462 -93.771597) (xy 60.096208 -93.676679) (xy 59.985217 -93.575657) (xy 59.879809 -93.468824)
			(xy 59.780287 -93.356487) (xy 59.686938 -93.23897) (xy 59.600032 -93.116611) (xy 59.519819 -92.989764)
			(xy 59.44653 -92.858795) (xy 59.380377 -92.72408) (xy 59.32155 -92.586009) (xy 59.270219 -92.444979)
			(xy 59.226533 -92.301397) (xy 59.190616 -92.155677) (xy 59.162573 -92.008239) (xy 59.142484 -91.859509)
			(xy 59.130407 -91.709915) (xy 59.126378 -91.559888) (xy 45.157898 -91.559888) (xy 45.157394 -91.634928)
			(xy 45.149339 -91.784793) (xy 45.13325 -91.934009) (xy 45.109176 -92.082147) (xy 45.077184 -92.228778)
			(xy 45.037368 -92.373481) (xy 44.989842 -92.515838) (xy 44.934744 -92.655439) (xy 44.872231 -92.791882)
			(xy 44.802485 -92.924772) (xy 44.725706 -93.053726) (xy 44.642117 -93.178374) (xy 44.551957 -93.298355)
			(xy 44.455487 -93.413324) (xy 44.352984 -93.522949) (xy 44.244746 -93.626913) (xy 44.131082 -93.724918)
			(xy 44.012323 -93.816681) (xy 43.888808 -93.901936) (xy 43.760896 -93.980439) (xy 43.628954 -94.051963)
			(xy 43.493364 -94.116302) (xy 43.354515 -94.17327) (xy 43.212809 -94.222702) (xy 43.068653 -94.264457)
			(xy 42.922464 -94.298415) (xy 42.774663 -94.324476) (xy 42.625677 -94.342566) (xy 42.475934 -94.352633)
			(xy 42.325866 -94.354648) (xy 42.175907 -94.348605) (xy 42.026489 -94.334521) (xy 41.878041 -94.312437)
			(xy 41.730993 -94.282417) (xy 41.585769 -94.244548) (xy 41.442786 -94.198937) (xy 41.302458 -94.145718)
			(xy 41.165189 -94.085043) (xy 41.031375 -94.017087) (xy 40.901401 -93.942047) (xy 40.775642 -93.860138)
			(xy 40.654462 -93.771597) (xy 40.538208 -93.676679) (xy 40.427217 -93.575657) (xy 40.321809 -93.468824)
			(xy 40.222287 -93.356487) (xy 40.128938 -93.23897) (xy 40.042032 -93.116611) (xy 39.961819 -92.989764)
			(xy 39.88853 -92.858795) (xy 39.822377 -92.72408) (xy 39.76355 -92.586009) (xy 39.712219 -92.444979)
			(xy 39.668533 -92.301397) (xy 39.632616 -92.155677) (xy 39.604573 -92.008239) (xy 39.584484 -91.859509)
			(xy 39.572407 -91.709915) (xy 39.568378 -91.559888) (xy 34.042096 -91.559888) (xy 34.042096 -99.949508)
			(xy 41.347136 -99.949508) (xy 41.347136 -98.171) (xy 41.347635 -98.154302) (xy 41.35627 -98.122043)
			(xy 41.372951 -98.093113) (xy 41.396546 -98.06948) (xy 41.425448 -98.05275) (xy 41.457693 -98.044063)
			(xy 41.47439 -98.043492) (xy 43.25239 -98.043492) (xy 43.269054 -98.043997) (xy 43.301249 -98.052612)
			(xy 43.330122 -98.069258) (xy 43.353708 -98.092804) (xy 43.370404 -98.121649) (xy 43.379075 -98.153829)
			(xy 43.379644 -98.170492) (xy 43.379644 -99.949) (xy 43.379626 -99.949508) (xy 60.905136 -99.949508)
			(xy 60.905136 -98.171) (xy 60.905635 -98.154302) (xy 60.91427 -98.122043) (xy 60.930951 -98.093113)
			(xy 60.954546 -98.06948) (xy 60.983448 -98.05275) (xy 61.015693 -98.044063) (xy 61.03239 -98.043492)
			(xy 62.81039 -98.043492) (xy 62.827054 -98.043997) (xy 62.859249 -98.052612) (xy 62.888122 -98.069258)
			(xy 62.911708 -98.092804) (xy 62.928404 -98.121649) (xy 62.937075 -98.153829) (xy 62.937644 -98.170492)
			(xy 62.937644 -99.949) (xy 62.937066 -99.965691) (xy 62.928438 -99.997939) (xy 62.911769 -100.026861)
			(xy 62.888192 -100.050492) (xy 62.859308 -100.067227) (xy 62.82708 -100.075928) (xy 62.81039 -100.076508)
			(xy 61.03239 -100.076508) (xy 61.015725 -100.076021) (xy 60.983529 -100.067401) (xy 60.954657 -100.05075)
			(xy 60.931071 -100.027201) (xy 60.914375 -99.998354) (xy 60.905705 -99.966172) (xy 60.905136 -99.949508)
			(xy 43.379626 -99.949508) (xy 43.379066 -99.965691) (xy 43.370438 -99.997939) (xy 43.353769 -100.026861)
			(xy 43.330192 -100.050492) (xy 43.301308 -100.067227) (xy 43.26908 -100.075928) (xy 43.25239 -100.076508)
			(xy 41.47439 -100.076508) (xy 41.457725 -100.076021) (xy 41.425529 -100.067401) (xy 41.396657 -100.05075)
			(xy 41.373071 -100.027201) (xy 41.356375 -99.998354) (xy 41.347705 -99.966172) (xy 41.347136 -99.949508)
			(xy 34.042096 -99.949508) (xy 34.042096 -111.879888) (xy 39.568378 -111.879888) (xy 39.572407 -111.729861)
			(xy 39.584484 -111.580267) (xy 39.604573 -111.431537) (xy 39.632616 -111.284099) (xy 39.668533 -111.138379)
			(xy 39.712219 -110.994797) (xy 39.76355 -110.853767) (xy 39.822377 -110.715696) (xy 39.88853 -110.580981)
			(xy 39.961819 -110.450012) (xy 40.042032 -110.323165) (xy 40.128938 -110.200806) (xy 40.222287 -110.083289)
			(xy 40.321809 -109.970952) (xy 40.427217 -109.864119) (xy 40.538208 -109.763097) (xy 40.654462 -109.668179)
			(xy 40.775642 -109.579638) (xy 40.901401 -109.497729) (xy 41.031375 -109.422689) (xy 41.165189 -109.354733)
			(xy 41.302458 -109.294058) (xy 41.442786 -109.240839) (xy 41.585769 -109.195228) (xy 41.730993 -109.157359)
			(xy 41.878041 -109.127339) (xy 42.026489 -109.105255) (xy 42.175907 -109.091171) (xy 42.325866 -109.085128)
			(xy 42.475934 -109.087143) (xy 42.625677 -109.09721) (xy 42.774663 -109.1153) (xy 42.922464 -109.141361)
			(xy 43.068653 -109.175319) (xy 43.212809 -109.217074) (xy 43.354515 -109.266506) (xy 43.493364 -109.323474)
			(xy 43.628954 -109.387813) (xy 43.760896 -109.459337) (xy 43.888808 -109.53784) (xy 44.012323 -109.623095)
			(xy 44.131082 -109.714858) (xy 44.244746 -109.812863) (xy 44.352984 -109.916827) (xy 44.455487 -110.026452)
			(xy 44.551957 -110.141421) (xy 44.642117 -110.261402) (xy 44.725706 -110.38605) (xy 44.802485 -110.515004)
			(xy 44.872231 -110.647894) (xy 44.934744 -110.784337) (xy 44.989842 -110.923938) (xy 45.037368 -111.066295)
			(xy 45.077184 -111.210998) (xy 45.109176 -111.357629) (xy 45.13325 -111.505767) (xy 45.149339 -111.654983)
			(xy 45.157394 -111.804848) (xy 45.157898 -111.879888) (xy 59.126378 -111.879888) (xy 59.130407 -111.729861)
			(xy 59.142484 -111.580267) (xy 59.162573 -111.431537) (xy 59.190616 -111.284099) (xy 59.226533 -111.138379)
			(xy 59.270219 -110.994797) (xy 59.32155 -110.853767) (xy 59.380377 -110.715696) (xy 59.44653 -110.580981)
			(xy 59.519819 -110.450012) (xy 59.600032 -110.323165) (xy 59.686938 -110.200806) (xy 59.780287 -110.083289)
			(xy 59.879809 -109.970952) (xy 59.985217 -109.864119) (xy 60.096208 -109.763097) (xy 60.212462 -109.668179)
			(xy 60.333642 -109.579638) (xy 60.459401 -109.497729) (xy 60.589375 -109.422689) (xy 60.723189 -109.354733)
			(xy 60.860458 -109.294058) (xy 61.000786 -109.240839) (xy 61.143769 -109.195228) (xy 61.288993 -109.157359)
			(xy 61.436041 -109.127339) (xy 61.584489 -109.105255) (xy 61.733907 -109.091171) (xy 61.883866 -109.085128)
			(xy 62.033934 -109.087143) (xy 62.183677 -109.09721) (xy 62.332663 -109.1153) (xy 62.480464 -109.141361)
			(xy 62.626653 -109.175319) (xy 62.770809 -109.217074) (xy 62.912515 -109.266506) (xy 63.051364 -109.323474)
			(xy 63.186954 -109.387813) (xy 63.318896 -109.459337) (xy 63.446808 -109.53784) (xy 63.570323 -109.623095)
			(xy 63.689082 -109.714858) (xy 63.802746 -109.812863) (xy 63.910984 -109.916827) (xy 64.013487 -110.026452)
			(xy 64.109957 -110.141421) (xy 64.200117 -110.261402) (xy 64.283706 -110.38605) (xy 64.360485 -110.515004)
			(xy 64.430231 -110.647894) (xy 64.492744 -110.784337) (xy 64.547842 -110.923938) (xy 64.595368 -111.066295)
			(xy 64.635184 -111.210998) (xy 64.667176 -111.357629) (xy 64.69125 -111.505767) (xy 64.707339 -111.654983)
			(xy 64.715394 -111.804848) (xy 64.715898 -111.879888) (xy 64.715394 -111.954928) (xy 64.707339 -112.104793)
			(xy 64.69125 -112.254009) (xy 64.667176 -112.402147) (xy 64.635184 -112.548778) (xy 64.595368 -112.693481)
			(xy 64.547842 -112.835838) (xy 64.492744 -112.975439) (xy 64.430231 -113.111882) (xy 64.360485 -113.244772)
			(xy 64.283706 -113.373726) (xy 64.200117 -113.498374) (xy 64.109957 -113.618355) (xy 64.013487 -113.733324)
			(xy 63.910984 -113.842949) (xy 63.802746 -113.946913) (xy 63.689082 -114.044918) (xy 63.570323 -114.136681)
			(xy 63.446808 -114.221936) (xy 63.318896 -114.300439) (xy 63.186954 -114.371963) (xy 63.051364 -114.436302)
			(xy 62.912515 -114.49327) (xy 62.770809 -114.542702) (xy 62.626653 -114.584457) (xy 62.480464 -114.618415)
			(xy 62.332663 -114.644476) (xy 62.183677 -114.662566) (xy 62.033934 -114.672633) (xy 61.883866 -114.674648)
			(xy 61.733907 -114.668605) (xy 61.584489 -114.654521) (xy 61.436041 -114.632437) (xy 61.288993 -114.602417)
			(xy 61.143769 -114.564548) (xy 61.000786 -114.518937) (xy 60.860458 -114.465718) (xy 60.723189 -114.405043)
			(xy 60.589375 -114.337087) (xy 60.459401 -114.262047) (xy 60.333642 -114.180138) (xy 60.212462 -114.091597)
			(xy 60.096208 -113.996679) (xy 59.985217 -113.895657) (xy 59.879809 -113.788824) (xy 59.780287 -113.676487)
			(xy 59.686938 -113.55897) (xy 59.600032 -113.436611) (xy 59.519819 -113.309764) (xy 59.44653 -113.178795)
			(xy 59.380377 -113.04408) (xy 59.32155 -112.906009) (xy 59.270219 -112.764979) (xy 59.226533 -112.621397)
			(xy 59.190616 -112.475677) (xy 59.162573 -112.328239) (xy 59.142484 -112.179509) (xy 59.130407 -112.029915)
			(xy 59.126378 -111.879888) (xy 45.157898 -111.879888) (xy 45.157394 -111.954928) (xy 45.149339 -112.104793)
			(xy 45.13325 -112.254009) (xy 45.109176 -112.402147) (xy 45.077184 -112.548778) (xy 45.037368 -112.693481)
			(xy 44.989842 -112.835838) (xy 44.934744 -112.975439) (xy 44.872231 -113.111882) (xy 44.802485 -113.244772)
			(xy 44.725706 -113.373726) (xy 44.642117 -113.498374) (xy 44.551957 -113.618355) (xy 44.455487 -113.733324)
			(xy 44.352984 -113.842949) (xy 44.244746 -113.946913) (xy 44.131082 -114.044918) (xy 44.012323 -114.136681)
			(xy 43.888808 -114.221936) (xy 43.760896 -114.300439) (xy 43.628954 -114.371963) (xy 43.493364 -114.436302)
			(xy 43.354515 -114.49327) (xy 43.212809 -114.542702) (xy 43.068653 -114.584457) (xy 42.922464 -114.618415)
			(xy 42.774663 -114.644476) (xy 42.625677 -114.662566) (xy 42.475934 -114.672633) (xy 42.325866 -114.674648)
			(xy 42.175907 -114.668605) (xy 42.026489 -114.654521) (xy 41.878041 -114.632437) (xy 41.730993 -114.602417)
			(xy 41.585769 -114.564548) (xy 41.442786 -114.518937) (xy 41.302458 -114.465718) (xy 41.165189 -114.405043)
			(xy 41.031375 -114.337087) (xy 40.901401 -114.262047) (xy 40.775642 -114.180138) (xy 40.654462 -114.091597)
			(xy 40.538208 -113.996679) (xy 40.427217 -113.895657) (xy 40.321809 -113.788824) (xy 40.222287 -113.676487)
			(xy 40.128938 -113.55897) (xy 40.042032 -113.436611) (xy 39.961819 -113.309764) (xy 39.88853 -113.178795)
			(xy 39.822377 -113.04408) (xy 39.76355 -112.906009) (xy 39.712219 -112.764979) (xy 39.668533 -112.621397)
			(xy 39.632616 -112.475677) (xy 39.604573 -112.328239) (xy 39.584484 -112.179509) (xy 39.572407 -112.029915)
			(xy 39.568378 -111.879888) (xy 34.042096 -111.879888) (xy 34.042096 -120.269508) (xy 41.347136 -120.269508)
			(xy 41.347136 -118.491) (xy 41.347635 -118.474302) (xy 41.35627 -118.442043) (xy 41.372951 -118.413113)
			(xy 41.396546 -118.38948) (xy 41.425448 -118.37275) (xy 41.457693 -118.364063) (xy 41.47439 -118.363492)
			(xy 43.25239 -118.363492) (xy 43.269054 -118.363997) (xy 43.301249 -118.372612) (xy 43.330122 -118.389258)
			(xy 43.353708 -118.412804) (xy 43.370404 -118.441649) (xy 43.379075 -118.473829) (xy 43.379644 -118.490492)
			(xy 43.379644 -120.269) (xy 43.379626 -120.269508) (xy 60.905136 -120.269508) (xy 60.905136 -118.491)
			(xy 60.905635 -118.474302) (xy 60.91427 -118.442043) (xy 60.930951 -118.413113) (xy 60.954546 -118.38948)
			(xy 60.983448 -118.37275) (xy 61.015693 -118.364063) (xy 61.03239 -118.363492) (xy 62.81039 -118.363492)
			(xy 62.827054 -118.363997) (xy 62.859249 -118.372612) (xy 62.888122 -118.389258) (xy 62.911708 -118.412804)
			(xy 62.928404 -118.441649) (xy 62.937075 -118.473829) (xy 62.937644 -118.490492) (xy 62.937644 -120.269)
			(xy 62.937066 -120.285691) (xy 62.928438 -120.317939) (xy 62.911769 -120.346861) (xy 62.888192 -120.370492)
			(xy 62.859308 -120.387227) (xy 62.82708 -120.395928) (xy 62.81039 -120.396508) (xy 61.03239 -120.396508)
			(xy 61.015725 -120.396021) (xy 60.983529 -120.387401) (xy 60.954657 -120.37075) (xy 60.931071 -120.347201)
			(xy 60.914375 -120.318354) (xy 60.905705 -120.286172) (xy 60.905136 -120.269508) (xy 43.379626 -120.269508)
			(xy 43.379066 -120.285691) (xy 43.370438 -120.317939) (xy 43.353769 -120.346861) (xy 43.330192 -120.370492)
			(xy 43.301308 -120.387227) (xy 43.26908 -120.395928) (xy 43.25239 -120.396508) (xy 41.47439 -120.396508)
			(xy 41.457725 -120.396021) (xy 41.425529 -120.387401) (xy 41.396657 -120.37075) (xy 41.373071 -120.347201)
			(xy 41.356375 -120.318354) (xy 41.347705 -120.286172) (xy 41.347136 -120.269508) (xy 34.042096 -120.269508)
			(xy 34.042096 -132.199888) (xy 39.568378 -132.199888) (xy 39.572407 -132.049861) (xy 39.584484 -131.900267)
			(xy 39.604573 -131.751537) (xy 39.632616 -131.604099) (xy 39.668533 -131.458379) (xy 39.712219 -131.314797)
			(xy 39.76355 -131.173767) (xy 39.822377 -131.035696) (xy 39.88853 -130.900981) (xy 39.961819 -130.770012)
			(xy 40.042032 -130.643165) (xy 40.128938 -130.520806) (xy 40.222287 -130.403289) (xy 40.321809 -130.290952)
			(xy 40.427217 -130.184119) (xy 40.538208 -130.083097) (xy 40.654462 -129.988179) (xy 40.775642 -129.899638)
			(xy 40.901401 -129.817729) (xy 41.031375 -129.742689) (xy 41.165189 -129.674733) (xy 41.302458 -129.614058)
			(xy 41.442786 -129.560839) (xy 41.585769 -129.515228) (xy 41.730993 -129.477359) (xy 41.878041 -129.447339)
			(xy 42.026489 -129.425255) (xy 42.175907 -129.411171) (xy 42.325866 -129.405128) (xy 42.475934 -129.407143)
			(xy 42.625677 -129.41721) (xy 42.774663 -129.4353) (xy 42.922464 -129.461361) (xy 43.068653 -129.495319)
			(xy 43.212809 -129.537074) (xy 43.354515 -129.586506) (xy 43.493364 -129.643474) (xy 43.628954 -129.707813)
			(xy 43.760896 -129.779337) (xy 43.888808 -129.85784) (xy 44.012323 -129.943095) (xy 44.131082 -130.034858)
			(xy 44.244746 -130.132863) (xy 44.352984 -130.236827) (xy 44.455487 -130.346452) (xy 44.551957 -130.461421)
			(xy 44.642117 -130.581402) (xy 44.725706 -130.70605) (xy 44.802485 -130.835004) (xy 44.872231 -130.967894)
			(xy 44.934744 -131.104337) (xy 44.989842 -131.243938) (xy 45.037368 -131.386295) (xy 45.077184 -131.530998)
			(xy 45.109176 -131.677629) (xy 45.13325 -131.825767) (xy 45.149339 -131.974983) (xy 45.157394 -132.124848)
			(xy 45.157898 -132.199888) (xy 59.126378 -132.199888) (xy 59.130407 -132.049861) (xy 59.142484 -131.900267)
			(xy 59.162573 -131.751537) (xy 59.190616 -131.604099) (xy 59.226533 -131.458379) (xy 59.270219 -131.314797)
			(xy 59.32155 -131.173767) (xy 59.380377 -131.035696) (xy 59.44653 -130.900981) (xy 59.519819 -130.770012)
			(xy 59.600032 -130.643165) (xy 59.686938 -130.520806) (xy 59.780287 -130.403289) (xy 59.879809 -130.290952)
			(xy 59.985217 -130.184119) (xy 60.096208 -130.083097) (xy 60.212462 -129.988179) (xy 60.333642 -129.899638)
			(xy 60.459401 -129.817729) (xy 60.589375 -129.742689) (xy 60.723189 -129.674733) (xy 60.860458 -129.614058)
			(xy 61.000786 -129.560839) (xy 61.143769 -129.515228) (xy 61.288993 -129.477359) (xy 61.436041 -129.447339)
			(xy 61.584489 -129.425255) (xy 61.733907 -129.411171) (xy 61.883866 -129.405128) (xy 62.033934 -129.407143)
			(xy 62.183677 -129.41721) (xy 62.332663 -129.4353) (xy 62.480464 -129.461361) (xy 62.626653 -129.495319)
			(xy 62.770809 -129.537074) (xy 62.912515 -129.586506) (xy 63.051364 -129.643474) (xy 63.186954 -129.707813)
			(xy 63.318896 -129.779337) (xy 63.446808 -129.85784) (xy 63.570323 -129.943095) (xy 63.689082 -130.034858)
			(xy 63.802746 -130.132863) (xy 63.910984 -130.236827) (xy 64.013487 -130.346452) (xy 64.109957 -130.461421)
			(xy 64.200117 -130.581402) (xy 64.283706 -130.70605) (xy 64.360485 -130.835004) (xy 64.430231 -130.967894)
			(xy 64.492744 -131.104337) (xy 64.547842 -131.243938) (xy 64.595368 -131.386295) (xy 64.635184 -131.530998)
			(xy 64.667176 -131.677629) (xy 64.69125 -131.825767) (xy 64.707339 -131.974983) (xy 64.715394 -132.124848)
			(xy 64.715898 -132.199888) (xy 64.715394 -132.274928) (xy 64.707339 -132.424793) (xy 64.69125 -132.574009)
			(xy 64.667176 -132.722147) (xy 64.635184 -132.868778) (xy 64.595368 -133.013481) (xy 64.547842 -133.155838)
			(xy 64.492744 -133.295439) (xy 64.430231 -133.431882) (xy 64.360485 -133.564772) (xy 64.283706 -133.693726)
			(xy 64.200117 -133.818374) (xy 64.109957 -133.938355) (xy 64.013487 -134.053324) (xy 63.910984 -134.162949)
			(xy 63.802746 -134.266913) (xy 63.689082 -134.364918) (xy 63.570323 -134.456681) (xy 63.446808 -134.541936)
			(xy 63.318896 -134.620439) (xy 63.186954 -134.691963) (xy 63.051364 -134.756302) (xy 62.912515 -134.81327)
			(xy 62.770809 -134.862702) (xy 62.626653 -134.904457) (xy 62.480464 -134.938415) (xy 62.332663 -134.964476)
			(xy 62.183677 -134.982566) (xy 62.033934 -134.992633) (xy 61.883866 -134.994648) (xy 61.733907 -134.988605)
			(xy 61.584489 -134.974521) (xy 61.436041 -134.952437) (xy 61.288993 -134.922417) (xy 61.143769 -134.884548)
			(xy 61.000786 -134.838937) (xy 60.860458 -134.785718) (xy 60.723189 -134.725043) (xy 60.589375 -134.657087)
			(xy 60.459401 -134.582047) (xy 60.333642 -134.500138) (xy 60.212462 -134.411597) (xy 60.096208 -134.316679)
			(xy 59.985217 -134.215657) (xy 59.879809 -134.108824) (xy 59.780287 -133.996487) (xy 59.686938 -133.87897)
			(xy 59.600032 -133.756611) (xy 59.519819 -133.629764) (xy 59.44653 -133.498795) (xy 59.380377 -133.36408)
			(xy 59.32155 -133.226009) (xy 59.270219 -133.084979) (xy 59.226533 -132.941397) (xy 59.190616 -132.795677)
			(xy 59.162573 -132.648239) (xy 59.142484 -132.499509) (xy 59.130407 -132.349915) (xy 59.126378 -132.199888)
			(xy 45.157898 -132.199888) (xy 45.157394 -132.274928) (xy 45.149339 -132.424793) (xy 45.13325 -132.574009)
			(xy 45.109176 -132.722147) (xy 45.077184 -132.868778) (xy 45.037368 -133.013481) (xy 44.989842 -133.155838)
			(xy 44.934744 -133.295439) (xy 44.872231 -133.431882) (xy 44.802485 -133.564772) (xy 44.725706 -133.693726)
			(xy 44.642117 -133.818374) (xy 44.551957 -133.938355) (xy 44.455487 -134.053324) (xy 44.352984 -134.162949)
			(xy 44.244746 -134.266913) (xy 44.131082 -134.364918) (xy 44.012323 -134.456681) (xy 43.888808 -134.541936)
			(xy 43.760896 -134.620439) (xy 43.628954 -134.691963) (xy 43.493364 -134.756302) (xy 43.354515 -134.81327)
			(xy 43.212809 -134.862702) (xy 43.068653 -134.904457) (xy 42.922464 -134.938415) (xy 42.774663 -134.964476)
			(xy 42.625677 -134.982566) (xy 42.475934 -134.992633) (xy 42.325866 -134.994648) (xy 42.175907 -134.988605)
			(xy 42.026489 -134.974521) (xy 41.878041 -134.952437) (xy 41.730993 -134.922417) (xy 41.585769 -134.884548)
			(xy 41.442786 -134.838937) (xy 41.302458 -134.785718) (xy 41.165189 -134.725043) (xy 41.031375 -134.657087)
			(xy 40.901401 -134.582047) (xy 40.775642 -134.500138) (xy 40.654462 -134.411597) (xy 40.538208 -134.316679)
			(xy 40.427217 -134.215657) (xy 40.321809 -134.108824) (xy 40.222287 -133.996487) (xy 40.128938 -133.87897)
			(xy 40.042032 -133.756611) (xy 39.961819 -133.629764) (xy 39.88853 -133.498795) (xy 39.822377 -133.36408)
			(xy 39.76355 -133.226009) (xy 39.712219 -133.084979) (xy 39.668533 -132.941397) (xy 39.632616 -132.795677)
			(xy 39.604573 -132.648239) (xy 39.584484 -132.499509) (xy 39.572407 -132.349915) (xy 39.568378 -132.199888)
			(xy 34.042096 -132.199888) (xy 34.042096 -140.589508) (xy 41.347136 -140.589508) (xy 41.347136 -138.811)
			(xy 41.347635 -138.794302) (xy 41.35627 -138.762043) (xy 41.372951 -138.733113) (xy 41.396546 -138.70948)
			(xy 41.425448 -138.69275) (xy 41.457693 -138.684063) (xy 41.47439 -138.683492) (xy 43.25239 -138.683492)
			(xy 43.269054 -138.683997) (xy 43.301249 -138.692612) (xy 43.330122 -138.709258) (xy 43.353708 -138.732804)
			(xy 43.370404 -138.761649) (xy 43.379075 -138.793829) (xy 43.379644 -138.810492) (xy 43.379644 -140.589)
			(xy 43.379626 -140.589508) (xy 60.905136 -140.589508) (xy 60.905136 -138.811) (xy 60.905635 -138.794302)
			(xy 60.91427 -138.762043) (xy 60.930951 -138.733113) (xy 60.954546 -138.70948) (xy 60.983448 -138.69275)
			(xy 61.015693 -138.684063) (xy 61.03239 -138.683492) (xy 62.81039 -138.683492) (xy 62.827054 -138.683997)
			(xy 62.859249 -138.692612) (xy 62.888122 -138.709258) (xy 62.911708 -138.732804) (xy 62.928404 -138.761649)
			(xy 62.937075 -138.793829) (xy 62.937644 -138.810492) (xy 62.937644 -140.589) (xy 62.937066 -140.605691)
			(xy 62.928438 -140.637939) (xy 62.911769 -140.666861) (xy 62.888192 -140.690492) (xy 62.859308 -140.707227)
			(xy 62.82708 -140.715928) (xy 62.81039 -140.716508) (xy 61.03239 -140.716508) (xy 61.015725 -140.716021)
			(xy 60.983529 -140.707401) (xy 60.954657 -140.69075) (xy 60.931071 -140.667201) (xy 60.914375 -140.638354)
			(xy 60.905705 -140.606172) (xy 60.905136 -140.589508) (xy 43.379626 -140.589508) (xy 43.379066 -140.605691)
			(xy 43.370438 -140.637939) (xy 43.353769 -140.666861) (xy 43.330192 -140.690492) (xy 43.301308 -140.707227)
			(xy 43.26908 -140.715928) (xy 43.25239 -140.716508) (xy 41.47439 -140.716508) (xy 41.457725 -140.716021)
			(xy 41.425529 -140.707401) (xy 41.396657 -140.69075) (xy 41.373071 -140.667201) (xy 41.356375 -140.638354)
			(xy 41.347705 -140.606172) (xy 41.347136 -140.589508) (xy 34.042096 -140.589508) (xy 34.042096 -149.315932)
			(xy 34.042525 -149.326) (xy 34.050247 -149.344596) (xy 34.057082 -149.352) (xy 34.057082 -168.030144)
			(xy 34.057164 -168.03482) (xy 34.058824 -168.044023) (xy 34.060384 -168.048432) (xy 34.084555 -168.109627)
			(xy 34.139601 -168.229148) (xy 34.202095 -168.344948) (xy 34.271789 -168.456564) (xy 34.348401 -168.563549)
			(xy 34.431627 -168.665474) (xy 34.521132 -168.761932) (xy 34.616559 -168.852536) (xy 34.717525 -168.936923)
			(xy 34.823625 -169.014756) (xy 34.934436 -169.085722) (xy 35.049513 -169.149538) (xy 35.168396 -169.205949)
			(xy 35.290609 -169.254728) (xy 35.415662 -169.29568) (xy 35.543054 -169.32864) (xy 35.672276 -169.353478)
			(xy 35.80281 -169.370094) (xy 35.934134 -169.378421) (xy 35.999928 -169.378884)
		)
		(stroke
			(width 0)
			(type solid)
		)
		(fill yes)
		(layer "B.Cu")
		(net "P52V_HS2")
	)
	(gr_poly
		(pts
			(xy 397.614394 -169.37863) (xy 397.64092 -169.377425) (xy 397.694012 -169.376154) (xy 397.720566 -169.37609)
			(xy 397.74712 -169.376151) (xy 397.800212 -169.377421) (xy 397.826738 -169.37863) (xy 397.827754 -169.378884)
			(xy 400.580352 -169.378884) (xy 400.589811 -169.378254) (xy 400.607285 -169.370939) (xy 400.614388 -169.36466)
			(xy 400.617944 -169.36085) (xy 400.667982 -169.301414) (xy 400.671505 -169.296957) (xy 400.676639 -169.286826)
			(xy 400.678142 -169.281348) (xy 400.680936 -169.27068) (xy 400.678904 -169.259504) (xy 400.667009 -169.188713)
			(xy 400.65042 -169.04611) (xy 400.642094 -168.902788) (xy 400.641566 -168.831006) (xy 400.641566 -168.82999)
			(xy 400.6421 -168.758031) (xy 400.650467 -168.614356) (xy 400.667138 -168.471407) (xy 400.692056 -168.329662)
			(xy 400.725138 -168.189598) (xy 400.766273 -168.051684) (xy 400.815323 -167.916382) (xy 400.843242 -167.850058)
			(xy 400.84688 -167.840349) (xy 400.846877 -167.819636) (xy 400.843242 -167.809926) (xy 400.815308 -167.743607)
			(xy 400.766243 -167.608309) (xy 400.725099 -167.470395) (xy 400.692013 -167.33033) (xy 400.667097 -167.188583)
			(xy 400.650434 -167.045631) (xy 400.64208 -166.901954) (xy 400.641566 -166.829994) (xy 400.6421 -166.758035)
			(xy 400.650467 -166.61436) (xy 400.667137 -166.471411) (xy 400.692055 -166.329666) (xy 400.725137 -166.189602)
			(xy 400.766271 -166.051687) (xy 400.815321 -165.916386) (xy 400.843242 -165.850062) (xy 400.846881 -165.840353)
			(xy 400.846879 -165.819639) (xy 400.843242 -165.80993) (xy 400.815307 -165.743611) (xy 400.766243 -165.608313)
			(xy 400.725099 -165.470399) (xy 400.692013 -165.330334) (xy 400.667096 -165.188587) (xy 400.650433 -165.045635)
			(xy 400.642078 -164.901958) (xy 400.641566 -164.829998) (xy 400.6421 -164.758039) (xy 400.650466 -164.614364)
			(xy 400.667136 -164.471415) (xy 400.692054 -164.32967) (xy 400.725136 -164.189605) (xy 400.76627 -164.051691)
			(xy 400.81532 -163.916389) (xy 400.843242 -163.850066) (xy 400.846881 -163.840357) (xy 400.846881 -163.819643)
			(xy 400.843242 -163.809934) (xy 400.815307 -163.743615) (xy 400.766243 -163.608317) (xy 400.725098 -163.470404)
			(xy 400.692012 -163.330338) (xy 400.667095 -163.188591) (xy 400.650431 -163.045639) (xy 400.642077 -162.901962)
			(xy 400.641566 -162.830002) (xy 400.6421 -162.758043) (xy 400.650466 -162.614368) (xy 400.667136 -162.471418)
			(xy 400.692053 -162.329674) (xy 400.725135 -162.189609) (xy 400.766269 -162.051694) (xy 400.815319 -161.916392)
			(xy 400.843242 -161.85007) (xy 400.846882 -161.840361) (xy 400.846884 -161.819646) (xy 400.843242 -161.809938)
			(xy 400.815307 -161.743619) (xy 400.766242 -161.608321) (xy 400.725098 -161.470408) (xy 400.692011 -161.330342)
			(xy 400.667094 -161.188596) (xy 400.65043 -161.045643) (xy 400.642075 -160.901966) (xy 400.641566 -160.830006)
			(xy 400.6421 -160.758047) (xy 400.650466 -160.614372) (xy 400.667135 -160.471422) (xy 400.692052 -160.329677)
			(xy 400.725134 -160.189613) (xy 400.766268 -160.051698) (xy 400.815317 -159.916396) (xy 400.843242 -159.850074)
			(xy 400.846883 -159.840365) (xy 400.846886 -159.819649) (xy 400.843242 -159.809942) (xy 400.815307 -159.743623)
			(xy 400.766242 -159.608325) (xy 400.725097 -159.470412) (xy 400.69201 -159.330346) (xy 400.667093 -159.1886)
			(xy 400.650429 -159.045647) (xy 400.642074 -158.90197) (xy 400.641566 -158.83001) (xy 400.6421 -158.758051)
			(xy 400.650465 -158.614376) (xy 400.667135 -158.471426) (xy 400.692052 -158.329681) (xy 400.725133 -158.189616)
			(xy 400.766267 -158.051702) (xy 400.815316 -157.916399) (xy 400.843242 -157.850078) (xy 400.846884 -157.840369)
			(xy 400.846888 -157.819653) (xy 400.843242 -157.809946) (xy 400.815307 -157.743627) (xy 400.766242 -157.608329)
			(xy 400.725097 -157.470416) (xy 400.69201 -157.33035) (xy 400.667092 -157.188604) (xy 400.650428 -157.045652)
			(xy 400.642072 -156.901974) (xy 400.641566 -156.830014) (xy 400.6421 -156.758055) (xy 400.650465 -156.61438)
			(xy 400.667134 -156.47143) (xy 400.692051 -156.329685) (xy 400.725132 -156.18962) (xy 400.766266 -156.051705)
			(xy 400.815314 -155.916403) (xy 400.843242 -155.850082) (xy 400.846885 -155.840373) (xy 400.846891 -155.819656)
			(xy 400.843242 -155.80995) (xy 400.81531 -155.743631) (xy 400.76625 -155.608332) (xy 400.72511 -155.470418)
			(xy 400.692028 -155.330353) (xy 400.667116 -155.188606) (xy 400.650457 -155.045654) (xy 400.642108 -154.901978)
			(xy 400.641566 -154.830018) (xy 400.642099 -154.758059) (xy 400.650465 -154.614384) (xy 400.667134 -154.471434)
			(xy 400.69205 -154.329689) (xy 400.725131 -154.189624) (xy 400.766264 -154.051709) (xy 400.815313 -153.916406)
			(xy 400.843242 -153.850086) (xy 400.846886 -153.840377) (xy 400.846893 -153.819659) (xy 400.843242 -153.809954)
			(xy 400.815309 -153.743635) (xy 400.766249 -153.608336) (xy 400.725109 -153.470422) (xy 400.692027 -153.330357)
			(xy 400.667115 -153.18861) (xy 400.650456 -153.045658) (xy 400.642106 -152.901982) (xy 400.641566 -152.830022)
			(xy 400.641566 -152.829514) (xy 400.642057 -152.759957) (xy 400.649855 -152.621063) (xy 400.665415 -152.482823)
			(xy 400.68869 -152.34567) (xy 400.719606 -152.210036) (xy 400.758067 -152.076345) (xy 400.803951 -151.945016)
			(xy 400.857114 -151.816462) (xy 400.917391 -151.691086) (xy 400.984591 -151.56928) (xy 401.058505 -151.451427)
			(xy 401.1389 -151.337897) (xy 401.181824 -151.283162) (xy 401.193 -151.251666) (xy 401.193 -149.373082)
			(xy 401.193427 -149.363013) (xy 401.201146 -149.344414) (xy 401.207986 -149.337014) (xy 402.194014 -148.350986)
			(xy 402.201409 -148.344132) (xy 402.220008 -148.33639) (xy 402.230082 -148.336) (xy 413.871918 -148.336)
			(xy 413.877929 -148.335836) (xy 413.889614 -148.333019) (xy 413.895032 -148.330412) (xy 413.898506 -148.328572)
			(xy 413.904884 -148.323978) (xy 413.907732 -148.321268) (xy 415.006282 -147.222718) (xy 415.008988 -147.219867)
			(xy 415.013582 -147.213489) (xy 415.015426 -147.210018) (xy 415.018004 -147.20459) (xy 415.020817 -147.19291)
			(xy 415.021014 -147.186904) (xy 415.021014 -136.815068) (xy 415.021327 -136.807491) (xy 415.025841 -136.793023)
			(xy 415.029904 -136.78662) (xy 415.032444 -136.782048) (xy 415.034222 -136.775952) (xy 415.036 -136.762744)
			(xy 415.036 -54.123082) (xy 415.035836 -54.117071) (xy 415.033019 -54.105386) (xy 415.030412 -54.099968)
			(xy 415.028572 -54.096494) (xy 415.023978 -54.090116) (xy 415.021268 -54.087268) (xy 393.446 -32.512)
			(xy 393.440412 -32.507174) (xy 393.433673 -32.5025) (xy 393.418127 -32.497306) (xy 393.409932 -32.497014)
			(xy 392.470894 -32.497014) (xy 392.462701 -32.497325) (xy 392.447157 -32.502509) (xy 392.440414 -32.507174)
			(xy 392.434826 -32.512) (xy 392.151108 -32.795718) (xy 392.143714 -32.802574) (xy 392.125115 -32.810325)
			(xy 392.11504 -32.810704) (xy 367.497106 -32.810704) (xy 367.487035 -32.810282) (xy 367.468429 -32.80257)
			(xy 367.461038 -32.795718) (xy 354.35032 -19.685) (xy 328.68235 -19.685) (xy 328.5744 -19.79295)
			(xy 328.5744 -23.241) (xy 328.58964 -23.25624) (xy 328.582714 -23.263603) (xy 328.574855 -23.282209)
			(xy 328.5744 -23.292308) (xy 328.5744 -24.383492) (xy 328.574818 -24.393514) (xy 328.582487 -24.412034)
			(xy 328.596659 -24.426209) (xy 328.615178 -24.43388) (xy 328.6252 -24.434292) (xy 338.63661 -24.434292)
			(xy 338.64668 -24.434716) (xy 338.665282 -24.442433) (xy 338.672678 -24.449278) (xy 339.481414 -25.258014)
			(xy 339.488268 -25.265409) (xy 339.49601 -25.284008) (xy 339.4964 -25.294082) (xy 339.4964 -29.950918)
			(xy 339.495973 -29.960987) (xy 339.488254 -29.979586) (xy 339.481414 -29.986986) (xy 338.647278 -30.821122)
			(xy 338.639882 -30.827973) (xy 338.621283 -30.835712) (xy 338.61121 -30.836108) (xy 328.690986 -30.836108)
			(xy 328.5744 -30.952694) (xy 328.5744 -34.5186) (xy 328.58964 -34.53384) (xy 328.582714 -34.541203)
			(xy 328.574855 -34.559809) (xy 328.5744 -34.569908) (xy 328.5744 -35.661092) (xy 328.574818 -35.671114)
			(xy 328.582487 -35.689634) (xy 328.596659 -35.703809) (xy 328.615178 -35.71148) (xy 328.6252 -35.711892)
			(xy 343.396824 -35.711892) (xy 343.880186 -36.195254) (xy 343.880186 -38.3286) (xy 344.9066 -38.3286)
			(xy 345.48826 -38.91026) (xy 345.541518 -38.950707) (xy 345.643488 -39.037257) (xy 345.739905 -39.129951)
			(xy 345.830401 -39.228435) (xy 345.914629 -39.332331) (xy 345.992264 -39.441241) (xy 346.063011 -39.554747)
			(xy 346.126597 -39.672413) (xy 346.182778 -39.79379) (xy 346.23134 -39.918411) (xy 346.272096 -40.045798)
			(xy 346.304891 -40.175464) (xy 346.329597 -40.30691) (xy 346.34612 -40.439634) (xy 346.354398 -40.573126)
			(xy 346.354908 -40.64) (xy 346.3544 -40.706699) (xy 346.346166 -40.839843) (xy 346.329729 -40.972225)
			(xy 346.305151 -41.103339) (xy 346.272527 -41.232686) (xy 346.23198 -41.359773) (xy 346.183666 -41.484115)
			(xy 346.127769 -41.605237) (xy 346.064502 -41.722678) (xy 345.994105 -41.835989) (xy 345.916849 -41.944739)
			(xy 345.833027 -42.048513) (xy 345.74296 -42.146914) (xy 345.646989 -42.239569) (xy 345.545483 -42.326122)
			(xy 345.438827 -42.406245) (xy 345.327429 -42.479631) (xy 345.26982 -42.51325) (xy 345.212671 -42.549211)
			(xy 345.094568 -42.614691) (xy 344.972561 -42.67257) (xy 344.847138 -42.722619) (xy 344.718801 -42.764636)
			(xy 344.588064 -42.798453) (xy 344.45545 -42.823935) (xy 344.32149 -42.84098) (xy 344.18672 -42.849519)
			(xy 344.1192 -42.850054) (xy 343.287858 -42.850054) (xy 343.222139 -42.883612) (xy 343.087403 -42.943826)
			(xy 342.949338 -42.995957) (xy 342.808429 -43.039823) (xy 342.736932 -43.05808) (xy 342.695511 -43.09717)
			(xy 342.607621 -43.169622) (xy 342.514445 -43.235136) (xy 342.416528 -43.293327) (xy 342.314445 -43.343854)
			(xy 342.208795 -43.386421) (xy 342.100198 -43.420778) (xy 341.989289 -43.446724) (xy 341.87672 -43.464106)
			(xy 341.763151 -43.472823) (xy 341.7062 -43.47337) (xy 341.652074 -43.472882) (xy 341.544108 -43.46501)
			(xy 341.437 -43.449309) (xy 341.331317 -43.425861) (xy 341.227619 -43.394791) (xy 341.126455 -43.356262)
			(xy 341.02836 -43.31048) (xy 340.933854 -43.257686) (xy 340.843437 -43.19816) (xy 340.757587 -43.132216)
			(xy 340.67676 -43.060205) (xy 340.601383 -42.982508) (xy 340.531855 -42.899535) (xy 340.468544 -42.811726)
			(xy 340.411786 -42.719546) (xy 340.361881 -42.623482) (xy 340.319093 -42.524045) (xy 340.283649 -42.421759)
			(xy 340.255737 -42.317167) (xy 340.245192 -42.264076) (xy 340.200742 -42.206418) (xy 340.179531 -42.179986)
			(xy 340.138377 -42.126131) (xy 340.118446 -42.098722) (xy 338.545678 -42.098722) (xy 338.538282 -42.105573)
			(xy 338.519683 -42.113312) (xy 338.50961 -42.113708) (xy 328.690986 -42.113708) (xy 328.5744 -42.230294)
			(xy 328.5744 -45.7962) (xy 328.58964 -45.81144) (xy 328.582714 -45.818803) (xy 328.574855 -45.837409)
			(xy 328.5744 -45.847508) (xy 328.5744 -46.938692) (xy 328.574818 -46.948714) (xy 328.582487 -46.967234)
			(xy 328.596659 -46.981409) (xy 328.615178 -46.98908) (xy 328.6252 -46.989492) (xy 343.415366 -46.989492)
			(xy 343.880948 -47.455074) (xy 343.880948 -49.633632) (xy 343.88298 -49.6316) (xy 344.5764 -49.6316)
			(xy 344.795348 -49.850548) (xy 344.858059 -49.870036) (xy 344.981225 -49.915633) (xy 345.101393 -49.968631)
			(xy 345.218117 -50.028835) (xy 345.330966 -50.096021) (xy 345.439523 -50.169942) (xy 345.543387 -50.250323)
			(xy 345.642174 -50.336869) (xy 345.735518 -50.429259) (xy 345.823075 -50.527151) (xy 345.90452 -50.630183)
			(xy 345.979552 -50.737975) (xy 346.047895 -50.850128) (xy 346.084788 -50.919888) (xy 375.283988 -50.919888)
			(xy 375.288017 -50.769861) (xy 375.300094 -50.620267) (xy 375.320183 -50.471537) (xy 375.348226 -50.324099)
			(xy 375.384143 -50.178379) (xy 375.427829 -50.034797) (xy 375.47916 -49.893767) (xy 375.537987 -49.755696)
			(xy 375.60414 -49.620981) (xy 375.677429 -49.490012) (xy 375.757642 -49.363165) (xy 375.844548 -49.240806)
			(xy 375.937897 -49.123289) (xy 376.037419 -49.010952) (xy 376.142827 -48.904119) (xy 376.253818 -48.803097)
			(xy 376.370072 -48.708179) (xy 376.491252 -48.619638) (xy 376.617011 -48.537729) (xy 376.746985 -48.462689)
			(xy 376.880799 -48.394733) (xy 377.018068 -48.334058) (xy 377.158396 -48.280839) (xy 377.301379 -48.235228)
			(xy 377.446603 -48.197359) (xy 377.593651 -48.167339) (xy 377.742099 -48.145255) (xy 377.891517 -48.131171)
			(xy 378.041476 -48.125128) (xy 378.191544 -48.127143) (xy 378.341287 -48.13721) (xy 378.490273 -48.1553)
			(xy 378.638074 -48.181361) (xy 378.784263 -48.215319) (xy 378.928419 -48.257074) (xy 379.070125 -48.306506)
			(xy 379.208974 -48.363474) (xy 379.344564 -48.427813) (xy 379.476506 -48.499337) (xy 379.604418 -48.57784)
			(xy 379.727933 -48.663095) (xy 379.846692 -48.754858) (xy 379.960356 -48.852863) (xy 380.068594 -48.956827)
			(xy 380.171097 -49.066452) (xy 380.267567 -49.181421) (xy 380.357727 -49.301402) (xy 380.441316 -49.42605)
			(xy 380.518095 -49.555004) (xy 380.587841 -49.687894) (xy 380.650354 -49.824337) (xy 380.705452 -49.963938)
			(xy 380.752978 -50.106295) (xy 380.792794 -50.250998) (xy 380.824786 -50.397629) (xy 380.84886 -50.545767)
			(xy 380.864949 -50.694983) (xy 380.873004 -50.844848) (xy 380.873508 -50.919888) (xy 394.841988 -50.919888)
			(xy 394.846017 -50.769861) (xy 394.858094 -50.620267) (xy 394.878183 -50.471537) (xy 394.906226 -50.324099)
			(xy 394.942143 -50.178379) (xy 394.985829 -50.034797) (xy 395.03716 -49.893767) (xy 395.095987 -49.755696)
			(xy 395.16214 -49.620981) (xy 395.235429 -49.490012) (xy 395.315642 -49.363165) (xy 395.402548 -49.240806)
			(xy 395.495897 -49.123289) (xy 395.595419 -49.010952) (xy 395.700827 -48.904119) (xy 395.811818 -48.803097)
			(xy 395.928072 -48.708179) (xy 396.049252 -48.619638) (xy 396.175011 -48.537729) (xy 396.304985 -48.462689)
			(xy 396.438799 -48.394733) (xy 396.576068 -48.334058) (xy 396.716396 -48.280839) (xy 396.859379 -48.235228)
			(xy 397.004603 -48.197359) (xy 397.151651 -48.167339) (xy 397.300099 -48.145255) (xy 397.449517 -48.131171)
			(xy 397.599476 -48.125128) (xy 397.749544 -48.127143) (xy 397.899287 -48.13721) (xy 398.048273 -48.1553)
			(xy 398.196074 -48.181361) (xy 398.342263 -48.215319) (xy 398.486419 -48.257074) (xy 398.628125 -48.306506)
			(xy 398.766974 -48.363474) (xy 398.902564 -48.427813) (xy 399.034506 -48.499337) (xy 399.162418 -48.57784)
			(xy 399.285933 -48.663095) (xy 399.404692 -48.754858) (xy 399.518356 -48.852863) (xy 399.626594 -48.956827)
			(xy 399.729097 -49.066452) (xy 399.825567 -49.181421) (xy 399.915727 -49.301402) (xy 399.999316 -49.42605)
			(xy 400.076095 -49.555004) (xy 400.145841 -49.687894) (xy 400.208354 -49.824337) (xy 400.263452 -49.963938)
			(xy 400.310978 -50.106295) (xy 400.350794 -50.250998) (xy 400.382786 -50.397629) (xy 400.40686 -50.545767)
			(xy 400.422949 -50.694983) (xy 400.431004 -50.844848) (xy 400.431508 -50.919888) (xy 400.431004 -50.994928)
			(xy 400.422949 -51.144793) (xy 400.40686 -51.294009) (xy 400.382786 -51.442147) (xy 400.350794 -51.588778)
			(xy 400.310978 -51.733481) (xy 400.263452 -51.875838) (xy 400.208354 -52.015439) (xy 400.145841 -52.151882)
			(xy 400.076095 -52.284772) (xy 399.999316 -52.413726) (xy 399.915727 -52.538374) (xy 399.825567 -52.658355)
			(xy 399.729097 -52.773324) (xy 399.626594 -52.882949) (xy 399.518356 -52.986913) (xy 399.404692 -53.084918)
			(xy 399.285933 -53.176681) (xy 399.162418 -53.261936) (xy 399.034506 -53.340439) (xy 398.902564 -53.411963)
			(xy 398.766974 -53.476302) (xy 398.628125 -53.53327) (xy 398.486419 -53.582702) (xy 398.342263 -53.624457)
			(xy 398.196074 -53.658415) (xy 398.048273 -53.684476) (xy 397.899287 -53.702566) (xy 397.749544 -53.712633)
			(xy 397.599476 -53.714648) (xy 397.449517 -53.708605) (xy 397.300099 -53.694521) (xy 397.151651 -53.672437)
			(xy 397.004603 -53.642417) (xy 396.859379 -53.604548) (xy 396.716396 -53.558937) (xy 396.576068 -53.505718)
			(xy 396.438799 -53.445043) (xy 396.304985 -53.377087) (xy 396.175011 -53.302047) (xy 396.049252 -53.220138)
			(xy 395.928072 -53.131597) (xy 395.811818 -53.036679) (xy 395.700827 -52.935657) (xy 395.595419 -52.828824)
			(xy 395.495897 -52.716487) (xy 395.402548 -52.59897) (xy 395.315642 -52.476611) (xy 395.235429 -52.349764)
			(xy 395.16214 -52.218795) (xy 395.095987 -52.08408) (xy 395.03716 -51.946009) (xy 394.985829 -51.804979)
			(xy 394.942143 -51.661397) (xy 394.906226 -51.515677) (xy 394.878183 -51.368239) (xy 394.858094 -51.219509)
			(xy 394.846017 -51.069915) (xy 394.841988 -50.919888) (xy 380.873508 -50.919888) (xy 380.873004 -50.994928)
			(xy 380.864949 -51.144793) (xy 380.84886 -51.294009) (xy 380.824786 -51.442147) (xy 380.792794 -51.588778)
			(xy 380.752978 -51.733481) (xy 380.705452 -51.875838) (xy 380.650354 -52.015439) (xy 380.587841 -52.151882)
			(xy 380.518095 -52.284772) (xy 380.441316 -52.413726) (xy 380.357727 -52.538374) (xy 380.267567 -52.658355)
			(xy 380.171097 -52.773324) (xy 380.068594 -52.882949) (xy 379.960356 -52.986913) (xy 379.846692 -53.084918)
			(xy 379.727933 -53.176681) (xy 379.604418 -53.261936) (xy 379.476506 -53.340439) (xy 379.344564 -53.411963)
			(xy 379.208974 -53.476302) (xy 379.070125 -53.53327) (xy 378.928419 -53.582702) (xy 378.784263 -53.624457)
			(xy 378.638074 -53.658415) (xy 378.490273 -53.684476) (xy 378.341287 -53.702566) (xy 378.191544 -53.712633)
			(xy 378.041476 -53.714648) (xy 377.891517 -53.708605) (xy 377.742099 -53.694521) (xy 377.593651 -53.672437)
			(xy 377.446603 -53.642417) (xy 377.301379 -53.604548) (xy 377.158396 -53.558937) (xy 377.018068 -53.505718)
			(xy 376.880799 -53.445043) (xy 376.746985 -53.377087) (xy 376.617011 -53.302047) (xy 376.491252 -53.220138)
			(xy 376.370072 -53.131597) (xy 376.253818 -53.036679) (xy 376.142827 -52.935657) (xy 376.037419 -52.828824)
			(xy 375.937897 -52.716487) (xy 375.844548 -52.59897) (xy 375.757642 -52.476611) (xy 375.677429 -52.349764)
			(xy 375.60414 -52.218795) (xy 375.537987 -52.08408) (xy 375.47916 -51.946009) (xy 375.427829 -51.804979)
			(xy 375.384143 -51.661397) (xy 375.348226 -51.515677) (xy 375.320183 -51.368239) (xy 375.300094 -51.219509)
			(xy 375.288017 -51.069915) (xy 375.283988 -50.919888) (xy 346.084788 -50.919888) (xy 346.109295 -50.966227)
			(xy 346.163525 -51.085843) (xy 346.210385 -51.208534) (xy 346.249702 -51.333847) (xy 346.28133 -51.461317)
			(xy 346.305153 -51.590474) (xy 346.321081 -51.720839) (xy 346.329057 -51.851932) (xy 346.329508 -51.9176)
			(xy 346.329016 -51.982839) (xy 346.321138 -52.113078) (xy 346.30541 -52.242603) (xy 346.281891 -52.370943)
			(xy 346.250666 -52.497629) (xy 346.211849 -52.622198) (xy 346.165581 -52.744197) (xy 346.112031 -52.863179)
			(xy 346.051395 -52.97871) (xy 345.983895 -53.09037) (xy 345.909775 -53.197751) (xy 345.829308 -53.30046)
			(xy 345.742785 -53.398124) (xy 345.650524 -53.490385) (xy 345.55286 -53.576908) (xy 345.450151 -53.657375)
			(xy 345.34277 -53.731495) (xy 345.23111 -53.798995) (xy 345.115579 -53.859631) (xy 344.996597 -53.913181)
			(xy 344.874598 -53.959449) (xy 344.750029 -53.998266) (xy 344.623343 -54.029491) (xy 344.495003 -54.05301)
			(xy 344.365478 -54.068738) (xy 344.235239 -54.076616) (xy 344.17 -54.077108) (xy 344.106348 -54.076645)
			(xy 343.979265 -54.069149) (xy 343.916 -54.062122) (xy 343.852735 -54.069148) (xy 343.725652 -54.076646)
			(xy 343.662 -54.077108) (xy 343.605571 -54.076769) (xy 343.492864 -54.070925) (xy 343.436702 -54.065424)
			(xy 343.378079 -54.10033) (xy 343.257643 -54.164478) (xy 343.133898 -54.221986) (xy 343.007211 -54.272684)
			(xy 342.877957 -54.316421) (xy 342.746516 -54.35307) (xy 342.613277 -54.38252) (xy 342.478635 -54.404686)
			(xy 342.342988 -54.419502) (xy 342.206735 -54.426924) (xy 342.138508 -54.427374) (xy 342.138 -54.427374)
			(xy 342.067825 -54.426887) (xy 341.927695 -54.419043) (xy 341.788221 -54.403381) (xy 341.649841 -54.379948)
			(xy 341.512987 -54.348818) (xy 341.378087 -54.310088) (xy 341.245562 -54.263881) (xy 341.115826 -54.210338)
			(xy 340.989286 -54.14963) (xy 340.866335 -54.081944) (xy 340.74736 -54.007492) (xy 340.632732 -53.926508)
			(xy 340.522808 -53.839245) (xy 340.417934 -53.745974) (xy 340.318435 -53.646989) (xy 340.224624 -53.542597)
			(xy 340.136794 -53.433126) (xy 340.095586 -53.376322) (xy 338.952078 -53.376322) (xy 338.944682 -53.383173)
			(xy 338.926083 -53.390912) (xy 338.91601 -53.391308) (xy 328.690986 -53.391308) (xy 328.5744 -53.507894)
			(xy 328.5744 -57.0738) (xy 328.58964 -57.08904) (xy 328.582714 -57.096403) (xy 328.574855 -57.115009)
			(xy 328.5744 -57.125108) (xy 328.5744 -58.216292) (xy 328.574818 -58.226314) (xy 328.582487 -58.244834)
			(xy 328.596659 -58.259009) (xy 328.615178 -58.26668) (xy 328.6252 -58.267092) (xy 338.68741 -58.267092)
			(xy 338.69748 -58.267516) (xy 338.716082 -58.275233) (xy 338.723478 -58.282078) (xy 339.608414 -59.167014)
			(xy 339.615268 -59.174409) (xy 339.62301 -59.193008) (xy 339.6234 -59.203082) (xy 339.6234 -59.309)
			(xy 377.062492 -59.309) (xy 377.062492 -57.531) (xy 377.063038 -57.514285) (xy 377.07169 -57.481994)
			(xy 377.088405 -57.453043) (xy 377.112043 -57.429405) (xy 377.140994 -57.41269) (xy 377.173285 -57.404038)
			(xy 377.19 -57.403492) (xy 378.968 -57.403492) (xy 378.984715 -57.404038) (xy 379.017006 -57.41269)
			(xy 379.045957 -57.429405) (xy 379.069595 -57.453043) (xy 379.08631 -57.481994) (xy 379.094962 -57.514285)
			(xy 379.095508 -57.531) (xy 379.095508 -59.309) (xy 396.620492 -59.309) (xy 396.620492 -57.531) (xy 396.621038 -57.514285)
			(xy 396.62969 -57.481994) (xy 396.646405 -57.453043) (xy 396.670043 -57.429405) (xy 396.698994 -57.41269)
			(xy 396.731285 -57.404038) (xy 396.748 -57.403492) (xy 398.526 -57.403492) (xy 398.542715 -57.404038)
			(xy 398.575006 -57.41269) (xy 398.603957 -57.429405) (xy 398.627595 -57.453043) (xy 398.64431 -57.481994)
			(xy 398.652962 -57.514285) (xy 398.653508 -57.531) (xy 398.653508 -59.309) (xy 398.652962 -59.325715)
			(xy 398.64431 -59.358006) (xy 398.627595 -59.386957) (xy 398.603957 -59.410595) (xy 398.575006 -59.42731)
			(xy 398.542715 -59.435962) (xy 398.526 -59.436508) (xy 396.748 -59.436508) (xy 396.731285 -59.435962)
			(xy 396.698994 -59.42731) (xy 396.670043 -59.410595) (xy 396.646405 -59.386957) (xy 396.62969 -59.358006)
			(xy 396.621038 -59.325715) (xy 396.620492 -59.309) (xy 379.095508 -59.309) (xy 379.094962 -59.325715)
			(xy 379.08631 -59.358006) (xy 379.069595 -59.386957) (xy 379.045957 -59.410595) (xy 379.017006 -59.42731)
			(xy 378.984715 -59.435962) (xy 378.968 -59.436508) (xy 377.19 -59.436508) (xy 377.173285 -59.435962)
			(xy 377.140994 -59.42731) (xy 377.112043 -59.410595) (xy 377.088405 -59.386957) (xy 377.07169 -59.358006)
			(xy 377.063038 -59.325715) (xy 377.062492 -59.309) (xy 339.6234 -59.309) (xy 339.6234 -63.986918)
			(xy 339.622973 -63.996987) (xy 339.615254 -64.015586) (xy 339.608414 -64.022986) (xy 338.977478 -64.653922)
			(xy 338.970082 -64.660773) (xy 338.951483 -64.668512) (xy 338.94141 -64.668908) (xy 328.690986 -64.668908)
			(xy 328.5744 -64.785494) (xy 328.5744 -68.3514) (xy 328.58964 -68.36664) (xy 328.582714 -68.374003)
			(xy 328.574855 -68.392609) (xy 328.5744 -68.402708) (xy 328.5744 -69.493892) (xy 328.574818 -69.503914)
			(xy 328.582487 -69.522434) (xy 328.596659 -69.536609) (xy 328.615178 -69.54428) (xy 328.6252 -69.544692)
			(xy 338.91601 -69.544692) (xy 338.92608 -69.545116) (xy 338.944682 -69.552833) (xy 338.952078 -69.559678)
			(xy 339.608414 -70.216014) (xy 339.615268 -70.223409) (xy 339.62301 -70.242008) (xy 339.6234 -70.252082)
			(xy 339.6234 -71.239888) (xy 375.283988 -71.239888) (xy 375.288017 -71.089861) (xy 375.300094 -70.940267)
			(xy 375.320183 -70.791537) (xy 375.348226 -70.644099) (xy 375.384143 -70.498379) (xy 375.427829 -70.354797)
			(xy 375.47916 -70.213767) (xy 375.537987 -70.075696) (xy 375.60414 -69.940981) (xy 375.677429 -69.810012)
			(xy 375.757642 -69.683165) (xy 375.844548 -69.560806) (xy 375.937897 -69.443289) (xy 376.037419 -69.330952)
			(xy 376.142827 -69.224119) (xy 376.253818 -69.123097) (xy 376.370072 -69.028179) (xy 376.491252 -68.939638)
			(xy 376.617011 -68.857729) (xy 376.746985 -68.782689) (xy 376.880799 -68.714733) (xy 377.018068 -68.654058)
			(xy 377.158396 -68.600839) (xy 377.301379 -68.555228) (xy 377.446603 -68.517359) (xy 377.593651 -68.487339)
			(xy 377.742099 -68.465255) (xy 377.891517 -68.451171) (xy 378.041476 -68.445128) (xy 378.191544 -68.447143)
			(xy 378.341287 -68.45721) (xy 378.490273 -68.4753) (xy 378.638074 -68.501361) (xy 378.784263 -68.535319)
			(xy 378.928419 -68.577074) (xy 379.070125 -68.626506) (xy 379.208974 -68.683474) (xy 379.344564 -68.747813)
			(xy 379.476506 -68.819337) (xy 379.604418 -68.89784) (xy 379.727933 -68.983095) (xy 379.846692 -69.074858)
			(xy 379.960356 -69.172863) (xy 380.068594 -69.276827) (xy 380.171097 -69.386452) (xy 380.267567 -69.501421)
			(xy 380.357727 -69.621402) (xy 380.441316 -69.74605) (xy 380.518095 -69.875004) (xy 380.587841 -70.007894)
			(xy 380.650354 -70.144337) (xy 380.705452 -70.283938) (xy 380.752978 -70.426295) (xy 380.792794 -70.570998)
			(xy 380.824786 -70.717629) (xy 380.84886 -70.865767) (xy 380.864949 -71.014983) (xy 380.873004 -71.164848)
			(xy 380.873508 -71.239888) (xy 394.841988 -71.239888) (xy 394.846017 -71.089861) (xy 394.858094 -70.940267)
			(xy 394.878183 -70.791537) (xy 394.906226 -70.644099) (xy 394.942143 -70.498379) (xy 394.985829 -70.354797)
			(xy 395.03716 -70.213767) (xy 395.095987 -70.075696) (xy 395.16214 -69.940981) (xy 395.235429 -69.810012)
			(xy 395.315642 -69.683165) (xy 395.402548 -69.560806) (xy 395.495897 -69.443289) (xy 395.595419 -69.330952)
			(xy 395.700827 -69.224119) (xy 395.811818 -69.123097) (xy 395.928072 -69.028179) (xy 396.049252 -68.939638)
			(xy 396.175011 -68.857729) (xy 396.304985 -68.782689) (xy 396.438799 -68.714733) (xy 396.576068 -68.654058)
			(xy 396.716396 -68.600839) (xy 396.859379 -68.555228) (xy 397.004603 -68.517359) (xy 397.151651 -68.487339)
			(xy 397.300099 -68.465255) (xy 397.449517 -68.451171) (xy 397.599476 -68.445128) (xy 397.749544 -68.447143)
			(xy 397.899287 -68.45721) (xy 398.048273 -68.4753) (xy 398.196074 -68.501361) (xy 398.342263 -68.535319)
			(xy 398.486419 -68.577074) (xy 398.628125 -68.626506) (xy 398.766974 -68.683474) (xy 398.902564 -68.747813)
			(xy 399.034506 -68.819337) (xy 399.162418 -68.89784) (xy 399.285933 -68.983095) (xy 399.404692 -69.074858)
			(xy 399.518356 -69.172863) (xy 399.626594 -69.276827) (xy 399.729097 -69.386452) (xy 399.825567 -69.501421)
			(xy 399.915727 -69.621402) (xy 399.999316 -69.74605) (xy 400.076095 -69.875004) (xy 400.145841 -70.007894)
			(xy 400.208354 -70.144337) (xy 400.263452 -70.283938) (xy 400.310978 -70.426295) (xy 400.350794 -70.570998)
			(xy 400.382786 -70.717629) (xy 400.40686 -70.865767) (xy 400.422949 -71.014983) (xy 400.431004 -71.164848)
			(xy 400.431508 -71.239888) (xy 400.431004 -71.314928) (xy 400.422949 -71.464793) (xy 400.40686 -71.614009)
			(xy 400.382786 -71.762147) (xy 400.350794 -71.908778) (xy 400.310978 -72.053481) (xy 400.263452 -72.195838)
			(xy 400.208354 -72.335439) (xy 400.145841 -72.471882) (xy 400.076095 -72.604772) (xy 399.999316 -72.733726)
			(xy 399.915727 -72.858374) (xy 399.825567 -72.978355) (xy 399.729097 -73.093324) (xy 399.626594 -73.202949)
			(xy 399.518356 -73.306913) (xy 399.404692 -73.404918) (xy 399.285933 -73.496681) (xy 399.162418 -73.581936)
			(xy 399.034506 -73.660439) (xy 398.902564 -73.731963) (xy 398.766974 -73.796302) (xy 398.628125 -73.85327)
			(xy 398.486419 -73.902702) (xy 398.342263 -73.944457) (xy 398.196074 -73.978415) (xy 398.048273 -74.004476)
			(xy 397.899287 -74.022566) (xy 397.749544 -74.032633) (xy 397.599476 -74.034648) (xy 397.449517 -74.028605)
			(xy 397.300099 -74.014521) (xy 397.151651 -73.992437) (xy 397.004603 -73.962417) (xy 396.859379 -73.924548)
			(xy 396.716396 -73.878937) (xy 396.576068 -73.825718) (xy 396.438799 -73.765043) (xy 396.304985 -73.697087)
			(xy 396.175011 -73.622047) (xy 396.049252 -73.540138) (xy 395.928072 -73.451597) (xy 395.811818 -73.356679)
			(xy 395.700827 -73.255657) (xy 395.595419 -73.148824) (xy 395.495897 -73.036487) (xy 395.402548 -72.91897)
			(xy 395.315642 -72.796611) (xy 395.235429 -72.669764) (xy 395.16214 -72.538795) (xy 395.095987 -72.40408)
			(xy 395.03716 -72.266009) (xy 394.985829 -72.124979) (xy 394.942143 -71.981397) (xy 394.906226 -71.835677)
			(xy 394.878183 -71.688239) (xy 394.858094 -71.539509) (xy 394.846017 -71.389915) (xy 394.841988 -71.239888)
			(xy 380.873508 -71.239888) (xy 380.873004 -71.314928) (xy 380.864949 -71.464793) (xy 380.84886 -71.614009)
			(xy 380.824786 -71.762147) (xy 380.792794 -71.908778) (xy 380.752978 -72.053481) (xy 380.705452 -72.195838)
			(xy 380.650354 -72.335439) (xy 380.587841 -72.471882) (xy 380.518095 -72.604772) (xy 380.441316 -72.733726)
			(xy 380.357727 -72.858374) (xy 380.267567 -72.978355) (xy 380.171097 -73.093324) (xy 380.068594 -73.202949)
			(xy 379.960356 -73.306913) (xy 379.846692 -73.404918) (xy 379.727933 -73.496681) (xy 379.604418 -73.581936)
			(xy 379.476506 -73.660439) (xy 379.344564 -73.731963) (xy 379.208974 -73.796302) (xy 379.070125 -73.85327)
			(xy 378.928419 -73.902702) (xy 378.784263 -73.944457) (xy 378.638074 -73.978415) (xy 378.490273 -74.004476)
			(xy 378.341287 -74.022566) (xy 378.191544 -74.032633) (xy 378.041476 -74.034648) (xy 377.891517 -74.028605)
			(xy 377.742099 -74.014521) (xy 377.593651 -73.992437) (xy 377.446603 -73.962417) (xy 377.301379 -73.924548)
			(xy 377.158396 -73.878937) (xy 377.018068 -73.825718) (xy 376.880799 -73.765043) (xy 376.746985 -73.697087)
			(xy 376.617011 -73.622047) (xy 376.491252 -73.540138) (xy 376.370072 -73.451597) (xy 376.253818 -73.356679)
			(xy 376.142827 -73.255657) (xy 376.037419 -73.148824) (xy 375.937897 -73.036487) (xy 375.844548 -72.91897)
			(xy 375.757642 -72.796611) (xy 375.677429 -72.669764) (xy 375.60414 -72.538795) (xy 375.537987 -72.40408)
			(xy 375.47916 -72.266009) (xy 375.427829 -72.124979) (xy 375.384143 -71.981397) (xy 375.348226 -71.835677)
			(xy 375.320183 -71.688239) (xy 375.300094 -71.539509) (xy 375.288017 -71.389915) (xy 375.283988 -71.239888)
			(xy 339.6234 -71.239888) (xy 339.6234 -75.289918) (xy 339.622973 -75.299987) (xy 339.615254 -75.318586)
			(xy 339.608414 -75.325986) (xy 339.003386 -75.931014) (xy 338.995991 -75.937868) (xy 338.977392 -75.94561)
			(xy 338.967318 -75.946) (xy 335.030318 -75.946) (xy 334.986884 -75.946508) (xy 328.690986 -75.946508)
			(xy 328.5744 -76.063094) (xy 328.5744 -79.629) (xy 377.062492 -79.629) (xy 377.062492 -77.851) (xy 377.063038 -77.834285)
			(xy 377.07169 -77.801994) (xy 377.088405 -77.773043) (xy 377.112043 -77.749405) (xy 377.140994 -77.73269)
			(xy 377.173285 -77.724038) (xy 377.19 -77.723492) (xy 378.968 -77.723492) (xy 378.984715 -77.724038)
			(xy 379.017006 -77.73269) (xy 379.045957 -77.749405) (xy 379.069595 -77.773043) (xy 379.08631 -77.801994)
			(xy 379.094962 -77.834285) (xy 379.095508 -77.851) (xy 379.095508 -79.629) (xy 396.620492 -79.629)
			(xy 396.620492 -77.851) (xy 396.621038 -77.834285) (xy 396.62969 -77.801994) (xy 396.646405 -77.773043)
			(xy 396.670043 -77.749405) (xy 396.698994 -77.73269) (xy 396.731285 -77.724038) (xy 396.748 -77.723492)
			(xy 398.526 -77.723492) (xy 398.542715 -77.724038) (xy 398.575006 -77.73269) (xy 398.603957 -77.749405)
			(xy 398.627595 -77.773043) (xy 398.64431 -77.801994) (xy 398.652962 -77.834285) (xy 398.653508 -77.851)
			(xy 398.653508 -79.629) (xy 398.652962 -79.645715) (xy 398.64431 -79.678006) (xy 398.627595 -79.706957)
			(xy 398.603957 -79.730595) (xy 398.575006 -79.74731) (xy 398.542715 -79.755962) (xy 398.526 -79.756508)
			(xy 396.748 -79.756508) (xy 396.731285 -79.755962) (xy 396.698994 -79.74731) (xy 396.670043 -79.730595)
			(xy 396.646405 -79.706957) (xy 396.62969 -79.678006) (xy 396.621038 -79.645715) (xy 396.620492 -79.629)
			(xy 379.095508 -79.629) (xy 379.094962 -79.645715) (xy 379.08631 -79.678006) (xy 379.069595 -79.706957)
			(xy 379.045957 -79.730595) (xy 379.017006 -79.74731) (xy 378.984715 -79.755962) (xy 378.968 -79.756508)
			(xy 377.19 -79.756508) (xy 377.173285 -79.755962) (xy 377.140994 -79.74731) (xy 377.112043 -79.730595)
			(xy 377.088405 -79.706957) (xy 377.07169 -79.678006) (xy 377.063038 -79.645715) (xy 377.062492 -79.629)
			(xy 328.5744 -79.629) (xy 328.813414 -79.868014) (xy 328.820809 -79.874868) (xy 328.839408 -79.88261)
			(xy 328.849482 -79.883) (xy 345.444318 -79.883) (xy 345.454284 -79.883478) (xy 345.472721 -79.891053)
			(xy 345.480132 -79.897732) (xy 347.345 -81.7626) (xy 347.345 -91.559888) (xy 375.283988 -91.559888)
			(xy 375.288017 -91.409861) (xy 375.300094 -91.260267) (xy 375.320183 -91.111537) (xy 375.348226 -90.964099)
			(xy 375.384143 -90.818379) (xy 375.427829 -90.674797) (xy 375.47916 -90.533767) (xy 375.537987 -90.395696)
			(xy 375.60414 -90.260981) (xy 375.677429 -90.130012) (xy 375.757642 -90.003165) (xy 375.844548 -89.880806)
			(xy 375.937897 -89.763289) (xy 376.037419 -89.650952) (xy 376.142827 -89.544119) (xy 376.253818 -89.443097)
			(xy 376.370072 -89.348179) (xy 376.491252 -89.259638) (xy 376.617011 -89.177729) (xy 376.746985 -89.102689)
			(xy 376.880799 -89.034733) (xy 377.018068 -88.974058) (xy 377.158396 -88.920839) (xy 377.301379 -88.875228)
			(xy 377.446603 -88.837359) (xy 377.593651 -88.807339) (xy 377.742099 -88.785255) (xy 377.891517 -88.771171)
			(xy 378.041476 -88.765128) (xy 378.191544 -88.767143) (xy 378.341287 -88.77721) (xy 378.490273 -88.7953)
			(xy 378.638074 -88.821361) (xy 378.784263 -88.855319) (xy 378.928419 -88.897074) (xy 379.070125 -88.946506)
			(xy 379.208974 -89.003474) (xy 379.344564 -89.067813) (xy 379.476506 -89.139337) (xy 379.604418 -89.21784)
			(xy 379.727933 -89.303095) (xy 379.846692 -89.394858) (xy 379.960356 -89.492863) (xy 380.068594 -89.596827)
			(xy 380.171097 -89.706452) (xy 380.267567 -89.821421) (xy 380.357727 -89.941402) (xy 380.441316 -90.06605)
			(xy 380.518095 -90.195004) (xy 380.587841 -90.327894) (xy 380.650354 -90.464337) (xy 380.705452 -90.603938)
			(xy 380.752978 -90.746295) (xy 380.792794 -90.890998) (xy 380.824786 -91.037629) (xy 380.84886 -91.185767)
			(xy 380.864949 -91.334983) (xy 380.873004 -91.484848) (xy 380.873508 -91.559888) (xy 394.841988 -91.559888)
			(xy 394.846017 -91.409861) (xy 394.858094 -91.260267) (xy 394.878183 -91.111537) (xy 394.906226 -90.964099)
			(xy 394.942143 -90.818379) (xy 394.985829 -90.674797) (xy 395.03716 -90.533767) (xy 395.095987 -90.395696)
			(xy 395.16214 -90.260981) (xy 395.235429 -90.130012) (xy 395.315642 -90.003165) (xy 395.402548 -89.880806)
			(xy 395.495897 -89.763289) (xy 395.595419 -89.650952) (xy 395.700827 -89.544119) (xy 395.811818 -89.443097)
			(xy 395.928072 -89.348179) (xy 396.049252 -89.259638) (xy 396.175011 -89.177729) (xy 396.304985 -89.102689)
			(xy 396.438799 -89.034733) (xy 396.576068 -88.974058) (xy 396.716396 -88.920839) (xy 396.859379 -88.875228)
			(xy 397.004603 -88.837359) (xy 397.151651 -88.807339) (xy 397.300099 -88.785255) (xy 397.449517 -88.771171)
			(xy 397.599476 -88.765128) (xy 397.749544 -88.767143) (xy 397.899287 -88.77721) (xy 398.048273 -88.7953)
			(xy 398.196074 -88.821361) (xy 398.342263 -88.855319) (xy 398.486419 -88.897074) (xy 398.628125 -88.946506)
			(xy 398.766974 -89.003474) (xy 398.902564 -89.067813) (xy 399.034506 -89.139337) (xy 399.162418 -89.21784)
			(xy 399.285933 -89.303095) (xy 399.404692 -89.394858) (xy 399.518356 -89.492863) (xy 399.626594 -89.596827)
			(xy 399.729097 -89.706452) (xy 399.825567 -89.821421) (xy 399.915727 -89.941402) (xy 399.999316 -90.06605)
			(xy 400.076095 -90.195004) (xy 400.145841 -90.327894) (xy 400.208354 -90.464337) (xy 400.263452 -90.603938)
			(xy 400.310978 -90.746295) (xy 400.350794 -90.890998) (xy 400.382786 -91.037629) (xy 400.40686 -91.185767)
			(xy 400.422949 -91.334983) (xy 400.431004 -91.484848) (xy 400.431508 -91.559888) (xy 400.431004 -91.634928)
			(xy 400.422949 -91.784793) (xy 400.40686 -91.934009) (xy 400.382786 -92.082147) (xy 400.350794 -92.228778)
			(xy 400.310978 -92.373481) (xy 400.263452 -92.515838) (xy 400.208354 -92.655439) (xy 400.145841 -92.791882)
			(xy 400.076095 -92.924772) (xy 399.999316 -93.053726) (xy 399.915727 -93.178374) (xy 399.825567 -93.298355)
			(xy 399.729097 -93.413324) (xy 399.626594 -93.522949) (xy 399.518356 -93.626913) (xy 399.404692 -93.724918)
			(xy 399.285933 -93.816681) (xy 399.162418 -93.901936) (xy 399.034506 -93.980439) (xy 398.902564 -94.051963)
			(xy 398.766974 -94.116302) (xy 398.628125 -94.17327) (xy 398.486419 -94.222702) (xy 398.342263 -94.264457)
			(xy 398.196074 -94.298415) (xy 398.048273 -94.324476) (xy 397.899287 -94.342566) (xy 397.749544 -94.352633)
			(xy 397.599476 -94.354648) (xy 397.449517 -94.348605) (xy 397.300099 -94.334521) (xy 397.151651 -94.312437)
			(xy 397.004603 -94.282417) (xy 396.859379 -94.244548) (xy 396.716396 -94.198937) (xy 396.576068 -94.145718)
			(xy 396.438799 -94.085043) (xy 396.304985 -94.017087) (xy 396.175011 -93.942047) (xy 396.049252 -93.860138)
			(xy 395.928072 -93.771597) (xy 395.811818 -93.676679) (xy 395.700827 -93.575657) (xy 395.595419 -93.468824)
			(xy 395.495897 -93.356487) (xy 395.402548 -93.23897) (xy 395.315642 -93.116611) (xy 395.235429 -92.989764)
			(xy 395.16214 -92.858795) (xy 395.095987 -92.72408) (xy 395.03716 -92.586009) (xy 394.985829 -92.444979)
			(xy 394.942143 -92.301397) (xy 394.906226 -92.155677) (xy 394.878183 -92.008239) (xy 394.858094 -91.859509)
			(xy 394.846017 -91.709915) (xy 394.841988 -91.559888) (xy 380.873508 -91.559888) (xy 380.873004 -91.634928)
			(xy 380.864949 -91.784793) (xy 380.84886 -91.934009) (xy 380.824786 -92.082147) (xy 380.792794 -92.228778)
			(xy 380.752978 -92.373481) (xy 380.705452 -92.515838) (xy 380.650354 -92.655439) (xy 380.587841 -92.791882)
			(xy 380.518095 -92.924772) (xy 380.441316 -93.053726) (xy 380.357727 -93.178374) (xy 380.267567 -93.298355)
			(xy 380.171097 -93.413324) (xy 380.068594 -93.522949) (xy 379.960356 -93.626913) (xy 379.846692 -93.724918)
			(xy 379.727933 -93.816681) (xy 379.604418 -93.901936) (xy 379.476506 -93.980439) (xy 379.344564 -94.051963)
			(xy 379.208974 -94.116302) (xy 379.070125 -94.17327) (xy 378.928419 -94.222702) (xy 378.784263 -94.264457)
			(xy 378.638074 -94.298415) (xy 378.490273 -94.324476) (xy 378.341287 -94.342566) (xy 378.191544 -94.352633)
			(xy 378.041476 -94.354648) (xy 377.891517 -94.348605) (xy 377.742099 -94.334521) (xy 377.593651 -94.312437)
			(xy 377.446603 -94.282417) (xy 377.301379 -94.244548) (xy 377.158396 -94.198937) (xy 377.018068 -94.145718)
			(xy 376.880799 -94.085043) (xy 376.746985 -94.017087) (xy 376.617011 -93.942047) (xy 376.491252 -93.860138)
			(xy 376.370072 -93.771597) (xy 376.253818 -93.676679) (xy 376.142827 -93.575657) (xy 376.037419 -93.468824)
			(xy 375.937897 -93.356487) (xy 375.844548 -93.23897) (xy 375.757642 -93.116611) (xy 375.677429 -92.989764)
			(xy 375.60414 -92.858795) (xy 375.537987 -92.72408) (xy 375.47916 -92.586009) (xy 375.427829 -92.444979)
			(xy 375.384143 -92.301397) (xy 375.348226 -92.155677) (xy 375.320183 -92.008239) (xy 375.300094 -91.859509)
			(xy 375.288017 -91.709915) (xy 375.283988 -91.559888) (xy 347.345 -91.559888) (xy 347.345 -99.775518)
			(xy 347.518482 -99.949) (xy 377.062492 -99.949) (xy 377.062492 -98.171) (xy 377.063038 -98.154285)
			(xy 377.07169 -98.121994) (xy 377.088405 -98.093043) (xy 377.112043 -98.069405) (xy 377.140994 -98.05269)
			(xy 377.173285 -98.044038) (xy 377.19 -98.043492) (xy 378.968 -98.043492) (xy 378.984715 -98.044038)
			(xy 379.017006 -98.05269) (xy 379.045957 -98.069405) (xy 379.069595 -98.093043) (xy 379.08631 -98.121994)
			(xy 379.094962 -98.154285) (xy 379.095508 -98.171) (xy 379.095508 -99.949) (xy 396.620492 -99.949)
			(xy 396.620492 -98.171) (xy 396.621038 -98.154285) (xy 396.62969 -98.121994) (xy 396.646405 -98.093043)
			(xy 396.670043 -98.069405) (xy 396.698994 -98.05269) (xy 396.731285 -98.044038) (xy 396.748 -98.043492)
			(xy 398.526 -98.043492) (xy 398.542715 -98.044038) (xy 398.575006 -98.05269) (xy 398.603957 -98.069405)
			(xy 398.627595 -98.093043) (xy 398.64431 -98.121994) (xy 398.652962 -98.154285) (xy 398.653508 -98.171)
			(xy 398.653508 -99.949) (xy 398.652962 -99.965715) (xy 398.64431 -99.998006) (xy 398.627595 -100.026957)
			(xy 398.603957 -100.050595) (xy 398.575006 -100.06731) (xy 398.542715 -100.075962) (xy 398.526 -100.076508)
			(xy 396.748 -100.076508) (xy 396.731285 -100.075962) (xy 396.698994 -100.06731) (xy 396.670043 -100.050595)
			(xy 396.646405 -100.026957) (xy 396.62969 -99.998006) (xy 396.621038 -99.965715) (xy 396.620492 -99.949)
			(xy 379.095508 -99.949) (xy 379.094962 -99.965715) (xy 379.08631 -99.998006) (xy 379.069595 -100.026957)
			(xy 379.045957 -100.050595) (xy 379.017006 -100.06731) (xy 378.984715 -100.075962) (xy 378.968 -100.076508)
			(xy 377.19 -100.076508) (xy 377.173285 -100.075962) (xy 377.140994 -100.06731) (xy 377.112043 -100.050595)
			(xy 377.088405 -100.026957) (xy 377.07169 -99.998006) (xy 377.063038 -99.965715) (xy 377.062492 -99.949)
			(xy 347.518482 -99.949) (xy 348.0054 -100.435918) (xy 348.005501 -100.44053) (xy 348.007162 -100.449603)
			(xy 348.008702 -100.453952) (xy 348.009972 -100.457254) (xy 348.011952 -100.461236) (xy 348.017059 -100.468517)
			(xy 348.020132 -100.471732) (xy 348.797118 -101.248718) (xy 348.803976 -101.252274) (xy 348.932167 -101.319424)
			(xy 349.185206 -101.459915) (xy 349.434247 -101.607379) (xy 349.679096 -101.761702) (xy 349.919566 -101.922764)
			(xy 350.15547 -102.090443) (xy 350.386627 -102.264607) (xy 350.612858 -102.445124) (xy 350.833989 -102.631853)
			(xy 351.04985 -102.824651) (xy 351.260273 -103.023369) (xy 351.363026 -103.12527) (xy 351.363788 -103.126286)
			(xy 351.366074 -103.128318) (xy 351.414209 -103.170695) (xy 351.505936 -103.260343) (xy 351.592181 -103.355275)
			(xy 351.632774 -103.404924) (xy 351.634806 -103.40721) (xy 351.635314 -103.407718) (xy 351.730515 -103.510901)
			(xy 351.915996 -103.721698) (xy 352.095732 -103.937416) (xy 352.269591 -104.157897) (xy 352.437447 -104.382982)
			(xy 352.599179 -104.612507) (xy 352.754668 -104.846305) (xy 352.903803 -105.084208) (xy 353.046475 -105.326042)
			(xy 353.18258 -105.571631) (xy 353.247706 -105.696004) (xy 353.25685 -105.70845) (xy 355.356414 -107.808014)
			(xy 355.363268 -107.815409) (xy 355.37101 -107.834008) (xy 355.3714 -107.844082) (xy 355.3714 -111.879888)
			(xy 375.283988 -111.879888) (xy 375.288017 -111.729861) (xy 375.300094 -111.580267) (xy 375.320183 -111.431537)
			(xy 375.348226 -111.284099) (xy 375.384143 -111.138379) (xy 375.427829 -110.994797) (xy 375.47916 -110.853767)
			(xy 375.537987 -110.715696) (xy 375.60414 -110.580981) (xy 375.677429 -110.450012) (xy 375.757642 -110.323165)
			(xy 375.844548 -110.200806) (xy 375.937897 -110.083289) (xy 376.037419 -109.970952) (xy 376.142827 -109.864119)
			(xy 376.253818 -109.763097) (xy 376.370072 -109.668179) (xy 376.491252 -109.579638) (xy 376.617011 -109.497729)
			(xy 376.746985 -109.422689) (xy 376.880799 -109.354733) (xy 377.018068 -109.294058) (xy 377.158396 -109.240839)
			(xy 377.301379 -109.195228) (xy 377.446603 -109.157359) (xy 377.593651 -109.127339) (xy 377.742099 -109.105255)
			(xy 377.891517 -109.091171) (xy 378.041476 -109.085128) (xy 378.191544 -109.087143) (xy 378.341287 -109.09721)
			(xy 378.490273 -109.1153) (xy 378.638074 -109.141361) (xy 378.784263 -109.175319) (xy 378.928419 -109.217074)
			(xy 379.070125 -109.266506) (xy 379.208974 -109.323474) (xy 379.344564 -109.387813) (xy 379.476506 -109.459337)
			(xy 379.604418 -109.53784) (xy 379.727933 -109.623095) (xy 379.846692 -109.714858) (xy 379.960356 -109.812863)
			(xy 380.068594 -109.916827) (xy 380.171097 -110.026452) (xy 380.267567 -110.141421) (xy 380.357727 -110.261402)
			(xy 380.441316 -110.38605) (xy 380.518095 -110.515004) (xy 380.587841 -110.647894) (xy 380.650354 -110.784337)
			(xy 380.705452 -110.923938) (xy 380.752978 -111.066295) (xy 380.792794 -111.210998) (xy 380.824786 -111.357629)
			(xy 380.84886 -111.505767) (xy 380.864949 -111.654983) (xy 380.873004 -111.804848) (xy 380.873508 -111.879888)
			(xy 394.841988 -111.879888) (xy 394.846017 -111.729861) (xy 394.858094 -111.580267) (xy 394.878183 -111.431537)
			(xy 394.906226 -111.284099) (xy 394.942143 -111.138379) (xy 394.985829 -110.994797) (xy 395.03716 -110.853767)
			(xy 395.095987 -110.715696) (xy 395.16214 -110.580981) (xy 395.235429 -110.450012) (xy 395.315642 -110.323165)
			(xy 395.402548 -110.200806) (xy 395.495897 -110.083289) (xy 395.595419 -109.970952) (xy 395.700827 -109.864119)
			(xy 395.811818 -109.763097) (xy 395.928072 -109.668179) (xy 396.049252 -109.579638) (xy 396.175011 -109.497729)
			(xy 396.304985 -109.422689) (xy 396.438799 -109.354733) (xy 396.576068 -109.294058) (xy 396.716396 -109.240839)
			(xy 396.859379 -109.195228) (xy 397.004603 -109.157359) (xy 397.151651 -109.127339) (xy 397.300099 -109.105255)
			(xy 397.449517 -109.091171) (xy 397.599476 -109.085128) (xy 397.749544 -109.087143) (xy 397.899287 -109.09721)
			(xy 398.048273 -109.1153) (xy 398.196074 -109.141361) (xy 398.342263 -109.175319) (xy 398.486419 -109.217074)
			(xy 398.628125 -109.266506) (xy 398.766974 -109.323474) (xy 398.902564 -109.387813) (xy 399.034506 -109.459337)
			(xy 399.162418 -109.53784) (xy 399.285933 -109.623095) (xy 399.404692 -109.714858) (xy 399.518356 -109.812863)
			(xy 399.626594 -109.916827) (xy 399.729097 -110.026452) (xy 399.825567 -110.141421) (xy 399.915727 -110.261402)
			(xy 399.999316 -110.38605) (xy 400.076095 -110.515004) (xy 400.145841 -110.647894) (xy 400.208354 -110.784337)
			(xy 400.263452 -110.923938) (xy 400.310978 -111.066295) (xy 400.350794 -111.210998) (xy 400.382786 -111.357629)
			(xy 400.40686 -111.505767) (xy 400.422949 -111.654983) (xy 400.431004 -111.804848) (xy 400.431508 -111.879888)
			(xy 400.431004 -111.954928) (xy 400.422949 -112.104793) (xy 400.40686 -112.254009) (xy 400.382786 -112.402147)
			(xy 400.350794 -112.548778) (xy 400.310978 -112.693481) (xy 400.263452 -112.835838) (xy 400.208354 -112.975439)
			(xy 400.145841 -113.111882) (xy 400.076095 -113.244772) (xy 399.999316 -113.373726) (xy 399.915727 -113.498374)
			(xy 399.825567 -113.618355) (xy 399.729097 -113.733324) (xy 399.626594 -113.842949) (xy 399.518356 -113.946913)
			(xy 399.404692 -114.044918) (xy 399.285933 -114.136681) (xy 399.162418 -114.221936) (xy 399.034506 -114.300439)
			(xy 398.902564 -114.371963) (xy 398.766974 -114.436302) (xy 398.628125 -114.49327) (xy 398.486419 -114.542702)
			(xy 398.342263 -114.584457) (xy 398.196074 -114.618415) (xy 398.048273 -114.644476) (xy 397.899287 -114.662566)
			(xy 397.749544 -114.672633) (xy 397.599476 -114.674648) (xy 397.449517 -114.668605) (xy 397.300099 -114.654521)
			(xy 397.151651 -114.632437) (xy 397.004603 -114.602417) (xy 396.859379 -114.564548) (xy 396.716396 -114.518937)
			(xy 396.576068 -114.465718) (xy 396.438799 -114.405043) (xy 396.304985 -114.337087) (xy 396.175011 -114.262047)
			(xy 396.049252 -114.180138) (xy 395.928072 -114.091597) (xy 395.811818 -113.996679) (xy 395.700827 -113.895657)
			(xy 395.595419 -113.788824) (xy 395.495897 -113.676487) (xy 395.402548 -113.55897) (xy 395.315642 -113.436611)
			(xy 395.235429 -113.309764) (xy 395.16214 -113.178795) (xy 395.095987 -113.04408) (xy 395.03716 -112.906009)
			(xy 394.985829 -112.764979) (xy 394.942143 -112.621397) (xy 394.906226 -112.475677) (xy 394.878183 -112.328239)
			(xy 394.858094 -112.179509) (xy 394.846017 -112.029915) (xy 394.841988 -111.879888) (xy 380.873508 -111.879888)
			(xy 380.873004 -111.954928) (xy 380.864949 -112.104793) (xy 380.84886 -112.254009) (xy 380.824786 -112.402147)
			(xy 380.792794 -112.548778) (xy 380.752978 -112.693481) (xy 380.705452 -112.835838) (xy 380.650354 -112.975439)
			(xy 380.587841 -113.111882) (xy 380.518095 -113.244772) (xy 380.441316 -113.373726) (xy 380.357727 -113.498374)
			(xy 380.267567 -113.618355) (xy 380.171097 -113.733324) (xy 380.068594 -113.842949) (xy 379.960356 -113.946913)
			(xy 379.846692 -114.044918) (xy 379.727933 -114.136681) (xy 379.604418 -114.221936) (xy 379.476506 -114.300439)
			(xy 379.344564 -114.371963) (xy 379.208974 -114.436302) (xy 379.070125 -114.49327) (xy 378.928419 -114.542702)
			(xy 378.784263 -114.584457) (xy 378.638074 -114.618415) (xy 378.490273 -114.644476) (xy 378.341287 -114.662566)
			(xy 378.191544 -114.672633) (xy 378.041476 -114.674648) (xy 377.891517 -114.668605) (xy 377.742099 -114.654521)
			(xy 377.593651 -114.632437) (xy 377.446603 -114.602417) (xy 377.301379 -114.564548) (xy 377.158396 -114.518937)
			(xy 377.018068 -114.465718) (xy 376.880799 -114.405043) (xy 376.746985 -114.337087) (xy 376.617011 -114.262047)
			(xy 376.491252 -114.180138) (xy 376.370072 -114.091597) (xy 376.253818 -113.996679) (xy 376.142827 -113.895657)
			(xy 376.037419 -113.788824) (xy 375.937897 -113.676487) (xy 375.844548 -113.55897) (xy 375.757642 -113.436611)
			(xy 375.677429 -113.309764) (xy 375.60414 -113.178795) (xy 375.537987 -113.04408) (xy 375.47916 -112.906009)
			(xy 375.427829 -112.764979) (xy 375.384143 -112.621397) (xy 375.348226 -112.475677) (xy 375.320183 -112.328239)
			(xy 375.300094 -112.179509) (xy 375.288017 -112.029915) (xy 375.283988 -111.879888) (xy 355.3714 -111.879888)
			(xy 355.3714 -120.269) (xy 377.062492 -120.269) (xy 377.062492 -118.491) (xy 377.063038 -118.474285)
			(xy 377.07169 -118.441994) (xy 377.088405 -118.413043) (xy 377.112043 -118.389405) (xy 377.140994 -118.37269)
			(xy 377.173285 -118.364038) (xy 377.19 -118.363492) (xy 378.968 -118.363492) (xy 378.984715 -118.364038)
			(xy 379.017006 -118.37269) (xy 379.045957 -118.389405) (xy 379.069595 -118.413043) (xy 379.08631 -118.441994)
			(xy 379.094962 -118.474285) (xy 379.095508 -118.491) (xy 379.095508 -120.269) (xy 396.620492 -120.269)
			(xy 396.620492 -118.491) (xy 396.621038 -118.474285) (xy 396.62969 -118.441994) (xy 396.646405 -118.413043)
			(xy 396.670043 -118.389405) (xy 396.698994 -118.37269) (xy 396.731285 -118.364038) (xy 396.748 -118.363492)
			(xy 398.526 -118.363492) (xy 398.542715 -118.364038) (xy 398.575006 -118.37269) (xy 398.603957 -118.389405)
			(xy 398.627595 -118.413043) (xy 398.64431 -118.441994) (xy 398.652962 -118.474285) (xy 398.653508 -118.491)
			(xy 398.653508 -120.269) (xy 398.652962 -120.285715) (xy 398.64431 -120.318006) (xy 398.627595 -120.346957)
			(xy 398.603957 -120.370595) (xy 398.575006 -120.38731) (xy 398.542715 -120.395962) (xy 398.526 -120.396508)
			(xy 396.748 -120.396508) (xy 396.731285 -120.395962) (xy 396.698994 -120.38731) (xy 396.670043 -120.370595)
			(xy 396.646405 -120.346957) (xy 396.62969 -120.318006) (xy 396.621038 -120.285715) (xy 396.620492 -120.269)
			(xy 379.095508 -120.269) (xy 379.094962 -120.285715) (xy 379.08631 -120.318006) (xy 379.069595 -120.346957)
			(xy 379.045957 -120.370595) (xy 379.017006 -120.38731) (xy 378.984715 -120.395962) (xy 378.968 -120.396508)
			(xy 377.19 -120.396508) (xy 377.173285 -120.395962) (xy 377.140994 -120.38731) (xy 377.112043 -120.370595)
			(xy 377.088405 -120.346957) (xy 377.07169 -120.318006) (xy 377.063038 -120.285715) (xy 377.062492 -120.269)
			(xy 355.3714 -120.269) (xy 355.3714 -132.199888) (xy 375.283988 -132.199888) (xy 375.288017 -132.049861)
			(xy 375.300094 -131.900267) (xy 375.320183 -131.751537) (xy 375.348226 -131.604099) (xy 375.384143 -131.458379)
			(xy 375.427829 -131.314797) (xy 375.47916 -131.173767) (xy 375.537987 -131.035696) (xy 375.60414 -130.900981)
			(xy 375.677429 -130.770012) (xy 375.757642 -130.643165) (xy 375.844548 -130.520806) (xy 375.937897 -130.403289)
			(xy 376.037419 -130.290952) (xy 376.142827 -130.184119) (xy 376.253818 -130.083097) (xy 376.370072 -129.988179)
			(xy 376.491252 -129.899638) (xy 376.617011 -129.817729) (xy 376.746985 -129.742689) (xy 376.880799 -129.674733)
			(xy 377.018068 -129.614058) (xy 377.158396 -129.560839) (xy 377.301379 -129.515228) (xy 377.446603 -129.477359)
			(xy 377.593651 -129.447339) (xy 377.742099 -129.425255) (xy 377.891517 -129.411171) (xy 378.041476 -129.405128)
			(xy 378.191544 -129.407143) (xy 378.341287 -129.41721) (xy 378.490273 -129.4353) (xy 378.638074 -129.461361)
			(xy 378.784263 -129.495319) (xy 378.928419 -129.537074) (xy 379.070125 -129.586506) (xy 379.208974 -129.643474)
			(xy 379.344564 -129.707813) (xy 379.476506 -129.779337) (xy 379.604418 -129.85784) (xy 379.727933 -129.943095)
			(xy 379.846692 -130.034858) (xy 379.960356 -130.132863) (xy 380.068594 -130.236827) (xy 380.171097 -130.346452)
			(xy 380.267567 -130.461421) (xy 380.357727 -130.581402) (xy 380.441316 -130.70605) (xy 380.518095 -130.835004)
			(xy 380.587841 -130.967894) (xy 380.650354 -131.104337) (xy 380.705452 -131.243938) (xy 380.752978 -131.386295)
			(xy 380.792794 -131.530998) (xy 380.824786 -131.677629) (xy 380.84886 -131.825767) (xy 380.864949 -131.974983)
			(xy 380.873004 -132.124848) (xy 380.873508 -132.199888) (xy 394.841988 -132.199888) (xy 394.846017 -132.049861)
			(xy 394.858094 -131.900267) (xy 394.878183 -131.751537) (xy 394.906226 -131.604099) (xy 394.942143 -131.458379)
			(xy 394.985829 -131.314797) (xy 395.03716 -131.173767) (xy 395.095987 -131.035696) (xy 395.16214 -130.900981)
			(xy 395.235429 -130.770012) (xy 395.315642 -130.643165) (xy 395.402548 -130.520806) (xy 395.495897 -130.403289)
			(xy 395.595419 -130.290952) (xy 395.700827 -130.184119) (xy 395.811818 -130.083097) (xy 395.928072 -129.988179)
			(xy 396.049252 -129.899638) (xy 396.175011 -129.817729) (xy 396.304985 -129.742689) (xy 396.438799 -129.674733)
			(xy 396.576068 -129.614058) (xy 396.716396 -129.560839) (xy 396.859379 -129.515228) (xy 397.004603 -129.477359)
			(xy 397.151651 -129.447339) (xy 397.300099 -129.425255) (xy 397.449517 -129.411171) (xy 397.599476 -129.405128)
			(xy 397.749544 -129.407143) (xy 397.899287 -129.41721) (xy 398.048273 -129.4353) (xy 398.196074 -129.461361)
			(xy 398.342263 -129.495319) (xy 398.486419 -129.537074) (xy 398.628125 -129.586506) (xy 398.766974 -129.643474)
			(xy 398.902564 -129.707813) (xy 399.034506 -129.779337) (xy 399.162418 -129.85784) (xy 399.285933 -129.943095)
			(xy 399.404692 -130.034858) (xy 399.518356 -130.132863) (xy 399.626594 -130.236827) (xy 399.729097 -130.346452)
			(xy 399.825567 -130.461421) (xy 399.915727 -130.581402) (xy 399.999316 -130.70605) (xy 400.076095 -130.835004)
			(xy 400.145841 -130.967894) (xy 400.208354 -131.104337) (xy 400.263452 -131.243938) (xy 400.310978 -131.386295)
			(xy 400.350794 -131.530998) (xy 400.382786 -131.677629) (xy 400.40686 -131.825767) (xy 400.422949 -131.974983)
			(xy 400.431004 -132.124848) (xy 400.431508 -132.199888) (xy 400.431004 -132.274928) (xy 400.422949 -132.424793)
			(xy 400.40686 -132.574009) (xy 400.382786 -132.722147) (xy 400.350794 -132.868778) (xy 400.310978 -133.013481)
			(xy 400.263452 -133.155838) (xy 400.208354 -133.295439) (xy 400.145841 -133.431882) (xy 400.076095 -133.564772)
			(xy 399.999316 -133.693726) (xy 399.915727 -133.818374) (xy 399.825567 -133.938355) (xy 399.729097 -134.053324)
			(xy 399.626594 -134.162949) (xy 399.518356 -134.266913) (xy 399.404692 -134.364918) (xy 399.285933 -134.456681)
			(xy 399.162418 -134.541936) (xy 399.034506 -134.620439) (xy 398.902564 -134.691963) (xy 398.766974 -134.756302)
			(xy 398.628125 -134.81327) (xy 398.486419 -134.862702) (xy 398.342263 -134.904457) (xy 398.196074 -134.938415)
			(xy 398.048273 -134.964476) (xy 397.899287 -134.982566) (xy 397.749544 -134.992633) (xy 397.599476 -134.994648)
			(xy 397.449517 -134.988605) (xy 397.300099 -134.974521) (xy 397.151651 -134.952437) (xy 397.004603 -134.922417)
			(xy 396.859379 -134.884548) (xy 396.716396 -134.838937) (xy 396.576068 -134.785718) (xy 396.438799 -134.725043)
			(xy 396.304985 -134.657087) (xy 396.175011 -134.582047) (xy 396.049252 -134.500138) (xy 395.928072 -134.411597)
			(xy 395.811818 -134.316679) (xy 395.700827 -134.215657) (xy 395.595419 -134.108824) (xy 395.495897 -133.996487)
			(xy 395.402548 -133.87897) (xy 395.315642 -133.756611) (xy 395.235429 -133.629764) (xy 395.16214 -133.498795)
			(xy 395.095987 -133.36408) (xy 395.03716 -133.226009) (xy 394.985829 -133.084979) (xy 394.942143 -132.941397)
			(xy 394.906226 -132.795677) (xy 394.878183 -132.648239) (xy 394.858094 -132.499509) (xy 394.846017 -132.349915)
			(xy 394.841988 -132.199888) (xy 380.873508 -132.199888) (xy 380.873004 -132.274928) (xy 380.864949 -132.424793)
			(xy 380.84886 -132.574009) (xy 380.824786 -132.722147) (xy 380.792794 -132.868778) (xy 380.752978 -133.013481)
			(xy 380.705452 -133.155838) (xy 380.650354 -133.295439) (xy 380.587841 -133.431882) (xy 380.518095 -133.564772)
			(xy 380.441316 -133.693726) (xy 380.357727 -133.818374) (xy 380.267567 -133.938355) (xy 380.171097 -134.053324)
			(xy 380.068594 -134.162949) (xy 379.960356 -134.266913) (xy 379.846692 -134.364918) (xy 379.727933 -134.456681)
			(xy 379.604418 -134.541936) (xy 379.476506 -134.620439) (xy 379.344564 -134.691963) (xy 379.208974 -134.756302)
			(xy 379.070125 -134.81327) (xy 378.928419 -134.862702) (xy 378.784263 -134.904457) (xy 378.638074 -134.938415)
			(xy 378.490273 -134.964476) (xy 378.341287 -134.982566) (xy 378.191544 -134.992633) (xy 378.041476 -134.994648)
			(xy 377.891517 -134.988605) (xy 377.742099 -134.974521) (xy 377.593651 -134.952437) (xy 377.446603 -134.922417)
			(xy 377.301379 -134.884548) (xy 377.158396 -134.838937) (xy 377.018068 -134.785718) (xy 376.880799 -134.725043)
			(xy 376.746985 -134.657087) (xy 376.617011 -134.582047) (xy 376.491252 -134.500138) (xy 376.370072 -134.411597)
			(xy 376.253818 -134.316679) (xy 376.142827 -134.215657) (xy 376.037419 -134.108824) (xy 375.937897 -133.996487)
			(xy 375.844548 -133.87897) (xy 375.757642 -133.756611) (xy 375.677429 -133.629764) (xy 375.60414 -133.498795)
			(xy 375.537987 -133.36408) (xy 375.47916 -133.226009) (xy 375.427829 -133.084979) (xy 375.384143 -132.941397)
			(xy 375.348226 -132.795677) (xy 375.320183 -132.648239) (xy 375.300094 -132.499509) (xy 375.288017 -132.349915)
			(xy 375.283988 -132.199888) (xy 355.3714 -132.199888) (xy 355.3714 -135.138414) (xy 355.371712 -135.146607)
			(xy 355.376897 -135.16215) (xy 355.38156 -135.168894) (xy 355.386386 -135.174482) (xy 355.853746 -135.641842)
			(xy 355.859334 -135.646668) (xy 355.866076 -135.651333) (xy 355.881622 -135.656508) (xy 355.889814 -135.656828)
			(xy 362.988352 -135.656828) (xy 362.998417 -135.657261) (xy 363.017006 -135.664992) (xy 363.02442 -135.671814)
			(xy 366.632998 -139.280392) (xy 366.639846 -139.28779) (xy 366.647584 -139.306388) (xy 366.647984 -139.31646)
			(xy 366.647984 -140.589) (xy 377.062492 -140.589) (xy 377.062492 -138.811) (xy 377.063038 -138.794285)
			(xy 377.07169 -138.761994) (xy 377.088405 -138.733043) (xy 377.112043 -138.709405) (xy 377.140994 -138.69269)
			(xy 377.173285 -138.684038) (xy 377.19 -138.683492) (xy 378.968 -138.683492) (xy 378.984715 -138.684038)
			(xy 379.017006 -138.69269) (xy 379.045957 -138.709405) (xy 379.069595 -138.733043) (xy 379.08631 -138.761994)
			(xy 379.094962 -138.794285) (xy 379.095508 -138.811) (xy 379.095508 -140.589) (xy 396.620492 -140.589)
			(xy 396.620492 -138.811) (xy 396.621038 -138.794285) (xy 396.62969 -138.761994) (xy 396.646405 -138.733043)
			(xy 396.670043 -138.709405) (xy 396.698994 -138.69269) (xy 396.731285 -138.684038) (xy 396.748 -138.683492)
			(xy 398.526 -138.683492) (xy 398.542715 -138.684038) (xy 398.575006 -138.69269) (xy 398.603957 -138.709405)
			(xy 398.627595 -138.733043) (xy 398.64431 -138.761994) (xy 398.652962 -138.794285) (xy 398.653508 -138.811)
			(xy 398.653508 -140.589) (xy 398.652962 -140.605715) (xy 398.64431 -140.638006) (xy 398.627595 -140.666957)
			(xy 398.603957 -140.690595) (xy 398.575006 -140.70731) (xy 398.542715 -140.715962) (xy 398.526 -140.716508)
			(xy 396.748 -140.716508) (xy 396.731285 -140.715962) (xy 396.698994 -140.70731) (xy 396.670043 -140.690595)
			(xy 396.646405 -140.666957) (xy 396.62969 -140.638006) (xy 396.621038 -140.605715) (xy 396.620492 -140.589)
			(xy 379.095508 -140.589) (xy 379.094962 -140.605715) (xy 379.08631 -140.638006) (xy 379.069595 -140.666957)
			(xy 379.045957 -140.690595) (xy 379.017006 -140.70731) (xy 378.984715 -140.715962) (xy 378.968 -140.716508)
			(xy 377.19 -140.716508) (xy 377.173285 -140.715962) (xy 377.140994 -140.70731) (xy 377.112043 -140.690595)
			(xy 377.088405 -140.666957) (xy 377.07169 -140.638006) (xy 377.063038 -140.605715) (xy 377.062492 -140.589)
			(xy 366.647984 -140.589) (xy 366.647984 -150.640034) (xy 366.647554 -150.650101) (xy 366.639829 -150.668695)
			(xy 366.632998 -150.676102) (xy 362.563156 -154.745944) (xy 362.55833 -154.751532) (xy 362.553665 -154.758274)
			(xy 362.54849 -154.77382) (xy 362.54817 -154.782012) (xy 362.54817 -159.22244) (xy 362.548932 -159.231076)
			(xy 362.551218 -159.240474) (xy 362.590667 -159.348346) (xy 362.662182 -159.566646) (xy 362.695773 -159.684443)
			(xy 371.513342 -159.684443) (xy 371.513342 -159.575777) (xy 371.521274 -159.467402) (xy 371.537096 -159.359895)
			(xy 371.560723 -159.253829) (xy 371.592029 -159.149772) (xy 371.630848 -159.048277) (xy 371.676971 -158.949886)
			(xy 371.730154 -158.855125) (xy 371.790112 -158.764498) (xy 371.856525 -158.67849) (xy 371.92904 -158.597559)
			(xy 372.007268 -158.522137) (xy 372.090793 -158.452627) (xy 372.17917 -158.389399) (xy 372.271925 -158.332791)
			(xy 372.368566 -158.283105) (xy 372.468576 -158.240606) (xy 372.571421 -158.20552) (xy 372.676552 -158.178035)
			(xy 372.78341 -158.158297) (xy 372.891423 -158.146412) (xy 373.000016 -158.142444) (xy 373.108609 -158.146412)
			(xy 373.216622 -158.158297) (xy 373.32348 -158.178035) (xy 373.428611 -158.20552) (xy 373.531456 -158.240606)
			(xy 373.631466 -158.283105) (xy 373.728107 -158.332791) (xy 373.820862 -158.389399) (xy 373.909239 -158.452627)
			(xy 373.992764 -158.522137) (xy 374.070992 -158.597559) (xy 374.143507 -158.67849) (xy 374.20992 -158.764498)
			(xy 374.269878 -158.855125) (xy 374.323061 -158.949886) (xy 374.369184 -159.048277) (xy 374.408003 -159.149772)
			(xy 374.439309 -159.253829) (xy 374.462936 -159.359895) (xy 374.478758 -159.467402) (xy 374.48669 -159.575777)
			(xy 374.487186 -159.63011) (xy 374.48669 -159.684443) (xy 374.478758 -159.792818) (xy 374.462936 -159.900325)
			(xy 374.439309 -160.006391) (xy 374.408003 -160.110448) (xy 374.369184 -160.211943) (xy 374.323061 -160.310334)
			(xy 374.269878 -160.405095) (xy 374.20992 -160.495722) (xy 374.143507 -160.58173) (xy 374.070992 -160.662661)
			(xy 373.992764 -160.738083) (xy 373.909239 -160.807593) (xy 373.820862 -160.870821) (xy 373.728107 -160.927429)
			(xy 373.631466 -160.977115) (xy 373.531456 -161.019614) (xy 373.428611 -161.0547) (xy 373.32348 -161.082185)
			(xy 373.216622 -161.101923) (xy 373.108609 -161.113808) (xy 373.000016 -161.117777) (xy 372.891423 -161.113808)
			(xy 372.78341 -161.101923) (xy 372.676552 -161.082185) (xy 372.571421 -161.0547) (xy 372.468576 -161.019614)
			(xy 372.368566 -160.977115) (xy 372.271925 -160.927429) (xy 372.17917 -160.870821) (xy 372.090793 -160.807593)
			(xy 372.007268 -160.738083) (xy 371.92904 -160.662661) (xy 371.856525 -160.58173) (xy 371.790112 -160.495722)
			(xy 371.730154 -160.405095) (xy 371.676971 -160.310334) (xy 371.630848 -160.211943) (xy 371.592029 -160.110448)
			(xy 371.560723 -160.006391) (xy 371.537096 -159.900325) (xy 371.521274 -159.792818) (xy 371.513342 -159.684443)
			(xy 362.695773 -159.684443) (xy 362.725176 -159.787555) (xy 362.779553 -160.010742) (xy 362.825231 -160.23587)
			(xy 362.862142 -160.462601) (xy 362.890229 -160.690593) (xy 362.909452 -160.919503) (xy 362.91978 -161.148986)
			(xy 362.921042 -161.263838) (xy 362.921042 -161.266378) (xy 362.92269 -161.296895) (xy 362.924469 -161.357991)
			(xy 362.924598 -161.388552) (xy 362.924598 -161.390076) (xy 362.924458 -161.419111) (xy 362.922808 -161.477158)
			(xy 362.921296 -161.506154) (xy 362.921296 -161.6202) (xy 362.921784 -161.630208) (xy 362.929444 -161.6487)
			(xy 362.943596 -161.662854) (xy 362.962088 -161.670515) (xy 362.972096 -161.671) (xy 385.865116 -161.671)
			(xy 385.909312 -161.644838) (xy 385.935347 -161.596889) (xy 385.993568 -161.504601) (xy 386.05851 -161.416914)
			(xy 386.129813 -161.334315) (xy 386.207079 -161.257266) (xy 386.289878 -161.186195) (xy 386.377747 -161.121498)
			(xy 386.470198 -161.063537) (xy 386.566715 -161.012634) (xy 386.66676 -160.969072) (xy 386.769776 -160.933095)
			(xy 386.875188 -160.904902) (xy 386.98241 -160.884652) (xy 387.090844 -160.872456) (xy 387.199886 -160.868383)
			(xy 387.308928 -160.872456) (xy 387.417362 -160.884652) (xy 387.524584 -160.904902) (xy 387.629996 -160.933095)
			(xy 387.733012 -160.969072) (xy 387.833057 -161.012634) (xy 387.929574 -161.063537) (xy 388.022025 -161.121498)
			(xy 388.109894 -161.186195) (xy 388.192693 -161.257266) (xy 388.269959 -161.334315) (xy 388.341262 -161.416914)
			(xy 388.406204 -161.504601) (xy 388.464425 -161.596889) (xy 388.49046 -161.644838) (xy 388.534656 -161.671)
			(xy 396.345918 -161.671) (xy 396.355987 -161.671427) (xy 396.374586 -161.679146) (xy 396.381986 -161.685986)
			(xy 396.733014 -162.037014) (xy 396.739868 -162.044409) (xy 396.74761 -162.063008) (xy 396.748 -162.073082)
			(xy 396.748 -168.888918) (xy 396.748164 -168.894929) (xy 396.750981 -168.906614) (xy 396.753588 -168.912032)
			(xy 396.755428 -168.915506) (xy 396.760022 -168.921884) (xy 396.762732 -168.924732) (xy 397.201898 -169.363898)
			(xy 397.207486 -169.368724) (xy 397.214225 -169.373399) (xy 397.229771 -169.378593) (xy 397.237966 -169.378884)
			(xy 397.613378 -169.378884)
		)
		(stroke
			(width 0)
			(type solid)
		)
		(fill yes)
		(layer "B.Cu")
		(net "P52V_HS1")
	)
	(gr_poly
		(pts
			(xy 406.6667 -169.417238) (xy 406.674306 -169.415725) (xy 406.688143 -169.408742) (xy 406.693878 -169.403522)
			(xy 407.451814 -168.645586) (xy 407.458668 -168.638191) (xy 407.46641 -168.619592) (xy 407.4668 -168.609518)
			(xy 407.4668 -160.904682) (xy 407.467227 -160.894613) (xy 407.474946 -160.876014) (xy 407.481786 -160.868614)
			(xy 411.617414 -156.732986) (xy 411.624809 -156.726132) (xy 411.643408 -156.71839) (xy 411.653482 -156.718)
			(xy 435.842918 -156.718) (xy 435.852987 -156.717573) (xy 435.871586 -156.709854) (xy 435.878986 -156.703014)
			(xy 438.617614 -153.964386) (xy 438.624468 -153.956991) (xy 438.63221 -153.938392) (xy 438.6326 -153.928318)
			(xy 438.6326 -133.777482) (xy 438.633027 -133.767413) (xy 438.640746 -133.748814) (xy 438.647586 -133.741414)
			(xy 442.453014 -129.935986) (xy 442.460409 -129.929132) (xy 442.479008 -129.92139) (xy 442.489082 -129.921)
			(xy 472.418918 -129.921) (xy 472.428987 -129.920573) (xy 472.447586 -129.912854) (xy 472.454986 -129.906014)
			(xy 474.203014 -128.157986) (xy 474.209868 -128.150591) (xy 474.21761 -128.131992) (xy 474.218 -128.121918)
			(xy 474.218 -112.653318) (xy 474.217746 -112.647222) (xy 474.216476 -112.63757) (xy 474.215183 -112.629158)
			(xy 474.207779 -112.613845) (xy 474.201998 -112.607598) (xy 473.242386 -111.647986) (xy 473.235274 -111.64062)
			(xy 473.216478 -111.633) (xy 466.324188 -111.633) (xy 466.314119 -111.632575) (xy 466.295518 -111.624857)
			(xy 466.28812 -111.618014) (xy 464.031584 -109.361478) (xy 464.024732 -109.354082) (xy 464.016992 -109.335483)
			(xy 464.016598 -109.32541) (xy 464.016598 -92.3925) (xy 464.016344 -92.386404) (xy 464.015074 -92.376752)
			(xy 464.013778 -92.368341) (xy 464.00637 -92.353033) (xy 464.000596 -92.34678) (xy 463.366612 -91.712796)
			(xy 463.3595 -91.70543) (xy 463.340704 -91.69781) (xy 451.415912 -91.69781) (xy 451.405841 -91.69739)
			(xy 451.387232 -91.689679) (xy 451.379844 -91.682824) (xy 451.239636 -91.542616) (xy 451.236547 -91.539613)
			(xy 451.229522 -91.534629) (xy 451.225666 -91.53271) (xy 451.206108 -91.523312) (xy 451.198996 -91.522042)
			(xy 451.173214 -91.517122) (xy 451.123461 -91.500408) (xy 451.076859 -91.476262) (xy 451.03451 -91.445257)
			(xy 451.015608 -91.427046) (xy 448.860418 -89.271856) (xy 448.855846 -89.2683) (xy 448.841876 -89.259156)
			(xy 448.836542 -89.257124) (xy 448.809647 -89.246491) (xy 448.759164 -89.218279) (xy 448.713522 -89.182765)
			(xy 448.673768 -89.140764) (xy 448.640814 -89.093239) (xy 448.615418 -89.041283) (xy 448.598161 -88.986086)
			(xy 448.589441 -88.928916) (xy 448.588892 -88.9) (xy 448.589378 -88.872749) (xy 448.597134 -88.818801)
			(xy 448.612489 -88.766506) (xy 448.635131 -88.716929) (xy 448.664597 -88.671079) (xy 448.700288 -88.629888)
			(xy 448.741479 -88.594197) (xy 448.787329 -88.564731) (xy 448.836906 -88.542089) (xy 448.889201 -88.526734)
			(xy 448.943149 -88.518978) (xy 448.9704 -88.518492) (xy 448.999181 -88.519017) (xy 449.05609 -88.527667)
			(xy 449.111053 -88.54477) (xy 449.162821 -88.569939) (xy 449.21022 -88.602601) (xy 449.252172 -88.642014)
			(xy 449.287725 -88.687285) (xy 449.316071 -88.737384) (xy 449.326762 -88.76411) (xy 449.32727 -88.765634)
			(xy 449.32981 -88.771984) (xy 449.337684 -88.784176) (xy 449.340986 -88.788748) (xy 450.014594 -89.462356)
			(xy 450.022623 -89.469632) (xy 450.042878 -89.477278) (xy 450.05371 -89.477088) (xy 450.061584 -89.47658)
			(xy 450.147944 -89.444068) (xy 450.153786 -89.439496) (xy 450.160136 -89.43467) (xy 450.183504 -89.40292)
			(xy 450.18833 -89.39022) (xy 450.188838 -89.382854) (xy 450.19351 -89.331579) (xy 450.210107 -89.229957)
			(xy 450.234876 -89.130011) (xy 450.267653 -89.032399) (xy 450.308223 -88.937759) (xy 450.356319 -88.846713)
			(xy 450.411628 -88.759859) (xy 450.473784 -88.677767) (xy 450.542381 -88.600974) (xy 450.616968 -88.529986)
			(xy 450.697056 -88.465268) (xy 450.78212 -88.407244) (xy 450.871601 -88.356296) (xy 450.964912 -88.312757)
			(xy 451.061441 -88.276913) (xy 451.110858 -88.26246) (xy 451.118478 -88.260428) (xy 451.144894 -88.243156)
			(xy 451.150228 -88.236044) (xy 451.168369 -88.212806) (xy 451.210603 -88.171678) (xy 451.25866 -88.137535)
			(xy 451.311396 -88.111189) (xy 451.367557 -88.093268) (xy 451.425807 -88.084199) (xy 451.455282 -88.083644)
			(xy 451.479089 -88.084062) (xy 451.526323 -88.090085) (xy 451.572442 -88.101928) (xy 451.594728 -88.110314)
			(xy 451.606412 -88.11514) (xy 451.631558 -88.112346) (xy 451.711822 -88.057736) (xy 451.721762 -88.050162)
			(xy 451.733353 -88.028055) (xy 451.73392 -88.015572) (xy 451.73392 -68.071238) (xy 451.733666 -68.065142)
			(xy 451.732396 -68.05549) (xy 451.731107 -68.047076) (xy 451.723709 -68.031757) (xy 451.717918 -68.025518)
			(xy 451.525386 -67.832986) (xy 451.518274 -67.82562) (xy 451.499478 -67.818) (xy 441.74791 -67.818)
			(xy 441.742955 -67.817882) (xy 441.733233 -67.815965) (xy 441.728606 -67.81419) (xy 441.719462 -67.81038)
			(xy 441.712604 -67.803522) (xy 441.712096 -67.803014) (xy 440.88304 -66.973958) (xy 440.8763 -66.966587)
			(xy 440.868717 -66.948125) (xy 440.868308 -66.938144) (xy 440.868308 -62.753748) (xy 440.868741 -62.743682)
			(xy 440.876469 -62.725092) (xy 440.883294 -62.71768) (xy 441.482988 -62.117986) (xy 441.490382 -62.111128)
			(xy 441.508981 -62.103376) (xy 441.519056 -62.103) (xy 455.680318 -62.103) (xy 455.690387 -62.102573)
			(xy 455.708986 -62.094854) (xy 455.716386 -62.088014) (xy 455.948034 -61.856366) (xy 455.954882 -61.848969)
			(xy 455.962615 -61.83037) (xy 455.96302 -61.820298) (xy 455.96302 -54.571138) (xy 455.962766 -54.565042)
			(xy 455.961496 -54.55539) (xy 455.960207 -54.546976) (xy 455.952809 -54.531657) (xy 455.947018 -54.525418)
			(xy 454.217786 -52.796186) (xy 454.210674 -52.78882) (xy 454.191878 -52.7812) (xy 437.231282 -52.7812)
			(xy 437.221213 -52.780773) (xy 437.202614 -52.773054) (xy 437.195214 -52.766214) (xy 434.989986 -50.560986)
			(xy 434.983132 -50.553591) (xy 434.97539 -50.534992) (xy 434.975 -50.524918) (xy 434.975 -47.137066)
			(xy 434.974571 -47.126999) (xy 434.966847 -47.108403) (xy 434.960014 -47.100998) (xy 434.214016 -46.355)
			(xy 433.197 -46.355) (xy 432.181 -47.371) (xy 433.094382 -47.371) (xy 433.098453 -47.315378) (xy 433.110579 -47.260941)
			(xy 433.130502 -47.20885) (xy 433.157798 -47.160215) (xy 433.191884 -47.116072) (xy 433.232033 -47.077363)
			(xy 433.277391 -47.044912) (xy 433.326991 -47.019411) (xy 433.379775 -47.001404) (xy 433.434618 -46.991274)
			(xy 433.490352 -46.989237) (xy 433.545789 -46.995337) (xy 433.599746 -47.009443) (xy 433.651075 -47.031255)
			(xy 433.698681 -47.060309) (xy 433.741549 -47.095984) (xy 433.778766 -47.137521) (xy 433.809539 -47.184034)
			(xy 433.833211 -47.234531) (xy 433.849279 -47.287938) (xy 433.857399 -47.343114) (xy 433.857908 -47.371)
			(xy 433.857399 -47.398886) (xy 433.849279 -47.454062) (xy 433.833211 -47.507469) (xy 433.809539 -47.557966)
			(xy 433.778766 -47.604479) (xy 433.741549 -47.646016) (xy 433.698681 -47.681691) (xy 433.651075 -47.710745)
			(xy 433.599746 -47.732557) (xy 433.545789 -47.746663) (xy 433.490352 -47.752763) (xy 433.434618 -47.750726)
			(xy 433.379775 -47.740596) (xy 433.326991 -47.722589) (xy 433.277391 -47.697088) (xy 433.232033 -47.664637)
			(xy 433.191884 -47.625928) (xy 433.157798 -47.581785) (xy 433.130502 -47.53315) (xy 433.110579 -47.481059)
			(xy 433.098453 -47.426622) (xy 433.094382 -47.371) (xy 432.181 -47.371) (xy 431.546 -48.006) (xy 427.101 -48.006)
			(xy 426.593 -47.498) (xy 416.179 -47.498) (xy 411.48 -42.799) (xy 411.48 -38.608) (xy 411.820614 -38.267386)
			(xy 411.828009 -38.260532) (xy 411.846608 -38.25279) (xy 411.856682 -38.2524) (xy 413.414718 -38.2524)
			(xy 413.424787 -38.251973) (xy 413.443386 -38.244254) (xy 413.450786 -38.237414) (xy 413.497014 -38.191186)
			(xy 413.503868 -38.183791) (xy 413.51161 -38.165192) (xy 413.512 -38.155118) (xy 413.512 -37.790882)
			(xy 413.511573 -37.780813) (xy 413.503854 -37.762214) (xy 413.497014 -37.754814) (xy 413.476186 -37.733986)
			(xy 413.468791 -37.727132) (xy 413.450192 -37.71939) (xy 413.440118 -37.719) (xy 412.059882 -37.719)
			(xy 412.049813 -37.718573) (xy 412.031214 -37.710854) (xy 412.023814 -37.704014) (xy 411.901386 -37.581586)
			(xy 411.894532 -37.574191) (xy 411.88679 -37.555592) (xy 411.8864 -37.545518) (xy 411.8864 -35.7378)
			(xy 412.0642 -35.56) (xy 413.440118 -35.56) (xy 413.450187 -35.559573) (xy 413.468786 -35.551854)
			(xy 413.476186 -35.545014) (xy 413.497014 -35.524186) (xy 413.503868 -35.516791) (xy 413.51161 -35.498192)
			(xy 413.512 -35.488118) (xy 413.512 -27.9654) (xy 414.461198 -27.016202) (xy 414.461198 -23.809198)
			(xy 413.4612 -22.8092) (xy 413.4612 -16.937482) (xy 413.460773 -16.927413) (xy 413.453054 -16.908814)
			(xy 413.446214 -16.901414) (xy 405.195786 -8.650986) (xy 405.188391 -8.644132) (xy 405.169792 -8.63639)
			(xy 405.159718 -8.636) (xy 380.132082 -8.636) (xy 380.122013 -8.636427) (xy 380.103414 -8.644146)
			(xy 380.096014 -8.650986) (xy 379.668532 -9.078468) (xy 379.661166 -9.08558) (xy 379.653546 -9.104376)
			(xy 379.653546 -10.977372) (xy 379.654014 -10.987246) (xy 379.661466 -11.005535) (xy 379.668024 -11.012932)
			(xy 381.412242 -12.75715) (xy 381.430832 -12.776444) (xy 381.462322 -12.819791) (xy 381.486641 -12.867531)
			(xy 381.503189 -12.918488) (xy 381.511558 -12.971407) (xy 381.512064 -12.998196) (xy 381.512064 -15.35049)
			(xy 381.512487 -15.36056) (xy 381.520206 -15.379161) (xy 381.52705 -15.386558) (xy 382.04394 -15.903448)
			(xy 382.053025 -15.911615) (xy 382.076253 -15.919055) (xy 382.08839 -15.917672) (xy 382.100328 -15.91564)
			(xy 382.105408 -15.913608) (xy 382.135628 -15.901966) (xy 382.198281 -15.885578) (xy 382.262512 -15.877304)
			(xy 382.294892 -15.876778) (xy 382.2954 -15.876778) (xy 382.327217 -15.877277) (xy 382.39035 -15.885253)
			(xy 382.451986 -15.901078) (xy 382.511152 -15.924504) (xy 382.566915 -15.95516) (xy 382.618397 -15.992564)
			(xy 382.664785 -16.036125) (xy 382.705347 -16.085156) (xy 382.739444 -16.138885) (xy 382.766539 -16.196463)
			(xy 382.786203 -16.256983) (xy 382.798127 -16.319491) (xy 382.802123 -16.383) (xy 382.798127 -16.446509)
			(xy 382.786203 -16.509017) (xy 382.766539 -16.569537) (xy 382.739444 -16.627115) (xy 382.705347 -16.680844)
			(xy 382.664785 -16.729875) (xy 382.618397 -16.773436) (xy 382.566915 -16.81084) (xy 382.511152 -16.841496)
			(xy 382.451986 -16.864922) (xy 382.39035 -16.880747) (xy 382.327217 -16.888723) (xy 382.2954 -16.889222)
			(xy 382.263557 -16.888705) (xy 382.200381 -16.880648) (xy 382.138713 -16.864736) (xy 382.079525 -16.841221)
			(xy 382.023751 -16.810473) (xy 381.972271 -16.772978) (xy 381.925897 -16.729325) (xy 381.905256 -16.705072)
			(xy 381.904748 -16.704564) (xy 381.901954 -16.701262) (xy 381.901446 -16.700754) (xy 381.899668 -16.698722)
			(xy 381.88392 -16.68526) (xy 381.879094 -16.68272) (xy 381.857621 -16.670614) (xy 381.818099 -16.641157)
			(xy 381.800354 -16.624046) (xy 381.219202 -16.04264) (xy 381.211767 -16.035941) (xy 381.193273 -16.028346)
			(xy 381.173281 -16.028395) (xy 381.154825 -16.036081) (xy 381.140706 -16.050236) (xy 381.133069 -16.068712)
			(xy 381.132588 -16.078708) (xy 381.132588 -16.129) (xy 381.132085 -16.163618) (xy 381.124047 -16.232385)
			(xy 381.10808 -16.299755) (xy 381.0844 -16.364815) (xy 381.053327 -16.426686) (xy 381.015282 -16.484532)
			(xy 380.970778 -16.537569) (xy 380.920418 -16.585081) (xy 380.864882 -16.626426) (xy 380.804922 -16.661044)
			(xy 380.741349 -16.688467) (xy 380.675022 -16.708324) (xy 380.606838 -16.720346) (xy 380.53772 -16.724372)
			(xy 380.468602 -16.720346) (xy 380.400418 -16.708324) (xy 380.334091 -16.688467) (xy 380.270518 -16.661044)
			(xy 380.210558 -16.626426) (xy 380.155022 -16.585081) (xy 380.104662 -16.537569) (xy 380.060158 -16.484532)
			(xy 380.022113 -16.426686) (xy 379.99104 -16.364815) (xy 379.96736 -16.299755) (xy 379.951393 -16.232385)
			(xy 379.943355 -16.163618) (xy 379.942852 -16.129) (xy 379.942852 -15.442946) (xy 379.942395 -15.433698)
			(xy 379.935748 -15.416431) (xy 379.923437 -15.402619) (xy 379.91542 -15.397988) (xy 379.907546 -15.393924)
			(xy 379.892306 -15.388844) (xy 379.883244 -15.386272) (xy 379.864449 -15.387311) (xy 379.85573 -15.390876)
			(xy 379.847856 -15.394432) (xy 379.84176 -15.39875) (xy 379.836881 -15.402242) (xy 379.828797 -15.411103)
			(xy 379.825758 -15.416276) (xy 379.822456 -15.422372) (xy 379.816868 -15.438628) (xy 379.816868 -16.511778)
			(xy 379.817226 -16.520858) (xy 379.823563 -16.537876) (xy 379.835474 -16.551583) (xy 379.843284 -16.556228)
			(xy 379.868705 -16.570644) (xy 379.915193 -16.606057) (xy 379.955727 -16.648153) (xy 379.989359 -16.695945)
			(xy 380.015298 -16.748313) (xy 380.032936 -16.804026) (xy 380.04186 -16.86178) (xy 380.04242 -16.891)
			(xy 380.041934 -16.918252) (xy 380.034178 -16.9722) (xy 380.02073 -17.018) (xy 395.908792 -17.018)
			(xy 395.912794 -16.884265) (xy 395.924787 -16.75101) (xy 395.944728 -16.61871) (xy 395.972546 -16.487839)
			(xy 396.00814 -16.358866) (xy 396.051384 -16.232253) (xy 396.102122 -16.108452) (xy 396.160173 -15.987907)
			(xy 396.22533 -15.87105) (xy 396.297358 -15.758299) (xy 396.376 -15.650057) (xy 396.460975 -15.546712)
			(xy 396.551979 -15.448634) (xy 396.648684 -15.356173) (xy 396.750747 -15.269662) (xy 396.8578 -15.189409)
			(xy 396.969461 -15.115702) (xy 397.085331 -15.048805) (xy 397.204994 -14.988957) (xy 397.328021 -14.936372)
			(xy 397.453974 -14.891239) (xy 397.5824 -14.85372) (xy 397.712839 -14.823948) (xy 397.844826 -14.80203)
			(xy 397.977888 -14.788044) (xy 398.111548 -14.782042) (xy 398.245327 -14.784043) (xy 398.378747 -14.794042)
			(xy 398.511331 -14.812001) (xy 398.642603 -14.837858) (xy 398.772094 -14.871519) (xy 398.89934 -14.912864)
			(xy 399.023886 -14.961744) (xy 399.145285 -15.017986) (xy 399.263104 -15.081387) (xy 399.376921 -15.15172)
			(xy 399.486327 -15.228735) (xy 399.590932 -15.312154) (xy 399.69036 -15.40168) (xy 399.784257 -15.496992)
			(xy 399.872285 -15.597749) (xy 399.954131 -15.70359) (xy 400.0295 -15.814136) (xy 400.098123 -15.928991)
			(xy 400.159754 -16.047745) (xy 400.214173 -16.169973) (xy 400.261185 -16.295236) (xy 400.300622 -16.423086)
			(xy 400.332342 -16.553066) (xy 400.356232 -16.68471) (xy 400.372206 -16.817548) (xy 400.380208 -16.951103)
			(xy 400.380708 -17.018) (xy 400.380208 -17.084897) (xy 400.372206 -17.218452) (xy 400.356232 -17.35129)
			(xy 400.332342 -17.482934) (xy 400.300622 -17.612914) (xy 400.261185 -17.740764) (xy 400.214173 -17.866027)
			(xy 400.159754 -17.988255) (xy 400.098123 -18.107009) (xy 400.0295 -18.221864) (xy 399.954131 -18.33241)
			(xy 399.872285 -18.438251) (xy 399.784257 -18.539008) (xy 399.69036 -18.63432) (xy 399.590932 -18.723846)
			(xy 399.486327 -18.807265) (xy 399.376921 -18.88428) (xy 399.263104 -18.954613) (xy 399.145285 -19.018014)
			(xy 399.023886 -19.074256) (xy 398.89934 -19.123136) (xy 398.772094 -19.164481) (xy 398.642603 -19.198142)
			(xy 398.511331 -19.223999) (xy 398.378747 -19.241958) (xy 398.245327 -19.251957) (xy 398.111548 -19.253958)
			(xy 397.977888 -19.247956) (xy 397.844826 -19.23397) (xy 397.712839 -19.212052) (xy 397.5824 -19.18228)
			(xy 397.453974 -19.144761) (xy 397.328021 -19.099628) (xy 397.204994 -19.047043) (xy 397.085331 -18.987195)
			(xy 396.969461 -18.920298) (xy 396.8578 -18.846591) (xy 396.750747 -18.766338) (xy 396.648684 -18.679827)
			(xy 396.551979 -18.587366) (xy 396.460975 -18.489288) (xy 396.376 -18.385943) (xy 396.297358 -18.277701)
			(xy 396.22533 -18.16495) (xy 396.160173 -18.048093) (xy 396.102122 -17.927548) (xy 396.051384 -17.803747)
			(xy 396.00814 -17.677134) (xy 395.972546 -17.548161) (xy 395.944728 -17.41729) (xy 395.924787 -17.28499)
			(xy 395.912794 -17.151735) (xy 395.908792 -17.018) (xy 380.02073 -17.018) (xy 380.018823 -17.024495)
			(xy 379.996182 -17.074073) (xy 379.966716 -17.119925) (xy 379.931024 -17.161116) (xy 379.889834 -17.196809)
			(xy 379.843984 -17.226276) (xy 379.794407 -17.248919) (xy 379.742112 -17.264275) (xy 379.688164 -17.272033)
			(xy 379.660912 -17.272508) (xy 379.631737 -17.271955) (xy 379.574067 -17.263071) (xy 379.518423 -17.24551)
			(xy 379.466101 -17.21968) (xy 379.418323 -17.186184) (xy 379.376203 -17.145803) (xy 379.340723 -17.09948)
			(xy 379.312711 -17.048294) (xy 379.302264 -17.021048) (xy 379.298454 -17.01038) (xy 379.234954 -16.947134)
			(xy 379.220972 -16.932711) (xy 379.196141 -16.901132) (xy 379.185424 -16.884142) (xy 379.182122 -16.878808)
			(xy 379.177804 -16.87449) (xy 379.171573 -16.868795) (xy 379.156412 -16.861398) (xy 379.148086 -16.860012)
			(xy 379.068838 -16.850106) (xy 379.06833 -16.850106) (xy 379.057662 -16.848582) (xy 379.03531 -16.855948)
			(xy 378.98197 -16.909288) (xy 378.97435 -16.92529) (xy 378.973588 -16.93418) (xy 378.970195 -16.964725)
			(xy 378.956263 -17.024581) (xy 378.934447 -17.082036) (xy 378.90514 -17.136054) (xy 378.868868 -17.185666)
			(xy 378.826283 -17.229978) (xy 378.778153 -17.268193) (xy 378.725342 -17.299624) (xy 378.6688 -17.323707)
			(xy 378.609544 -17.340007) (xy 378.54864 -17.348232) (xy 378.517912 -17.348708) (xy 378.487942 -17.34824)
			(xy 378.428516 -17.340417) (xy 378.370619 -17.324905) (xy 378.315242 -17.301969) (xy 378.263333 -17.272)
			(xy 378.215779 -17.235512) (xy 378.173396 -17.19313) (xy 378.136906 -17.145577) (xy 378.106937 -17.093669)
			(xy 378.083998 -17.038292) (xy 378.068485 -16.980396) (xy 378.060661 -16.92097) (xy 378.060204 -16.891)
			(xy 378.060682 -16.861116) (xy 378.068447 -16.801856) (xy 378.083857 -16.74411) (xy 378.106652 -16.688861)
			(xy 378.136442 -16.637048) (xy 378.172722 -16.589552) (xy 378.214875 -16.547182) (xy 378.262183 -16.510657)
			(xy 378.313841 -16.4806) (xy 378.368972 -16.457521) (xy 378.426638 -16.441812) (xy 378.45619 -16.437356)
			(xy 378.47524 -16.434816) (xy 378.500132 -16.406114) (xy 378.500132 -13.50391) (xy 378.499878 -13.498068)
			(xy 378.498862 -13.490702) (xy 378.497601 -13.482222) (xy 378.490211 -13.466763) (xy 378.484384 -13.460476)
			(xy 372.361714 -7.337806) (xy 372.343118 -7.318514) (xy 372.311616 -7.275171) (xy 372.287285 -7.227432)
			(xy 372.270726 -7.176473) (xy 372.262346 -7.123551) (xy 372.261892 -7.09676) (xy 372.261892 -5.388864)
			(xy 372.261638 -5.383022) (xy 372.260622 -5.375656) (xy 372.259353 -5.36718) (xy 372.251949 -5.351736)
			(xy 372.246144 -5.34543) (xy 372.19636 -5.295646) (xy 372.189248 -5.28828) (xy 372.170452 -5.28066)
			(xy 372.160038 -5.28066) (xy 372.12867 -5.280284) (xy 372.066187 -5.274647) (xy 372.004451 -5.263484)
			(xy 371.97411 -5.255514) (xy 371.96268 -5.252466) (xy 371.939312 -5.256784) (xy 371.865398 -5.313172)
			(xy 371.865144 -5.313426) (xy 371.857016 -5.319268) (xy 371.851174 -5.330444) (xy 371.84838 -5.336032)
			(xy 371.845332 -5.34797) (xy 371.845332 -6.952234) (xy 371.844903 -6.962302) (xy 371.837184 -6.980901)
			(xy 371.830346 -6.988302) (xy 369.970812 -8.847836) (xy 369.963417 -8.854691) (xy 369.944819 -8.86244)
			(xy 369.934744 -8.862822) (xy 362.668566 -8.862822) (xy 362.66247 -8.863076) (xy 362.652818 -8.864346)
			(xy 362.644403 -8.865633) (xy 362.629082 -8.873029) (xy 362.622846 -8.878824) (xy 362.286296 -9.215374)
			(xy 362.278898 -9.222223) (xy 362.2603 -9.22996) (xy 362.250228 -9.23036) (xy 222.014796 -9.23036)
			(xy 222.004786 -9.230848) (xy 221.986289 -9.238507) (xy 221.972127 -9.252658) (xy 221.964455 -9.27115)
			(xy 221.963996 -9.28116) (xy 221.963996 -25.730454) (xy 221.964408 -25.740482) (xy 221.972069 -25.759015)
			(xy 221.986243 -25.773203) (xy 222.004769 -25.780883) (xy 222.014796 -25.781254) (xy 236.031278 -25.781254)
			(xy 236.03839 -25.782016) (xy 236.04601 -25.783032) (xy 236.061504 -25.781) (xy 236.070902 -25.776936)
			(xy 236.079271 -25.772644) (xy 236.092426 -25.759225) (xy 236.096556 -25.750774) (xy 236.097318 -25.748488)
			(xy 236.128306 -25.664922) (xy 236.131354 -25.657048) (xy 236.131862 -25.64892) (xy 236.132065 -25.641559)
			(xy 236.128715 -25.627227) (xy 236.125258 -25.620726) (xy 236.119416 -25.610312) (xy 236.111288 -25.599898)
			(xy 236.102906 -25.591516) (xy 236.033064 -25.530172) (xy 235.89833 -25.402073) (xy 235.769499 -25.268039)
			(xy 235.646832 -25.128341) (xy 235.530578 -24.983263) (xy 235.420972 -24.833099) (xy 235.318237 -24.678154)
			(xy 235.22258 -24.518741) (xy 235.134197 -24.355184) (xy 235.053265 -24.187814) (xy 234.979949 -24.01697)
			(xy 234.914399 -23.843) (xy 234.856745 -23.666255) (xy 234.807107 -23.487094) (xy 234.765583 -23.30588)
			(xy 234.732259 -23.122981) (xy 234.707201 -22.938767) (xy 234.690461 -22.753612) (xy 234.682073 -22.567891)
			(xy 234.681522 -22.474936) (xy 234.682027 -22.383593) (xy 234.690108 -22.201087) (xy 234.706253 -22.019117)
			(xy 234.730433 -21.838039) (xy 234.762598 -21.658208) (xy 234.802686 -21.479975) (xy 234.850619 -21.30369)
			(xy 234.906302 -21.129698) (xy 234.969627 -20.95834) (xy 235.04047 -20.78995) (xy 235.118692 -20.624859)
			(xy 235.204141 -20.463389) (xy 235.296647 -20.305857) (xy 235.396032 -20.152571) (xy 235.502099 -20.003831)
			(xy 235.614642 -19.859928) (xy 235.73344 -19.721145) (xy 235.858261 -19.587752) (xy 235.98886 -19.460011)
			(xy 236.124982 -19.338172) (xy 236.266359 -19.222473) (xy 236.412716 -19.113141) (xy 236.563766 -19.01039)
			(xy 236.719213 -18.914421) (xy 236.878753 -18.825421) (xy 237.042074 -18.743566) (xy 237.208855 -18.669015)
			(xy 237.378771 -18.601915) (xy 237.551488 -18.542396) (xy 237.72667 -18.490575) (xy 237.903972 -18.446554)
			(xy 238.083047 -18.410418) (xy 238.263546 -18.382239) (xy 238.445115 -18.362072) (xy 238.627398 -18.349956)
			(xy 238.810038 -18.345915) (xy 238.992678 -18.349956) (xy 239.174961 -18.362072) (xy 239.35653 -18.382239)
			(xy 239.537029 -18.410418) (xy 239.716104 -18.446554) (xy 239.893406 -18.490575) (xy 240.068588 -18.542396)
			(xy 240.241305 -18.601915) (xy 240.411221 -18.669015) (xy 240.578002 -18.743566) (xy 240.741323 -18.825421)
			(xy 240.900863 -18.914421) (xy 241.05631 -19.01039) (xy 241.20736 -19.113141) (xy 241.353717 -19.222473)
			(xy 241.495094 -19.338172) (xy 241.631216 -19.460011) (xy 241.761815 -19.587752) (xy 241.886636 -19.721145)
			(xy 242.005434 -19.859928) (xy 242.117977 -20.003831) (xy 242.224044 -20.152571) (xy 242.323429 -20.305857)
			(xy 242.415935 -20.463389) (xy 242.501384 -20.624859) (xy 242.579606 -20.78995) (xy 242.650449 -20.95834)
			(xy 242.713774 -21.129698) (xy 242.769457 -21.30369) (xy 242.81739 -21.479975) (xy 242.857478 -21.658208)
			(xy 242.889643 -21.838039) (xy 242.913823 -22.019117) (xy 242.929968 -22.201087) (xy 242.938049 -22.383593)
			(xy 242.938554 -22.474936) (xy 242.93803 -22.56807) (xy 242.929628 -22.754147) (xy 242.912841 -22.939657)
			(xy 242.887705 -23.124221) (xy 242.85427 -23.307463) (xy 242.812605 -23.48901) (xy 242.762794 -23.668494)
			(xy 242.704938 -23.845548) (xy 242.639156 -24.019813) (xy 242.565581 -24.190934) (xy 242.484364 -24.358562)
			(xy 242.395668 -24.522357) (xy 242.299676 -24.681985) (xy 242.196581 -24.83712) (xy 242.086595 -24.987448)
			(xy 241.96994 -25.132663) (xy 241.846855 -25.272468) (xy 241.71759 -25.40658) (xy 241.582407 -25.534725)
			(xy 241.512344 -25.596088) (xy 241.51209 -25.596342) (xy 241.507772 -25.600152) (xy 241.501422 -25.608534)
			(xy 241.493548 -25.625044) (xy 241.491221 -25.630206) (xy 241.48865 -25.641229) (xy 241.488468 -25.646888)
			(xy 241.488722 -25.656032) (xy 241.522758 -25.748234) (xy 241.52682 -25.757712) (xy 241.541037 -25.772624)
			(xy 241.559957 -25.78078) (xy 241.570256 -25.781254) (xy 276.2123 -25.781254) (xy 276.22218 -25.780799)
			(xy 276.240488 -25.773366) (xy 276.24786 -25.766776) (xy 276.379432 -25.635204) (xy 276.386287 -25.627809)
			(xy 276.394033 -25.60921) (xy 276.394418 -25.599136) (xy 276.394418 -13.593064) (xy 276.394848 -13.582997)
			(xy 276.402574 -13.564404) (xy 276.409404 -13.556996) (xy 278.521414 -11.444986) (xy 278.528809 -11.438132)
			(xy 278.547408 -11.43039) (xy 278.557482 -11.43) (xy 302.543718 -11.43) (xy 302.553595 -11.42954)
			(xy 302.571894 -11.422097) (xy 302.579278 -11.415522) (xy 303.258728 -10.736072) (xy 303.266125 -10.729222)
			(xy 303.284723 -10.721487) (xy 303.294796 -10.721086) (xy 323.259196 -10.721086) (xy 323.269267 -10.721508)
			(xy 323.287874 -10.72922) (xy 323.295264 -10.736072) (xy 327.555606 -14.996414) (xy 327.563001 -15.003269)
			(xy 327.5816 -15.011015) (xy 327.591674 -15.0114) (xy 336.300318 -15.0114) (xy 336.310387 -15.011827)
			(xy 336.328986 -15.019546) (xy 336.336386 -15.026386) (xy 336.657188 -15.347188) (xy 355.071172 -15.347188)
			(xy 357.133398 -17.409414) (xy 357.143468 -17.409837) (xy 357.162072 -17.417553) (xy 357.169466 -17.4244)
			(xy 358.698034 -18.952968) (xy 380.346694 -18.952968) (xy 380.346694 -18.893032) (xy 380.354517 -18.83361)
			(xy 380.37003 -18.775717) (xy 380.392966 -18.720344) (xy 380.422933 -18.668438) (xy 380.45942 -18.620888)
			(xy 380.5018 -18.578508) (xy 380.54935 -18.542021) (xy 380.601256 -18.512054) (xy 380.656629 -18.489118)
			(xy 380.714522 -18.473605) (xy 380.773944 -18.465782) (xy 380.83388 -18.465782) (xy 380.893302 -18.473605)
			(xy 380.951195 -18.489118) (xy 381.006568 -18.512054) (xy 381.058474 -18.542021) (xy 381.106024 -18.578508)
			(xy 381.148404 -18.620888) (xy 381.184891 -18.668438) (xy 381.214858 -18.720344) (xy 381.237794 -18.775717)
			(xy 381.253307 -18.83361) (xy 381.26113 -18.893032) (xy 381.261524 -18.917158) (xy 381.564894 -18.917158)
			(xy 381.568965 -18.861536) (xy 381.581091 -18.807099) (xy 381.601014 -18.755008) (xy 381.62831 -18.706373)
			(xy 381.662396 -18.66223) (xy 381.702545 -18.623521) (xy 381.747903 -18.59107) (xy 381.797503 -18.565569)
			(xy 381.850287 -18.547562) (xy 381.90513 -18.537432) (xy 381.960864 -18.535395) (xy 382.016301 -18.541495)
			(xy 382.070258 -18.555601) (xy 382.121587 -18.577413) (xy 382.169193 -18.606467) (xy 382.212061 -18.642142)
			(xy 382.249278 -18.683679) (xy 382.280051 -18.730192) (xy 382.303723 -18.780689) (xy 382.319791 -18.834096)
			(xy 382.327911 -18.889272) (xy 382.32842 -18.917158) (xy 382.327911 -18.945044) (xy 382.319791 -19.00022)
			(xy 382.303723 -19.053627) (xy 382.280051 -19.104124) (xy 382.249278 -19.150637) (xy 382.212061 -19.192174)
			(xy 382.169193 -19.227849) (xy 382.121587 -19.256903) (xy 382.070258 -19.278715) (xy 382.016301 -19.292821)
			(xy 381.960864 -19.298921) (xy 381.90513 -19.296884) (xy 381.850287 -19.286754) (xy 381.797503 -19.268747)
			(xy 381.747903 -19.243246) (xy 381.702545 -19.210795) (xy 381.662396 -19.172086) (xy 381.62831 -19.127943)
			(xy 381.601014 -19.079308) (xy 381.581091 -19.027217) (xy 381.568965 -18.97278) (xy 381.564894 -18.917158)
			(xy 381.261524 -18.917158) (xy 381.26162 -18.923) (xy 381.26113 -18.952968) (xy 381.253307 -19.01239)
			(xy 381.237794 -19.070283) (xy 381.214858 -19.125656) (xy 381.184891 -19.177562) (xy 381.148404 -19.225112)
			(xy 381.106024 -19.267492) (xy 381.058474 -19.303979) (xy 381.006568 -19.333946) (xy 380.951195 -19.356882)
			(xy 380.893302 -19.372395) (xy 380.83388 -19.380218) (xy 380.773944 -19.380218) (xy 380.714522 -19.372395)
			(xy 380.656629 -19.356882) (xy 380.601256 -19.333946) (xy 380.54935 -19.303979) (xy 380.5018 -19.267492)
			(xy 380.45942 -19.225112) (xy 380.422933 -19.177562) (xy 380.392966 -19.125656) (xy 380.37003 -19.070283)
			(xy 380.354517 -19.01239) (xy 380.346694 -18.952968) (xy 358.698034 -18.952968) (xy 360.222034 -20.476968)
			(xy 378.002782 -20.476968) (xy 378.002782 -20.417032) (xy 378.010605 -20.35761) (xy 378.026118 -20.299717)
			(xy 378.049054 -20.244344) (xy 378.079021 -20.192438) (xy 378.115508 -20.144888) (xy 378.157888 -20.102508)
			(xy 378.205438 -20.066021) (xy 378.257344 -20.036054) (xy 378.312717 -20.013118) (xy 378.37061 -19.997605)
			(xy 378.430032 -19.989782) (xy 378.489968 -19.989782) (xy 378.54939 -19.997605) (xy 378.571651 -20.00357)
			(xy 386.295635 -20.00357) (xy 386.295635 -19.87443) (xy 386.303585 -19.745535) (xy 386.319455 -19.617375)
			(xy 386.343184 -19.490434) (xy 386.374683 -19.365195) (xy 386.413832 -19.242132) (xy 386.460483 -19.121713)
			(xy 386.514458 -19.004394) (xy 386.575553 -18.89062) (xy 386.643536 -18.780823) (xy 386.71815 -18.67542)
			(xy 386.799111 -18.57481) (xy 386.886111 -18.479375) (xy 386.978822 -18.389476) (xy 387.076892 -18.305455)
			(xy 387.179947 -18.227631) (xy 387.287598 -18.156299) (xy 387.399437 -18.091729) (xy 387.515038 -18.034167)
			(xy 387.633963 -17.98383) (xy 387.755762 -17.94091) (xy 387.879972 -17.905569) (xy 388.006121 -17.877942)
			(xy 388.133733 -17.858133) (xy 388.262322 -17.846217) (xy 388.3914 -17.842241) (xy 388.520478 -17.846217)
			(xy 388.649067 -17.858133) (xy 388.776679 -17.877942) (xy 388.902828 -17.905569) (xy 389.027038 -17.94091)
			(xy 389.148837 -17.98383) (xy 389.267762 -18.034167) (xy 389.383363 -18.091729) (xy 389.495202 -18.156299)
			(xy 389.602853 -18.227631) (xy 389.705908 -18.305455) (xy 389.803978 -18.389476) (xy 389.896689 -18.479375)
			(xy 389.983689 -18.57481) (xy 390.06465 -18.67542) (xy 390.139264 -18.780823) (xy 390.207247 -18.89062)
			(xy 390.268342 -19.004394) (xy 390.322317 -19.121713) (xy 390.368968 -19.242132) (xy 390.408117 -19.365195)
			(xy 390.439616 -19.490434) (xy 390.463345 -19.617375) (xy 390.479215 -19.745535) (xy 390.487165 -19.87443)
			(xy 390.487662 -19.939) (xy 390.487165 -20.00357) (xy 390.479215 -20.132465) (xy 390.463345 -20.260625)
			(xy 390.439616 -20.387566) (xy 390.408117 -20.512805) (xy 390.368968 -20.635868) (xy 390.322317 -20.756287)
			(xy 390.268342 -20.873606) (xy 390.207247 -20.98738) (xy 390.139264 -21.097177) (xy 390.06465 -21.20258)
			(xy 389.983689 -21.30319) (xy 389.896689 -21.398625) (xy 389.803978 -21.488524) (xy 389.705908 -21.572545)
			(xy 389.602853 -21.650369) (xy 389.495202 -21.721701) (xy 389.383363 -21.786271) (xy 389.267762 -21.843833)
			(xy 389.148837 -21.89417) (xy 389.027038 -21.93709) (xy 388.902828 -21.972431) (xy 388.776679 -22.000058)
			(xy 388.649067 -22.019867) (xy 388.520478 -22.031783) (xy 388.3914 -22.03576) (xy 388.262322 -22.031783)
			(xy 388.133733 -22.019867) (xy 388.006121 -22.000058) (xy 387.879972 -21.972431) (xy 387.755762 -21.93709)
			(xy 387.633963 -21.89417) (xy 387.515038 -21.843833) (xy 387.399437 -21.786271) (xy 387.287598 -21.721701)
			(xy 387.179947 -21.650369) (xy 387.076892 -21.572545) (xy 386.978822 -21.488524) (xy 386.886111 -21.398625)
			(xy 386.799111 -21.30319) (xy 386.71815 -21.20258) (xy 386.643536 -21.097177) (xy 386.575553 -20.98738)
			(xy 386.514458 -20.873606) (xy 386.460483 -20.756287) (xy 386.413832 -20.635868) (xy 386.374683 -20.512805)
			(xy 386.343184 -20.387566) (xy 386.319455 -20.260625) (xy 386.303585 -20.132465) (xy 386.295635 -20.00357)
			(xy 378.571651 -20.00357) (xy 378.607283 -20.013118) (xy 378.662656 -20.036054) (xy 378.714562 -20.066021)
			(xy 378.762112 -20.102508) (xy 378.804492 -20.144888) (xy 378.840979 -20.192438) (xy 378.870946 -20.244344)
			(xy 378.893882 -20.299717) (xy 378.909395 -20.35761) (xy 378.917218 -20.417032) (xy 378.917708 -20.447)
			(xy 378.917218 -20.476968) (xy 378.909395 -20.53639) (xy 378.893882 -20.594283) (xy 378.870946 -20.649656)
			(xy 378.840979 -20.701562) (xy 378.804492 -20.749112) (xy 378.762112 -20.791492) (xy 378.714562 -20.827979)
			(xy 378.662656 -20.857946) (xy 378.607283 -20.880882) (xy 378.54939 -20.896395) (xy 378.489968 -20.904218)
			(xy 378.430032 -20.904218) (xy 378.37061 -20.896395) (xy 378.312717 -20.880882) (xy 378.257344 -20.857946)
			(xy 378.205438 -20.827979) (xy 378.157888 -20.791492) (xy 378.115508 -20.749112) (xy 378.079021 -20.701562)
			(xy 378.049054 -20.649656) (xy 378.026118 -20.594283) (xy 378.010605 -20.53639) (xy 378.002782 -20.476968)
			(xy 360.222034 -20.476968) (xy 360.954066 -21.209) (xy 379.278894 -21.209) (xy 379.282965 -21.153378)
			(xy 379.295091 -21.098941) (xy 379.315014 -21.04685) (xy 379.34231 -20.998215) (xy 379.376396 -20.954072)
			(xy 379.416545 -20.915363) (xy 379.461903 -20.882912) (xy 379.511503 -20.857411) (xy 379.564287 -20.839404)
			(xy 379.61913 -20.829274) (xy 379.674864 -20.827237) (xy 379.730301 -20.833337) (xy 379.784258 -20.847443)
			(xy 379.835587 -20.869255) (xy 379.883193 -20.898309) (xy 379.926061 -20.933984) (xy 379.963278 -20.975521)
			(xy 379.994051 -21.022034) (xy 380.017723 -21.072531) (xy 380.033791 -21.125938) (xy 380.041911 -21.181114)
			(xy 380.04242 -21.209) (xy 380.041911 -21.236886) (xy 380.033791 -21.292062) (xy 380.017723 -21.345469)
			(xy 379.994051 -21.395966) (xy 379.963278 -21.442479) (xy 379.926061 -21.484016) (xy 379.883193 -21.519691)
			(xy 379.835587 -21.548745) (xy 379.784258 -21.570557) (xy 379.730301 -21.584663) (xy 379.674864 -21.590763)
			(xy 379.61913 -21.588726) (xy 379.564287 -21.578596) (xy 379.511503 -21.560589) (xy 379.461903 -21.535088)
			(xy 379.416545 -21.502637) (xy 379.376396 -21.463928) (xy 379.34231 -21.419785) (xy 379.315014 -21.37115)
			(xy 379.295091 -21.319059) (xy 379.282965 -21.264622) (xy 379.278894 -21.209) (xy 360.954066 -21.209)
			(xy 364.286034 -24.540968) (xy 393.496782 -24.540968) (xy 393.496782 -24.481032) (xy 393.504605 -24.42161)
			(xy 393.520118 -24.363717) (xy 393.543054 -24.308344) (xy 393.573021 -24.256438) (xy 393.609508 -24.208888)
			(xy 393.651888 -24.166508) (xy 393.699438 -24.130021) (xy 393.751344 -24.100054) (xy 393.806717 -24.077118)
			(xy 393.86461 -24.061605) (xy 393.924032 -24.053782) (xy 393.983968 -24.053782) (xy 394.04339 -24.061605)
			(xy 394.101283 -24.077118) (xy 394.156656 -24.100054) (xy 394.208562 -24.130021) (xy 394.256112 -24.166508)
			(xy 394.298492 -24.208888) (xy 394.334979 -24.256438) (xy 394.364946 -24.308344) (xy 394.387882 -24.363717)
			(xy 394.403395 -24.42161) (xy 394.411218 -24.481032) (xy 394.411708 -24.511) (xy 394.411218 -24.540968)
			(xy 394.403395 -24.60039) (xy 394.387882 -24.658283) (xy 394.364946 -24.713656) (xy 394.334979 -24.765562)
			(xy 394.298492 -24.813112) (xy 394.256112 -24.855492) (xy 394.208562 -24.891979) (xy 394.156656 -24.921946)
			(xy 394.101283 -24.944882) (xy 394.04339 -24.960395) (xy 393.983968 -24.968218) (xy 393.924032 -24.968218)
			(xy 393.86461 -24.960395) (xy 393.806717 -24.944882) (xy 393.751344 -24.921946) (xy 393.699438 -24.891979)
			(xy 393.651888 -24.855492) (xy 393.609508 -24.813112) (xy 393.573021 -24.765562) (xy 393.543054 -24.713656)
			(xy 393.520118 -24.658283) (xy 393.504605 -24.60039) (xy 393.496782 -24.540968) (xy 364.286034 -24.540968)
			(xy 364.872016 -25.12695) (xy 387.501382 -25.12695) (xy 387.505453 -25.071328) (xy 387.517579 -25.016891)
			(xy 387.537502 -24.9648) (xy 387.564798 -24.916165) (xy 387.598884 -24.872022) (xy 387.639033 -24.833313)
			(xy 387.684391 -24.800862) (xy 387.733991 -24.775361) (xy 387.786775 -24.757354) (xy 387.841618 -24.747224)
			(xy 387.897352 -24.745187) (xy 387.952789 -24.751287) (xy 388.006746 -24.765393) (xy 388.058075 -24.787205)
			(xy 388.105681 -24.816259) (xy 388.148549 -24.851934) (xy 388.185766 -24.893471) (xy 388.216539 -24.939984)
			(xy 388.240211 -24.990481) (xy 388.256279 -25.043888) (xy 388.264399 -25.099064) (xy 388.264908 -25.12695)
			(xy 388.264399 -25.154836) (xy 388.256279 -25.210012) (xy 388.240211 -25.263419) (xy 388.216539 -25.313916)
			(xy 388.185766 -25.360429) (xy 388.148549 -25.401966) (xy 388.105681 -25.437641) (xy 388.058075 -25.466695)
			(xy 388.006746 -25.488507) (xy 387.952789 -25.502613) (xy 387.897352 -25.508713) (xy 387.841618 -25.506676)
			(xy 387.786775 -25.496546) (xy 387.733991 -25.478539) (xy 387.684391 -25.453038) (xy 387.639033 -25.420587)
			(xy 387.598884 -25.381878) (xy 387.564798 -25.337735) (xy 387.537502 -25.2891) (xy 387.517579 -25.237009)
			(xy 387.505453 -25.182572) (xy 387.501382 -25.12695) (xy 364.872016 -25.12695) (xy 369.560094 -29.815028)
			(xy 369.567489 -29.821883) (xy 369.586087 -29.829631) (xy 369.596162 -29.830014) (xy 385.409186 -29.830014)
			(xy 385.414141 -29.830131) (xy 385.423863 -29.832048) (xy 385.42849 -29.833824) (xy 385.44627 -29.84119)
			(xy 385.450898 -29.842965) (xy 385.460619 -29.844889) (xy 385.465574 -29.845) (xy 385.490466 -29.845)
			(xy 385.49999 -29.844609) (xy 385.517725 -29.837658) (xy 385.531691 -29.824704) (xy 385.536186 -29.816298)
			(xy 385.574286 -29.737558) (xy 385.577597 -29.729949) (xy 385.579664 -29.713494) (xy 385.57835 -29.7053)
			(xy 385.577334 -29.700728) (xy 385.569714 -29.679392) (xy 385.56438 -29.672788) (xy 385.523207 -29.620693)
			(xy 385.446589 -29.512225) (xy 385.376783 -29.399253) (xy 385.314051 -29.282204) (xy 385.258632 -29.161521)
			(xy 385.210735 -29.03766) (xy 385.170541 -28.91109) (xy 385.138202 -28.782289) (xy 385.11384 -28.651743)
			(xy 385.097547 -28.519948) (xy 385.089385 -28.3874) (xy 385.088892 -28.321) (xy 385.089384 -28.255761)
			(xy 385.097262 -28.125522) (xy 385.11299 -27.995997) (xy 385.136509 -27.867657) (xy 385.167734 -27.740971)
			(xy 385.206551 -27.616402) (xy 385.252819 -27.494403) (xy 385.306369 -27.375421) (xy 385.367005 -27.25989)
			(xy 385.434505 -27.14823) (xy 385.508625 -27.040849) (xy 385.589092 -26.93814) (xy 385.675615 -26.840476)
			(xy 385.767876 -26.748215) (xy 385.86554 -26.661692) (xy 385.968249 -26.581225) (xy 386.07563 -26.507105)
			(xy 386.18729 -26.439605) (xy 386.302821 -26.378969) (xy 386.421803 -26.325419) (xy 386.543802 -26.279151)
			(xy 386.668371 -26.240334) (xy 386.795057 -26.209109) (xy 386.923397 -26.18559) (xy 387.052922 -26.169862)
			(xy 387.183161 -26.161984) (xy 387.313639 -26.161984) (xy 387.443878 -26.169862) (xy 387.573403 -26.18559)
			(xy 387.701743 -26.209109) (xy 387.828429 -26.240334) (xy 387.952998 -26.279151) (xy 388.074997 -26.325419)
			(xy 388.193979 -26.378969) (xy 388.30951 -26.439605) (xy 388.315526 -26.443242) (xy 411.952183 -26.443242)
			(xy 411.952183 -26.358278) (xy 411.960259 -26.2737) (xy 411.976339 -26.190273) (xy 412.000276 -26.108751)
			(xy 412.031853 -26.029874) (xy 412.070786 -25.954356) (xy 412.11672 -25.882881) (xy 412.169241 -25.816095)
			(xy 412.227872 -25.754604) (xy 412.292083 -25.698966) (xy 412.361292 -25.649682) (xy 412.434872 -25.607201)
			(xy 412.512157 -25.571906) (xy 412.592447 -25.544117) (xy 412.675015 -25.524086) (xy 412.759113 -25.511995)
			(xy 412.84398 -25.507952) (xy 412.928847 -25.511995) (xy 413.012945 -25.524086) (xy 413.095513 -25.544117)
			(xy 413.175803 -25.571906) (xy 413.253088 -25.607201) (xy 413.326668 -25.649682) (xy 413.395877 -25.698966)
			(xy 413.460088 -25.754604) (xy 413.518719 -25.816095) (xy 413.57124 -25.882881) (xy 413.617174 -25.954356)
			(xy 413.656107 -26.029874) (xy 413.687684 -26.108751) (xy 413.711621 -26.190273) (xy 413.727701 -26.2737)
			(xy 413.735777 -26.358278) (xy 413.736282 -26.40076) (xy 413.735777 -26.443242) (xy 413.727701 -26.52782)
			(xy 413.711621 -26.611247) (xy 413.687684 -26.692769) (xy 413.656107 -26.771646) (xy 413.617174 -26.847164)
			(xy 413.57124 -26.918639) (xy 413.518719 -26.985425) (xy 413.460088 -27.046916) (xy 413.395877 -27.102554)
			(xy 413.326668 -27.151838) (xy 413.253088 -27.194319) (xy 413.175803 -27.229614) (xy 413.095513 -27.257403)
			(xy 413.012945 -27.277434) (xy 412.928847 -27.289525) (xy 412.84398 -27.293568) (xy 412.759113 -27.289525)
			(xy 412.675015 -27.277434) (xy 412.592447 -27.257403) (xy 412.512157 -27.229614) (xy 412.434872 -27.194319)
			(xy 412.361292 -27.151838) (xy 412.292083 -27.102554) (xy 412.227872 -27.046916) (xy 412.169241 -26.985425)
			(xy 412.11672 -26.918639) (xy 412.070786 -26.847164) (xy 412.031853 -26.771646) (xy 412.000276 -26.692769)
			(xy 411.976339 -26.611247) (xy 411.960259 -26.52782) (xy 411.952183 -26.443242) (xy 388.315526 -26.443242)
			(xy 388.42117 -26.507105) (xy 388.528551 -26.581225) (xy 388.63126 -26.661692) (xy 388.728924 -26.748215)
			(xy 388.821185 -26.840476) (xy 388.907708 -26.93814) (xy 388.988175 -27.040849) (xy 389.062295 -27.14823)
			(xy 389.129795 -27.25989) (xy 389.190431 -27.375421) (xy 389.243981 -27.494403) (xy 389.290249 -27.616402)
			(xy 389.329066 -27.740971) (xy 389.360291 -27.867657) (xy 389.38381 -27.995997) (xy 389.399538 -28.125522)
			(xy 389.407416 -28.255761) (xy 389.407908 -28.321) (xy 389.407398 -28.387785) (xy 389.399141 -28.5211)
			(xy 389.382659 -28.65365) (xy 389.358015 -28.784927) (xy 389.325302 -28.91443) (xy 389.284647 -29.041662)
			(xy 389.236205 -29.166139) (xy 389.222975 -29.19476) (xy 411.680912 -29.19476) (xy 411.684983 -29.139138)
			(xy 411.697109 -29.084701) (xy 411.717032 -29.03261) (xy 411.744328 -28.983975) (xy 411.778414 -28.939832)
			(xy 411.818563 -28.901123) (xy 411.863921 -28.868672) (xy 411.913521 -28.843171) (xy 411.966305 -28.825164)
			(xy 412.021148 -28.815034) (xy 412.076882 -28.812997) (xy 412.132319 -28.819097) (xy 412.186276 -28.833203)
			(xy 412.237605 -28.855015) (xy 412.285211 -28.884069) (xy 412.328079 -28.919744) (xy 412.365296 -28.961281)
			(xy 412.396069 -29.007794) (xy 412.419741 -29.058291) (xy 412.435809 -29.111698) (xy 412.443929 -29.166874)
			(xy 412.444438 -29.19476) (xy 412.443929 -29.222646) (xy 412.435809 -29.277822) (xy 412.419741 -29.331229)
			(xy 412.396069 -29.381726) (xy 412.365296 -29.428239) (xy 412.328079 -29.469776) (xy 412.285211 -29.505451)
			(xy 412.237605 -29.534505) (xy 412.186276 -29.556317) (xy 412.132319 -29.570423) (xy 412.076882 -29.576523)
			(xy 412.021148 -29.574486) (xy 411.966305 -29.564356) (xy 411.913521 -29.546349) (xy 411.863921 -29.520848)
			(xy 411.818563 -29.488397) (xy 411.778414 -29.449688) (xy 411.744328 -29.405545) (xy 411.717032 -29.35691)
			(xy 411.697109 -29.304819) (xy 411.684983 -29.250382) (xy 411.680912 -29.19476) (xy 389.222975 -29.19476)
			(xy 389.180161 -29.287383) (xy 389.116729 -29.40493) (xy 389.046152 -29.518332) (xy 388.9687 -29.627154)
			(xy 388.927086 -29.679392) (xy 388.917688 -29.690822) (xy 388.914386 -29.720032) (xy 388.96036 -29.816044)
			(xy 388.964813 -29.824506) (xy 388.978758 -29.837567) (xy 388.996527 -29.844593) (xy 389.00608 -29.845)
			(xy 395.456918 -29.845) (xy 395.466987 -29.845427) (xy 395.485586 -29.853146) (xy 395.492986 -29.859986)
			(xy 395.84376 -30.21076) (xy 411.680912 -30.21076) (xy 411.684983 -30.155138) (xy 411.697109 -30.100701)
			(xy 411.717032 -30.04861) (xy 411.744328 -29.999975) (xy 411.778414 -29.955832) (xy 411.818563 -29.917123)
			(xy 411.863921 -29.884672) (xy 411.913521 -29.859171) (xy 411.966305 -29.841164) (xy 412.021148 -29.831034)
			(xy 412.076882 -29.828997) (xy 412.132319 -29.835097) (xy 412.186276 -29.849203) (xy 412.237605 -29.871015)
			(xy 412.285211 -29.900069) (xy 412.328079 -29.935744) (xy 412.365296 -29.977281) (xy 412.396069 -30.023794)
			(xy 412.419741 -30.074291) (xy 412.435809 -30.127698) (xy 412.443929 -30.182874) (xy 412.444438 -30.21076)
			(xy 412.443929 -30.238646) (xy 412.435809 -30.293822) (xy 412.419741 -30.347229) (xy 412.396069 -30.397726)
			(xy 412.365296 -30.444239) (xy 412.328079 -30.485776) (xy 412.285211 -30.521451) (xy 412.237605 -30.550505)
			(xy 412.186276 -30.572317) (xy 412.132319 -30.586423) (xy 412.076882 -30.592523) (xy 412.021148 -30.590486)
			(xy 411.966305 -30.580356) (xy 411.913521 -30.562349) (xy 411.863921 -30.536848) (xy 411.818563 -30.504397)
			(xy 411.778414 -30.465688) (xy 411.744328 -30.421545) (xy 411.717032 -30.37291) (xy 411.697109 -30.320819)
			(xy 411.684983 -30.266382) (xy 411.680912 -30.21076) (xy 395.84376 -30.21076) (xy 397.666968 -32.033968)
			(xy 405.206182 -32.033968) (xy 405.206182 -31.974032) (xy 405.214005 -31.91461) (xy 405.229518 -31.856717)
			(xy 405.252454 -31.801344) (xy 405.282421 -31.749438) (xy 405.318908 -31.701888) (xy 405.361288 -31.659508)
			(xy 405.408838 -31.623021) (xy 405.460744 -31.593054) (xy 405.516117 -31.570118) (xy 405.57401 -31.554605)
			(xy 405.633432 -31.546782) (xy 405.693368 -31.546782) (xy 405.75279 -31.554605) (xy 405.810683 -31.570118)
			(xy 405.866056 -31.593054) (xy 405.917962 -31.623021) (xy 405.965512 -31.659508) (xy 406.007892 -31.701888)
			(xy 406.044379 -31.749438) (xy 406.044703 -31.75) (xy 409.599382 -31.75) (xy 409.603453 -31.694378)
			(xy 409.615579 -31.639941) (xy 409.635502 -31.58785) (xy 409.662798 -31.539215) (xy 409.696884 -31.495072)
			(xy 409.737033 -31.456363) (xy 409.782391 -31.423912) (xy 409.831991 -31.398411) (xy 409.884775 -31.380404)
			(xy 409.939618 -31.370274) (xy 409.995352 -31.368237) (xy 410.050789 -31.374337) (xy 410.104746 -31.388443)
			(xy 410.156075 -31.410255) (xy 410.203681 -31.439309) (xy 410.246549 -31.474984) (xy 410.283766 -31.516521)
			(xy 410.314539 -31.563034) (xy 410.338211 -31.613531) (xy 410.354279 -31.666938) (xy 410.362399 -31.722114)
			(xy 410.362908 -31.75) (xy 410.362399 -31.777886) (xy 410.354279 -31.833062) (xy 410.338211 -31.886469)
			(xy 410.314539 -31.936966) (xy 410.283766 -31.983479) (xy 410.246549 -32.025016) (xy 410.203681 -32.060691)
			(xy 410.156075 -32.089745) (xy 410.104746 -32.111557) (xy 410.050789 -32.125663) (xy 409.995352 -32.131763)
			(xy 409.939618 -32.129726) (xy 409.884775 -32.119596) (xy 409.831991 -32.101589) (xy 409.782391 -32.076088)
			(xy 409.737033 -32.043637) (xy 409.696884 -32.004928) (xy 409.662798 -31.960785) (xy 409.635502 -31.91215)
			(xy 409.615579 -31.860059) (xy 409.603453 -31.805622) (xy 409.599382 -31.75) (xy 406.044703 -31.75)
			(xy 406.074346 -31.801344) (xy 406.097282 -31.856717) (xy 406.112795 -31.91461) (xy 406.120618 -31.974032)
			(xy 406.121108 -32.004) (xy 406.120618 -32.033968) (xy 406.112795 -32.09339) (xy 406.097282 -32.151283)
			(xy 406.074346 -32.206656) (xy 406.044379 -32.258562) (xy 406.007892 -32.306112) (xy 405.965512 -32.348492)
			(xy 405.917962 -32.384979) (xy 405.866056 -32.414946) (xy 405.810683 -32.437882) (xy 405.75279 -32.453395)
			(xy 405.693368 -32.461218) (xy 405.633432 -32.461218) (xy 405.57401 -32.453395) (xy 405.516117 -32.437882)
			(xy 405.460744 -32.414946) (xy 405.408838 -32.384979) (xy 405.361288 -32.348492) (xy 405.318908 -32.306112)
			(xy 405.282421 -32.258562) (xy 405.252454 -32.206656) (xy 405.229518 -32.151283) (xy 405.214005 -32.09339)
			(xy 405.206182 -32.033968) (xy 397.666968 -32.033968) (xy 402.492968 -36.859968) (xy 405.206182 -36.859968)
			(xy 405.206182 -36.800032) (xy 405.214005 -36.74061) (xy 405.229518 -36.682717) (xy 405.252454 -36.627344)
			(xy 405.282421 -36.575438) (xy 405.318908 -36.527888) (xy 405.361288 -36.485508) (xy 405.408838 -36.449021)
			(xy 405.460744 -36.419054) (xy 405.516117 -36.396118) (xy 405.57401 -36.380605) (xy 405.633432 -36.372782)
			(xy 405.693368 -36.372782) (xy 405.75279 -36.380605) (xy 405.810683 -36.396118) (xy 405.866056 -36.419054)
			(xy 405.917962 -36.449021) (xy 405.965512 -36.485508) (xy 406.007892 -36.527888) (xy 406.044379 -36.575438)
			(xy 406.074346 -36.627344) (xy 406.097282 -36.682717) (xy 406.112795 -36.74061) (xy 406.120618 -36.800032)
			(xy 406.121108 -36.83) (xy 406.120618 -36.859968) (xy 406.112795 -36.91939) (xy 406.097282 -36.977283)
			(xy 406.074346 -37.032656) (xy 406.044379 -37.084562) (xy 406.007892 -37.132112) (xy 405.965512 -37.174492)
			(xy 405.917962 -37.210979) (xy 405.866056 -37.240946) (xy 405.810683 -37.263882) (xy 405.75279 -37.279395)
			(xy 405.693368 -37.287218) (xy 405.633432 -37.287218) (xy 405.57401 -37.279395) (xy 405.516117 -37.263882)
			(xy 405.460744 -37.240946) (xy 405.408838 -37.210979) (xy 405.361288 -37.174492) (xy 405.318908 -37.132112)
			(xy 405.282421 -37.084562) (xy 405.252454 -37.032656) (xy 405.229518 -36.977283) (xy 405.214005 -36.91939)
			(xy 405.206182 -36.859968) (xy 402.492968 -36.859968) (xy 403.45995 -37.82695) (xy 410.615128 -37.82695)
			(xy 410.619201 -37.771291) (xy 410.631336 -37.716818) (xy 410.651272 -37.664692) (xy 410.678586 -37.616024)
			(xy 410.712694 -37.571852) (xy 410.752871 -37.533117) (xy 410.798259 -37.500645) (xy 410.847891 -37.475127)
			(xy 410.900711 -37.457108) (xy 410.95559 -37.446971) (xy 411.011361 -37.444933) (xy 411.066835 -37.451036)
			(xy 411.120828 -37.465152) (xy 411.172191 -37.486979) (xy 411.219829 -37.516052) (xy 411.262725 -37.551751)
			(xy 411.299967 -37.593315) (xy 411.330761 -37.639859) (xy 411.354449 -37.69039) (xy 411.370527 -37.743832)
			(xy 411.378653 -37.799046) (xy 411.379162 -37.82695) (xy 411.378653 -37.854854) (xy 411.370527 -37.910068)
			(xy 411.354449 -37.96351) (xy 411.330761 -38.014041) (xy 411.299967 -38.060585) (xy 411.262725 -38.102149)
			(xy 411.219829 -38.137848) (xy 411.172191 -38.166921) (xy 411.120828 -38.188748) (xy 411.066835 -38.202864)
			(xy 411.011361 -38.208967) (xy 410.95559 -38.206929) (xy 410.900711 -38.196792) (xy 410.847891 -38.178773)
			(xy 410.798259 -38.153255) (xy 410.752871 -38.120783) (xy 410.712694 -38.082048) (xy 410.678586 -38.037876)
			(xy 410.651272 -37.989208) (xy 410.631336 -37.937082) (xy 410.619201 -37.882609) (xy 410.615128 -37.82695)
			(xy 403.45995 -37.82695) (xy 414.557968 -48.924968) (xy 419.658782 -48.924968) (xy 419.658782 -48.865032)
			(xy 419.666605 -48.80561) (xy 419.682118 -48.747717) (xy 419.705054 -48.692344) (xy 419.735021 -48.640438)
			(xy 419.771508 -48.592888) (xy 419.813888 -48.550508) (xy 419.861438 -48.514021) (xy 419.913344 -48.484054)
			(xy 419.968717 -48.461118) (xy 420.02661 -48.445605) (xy 420.086032 -48.437782) (xy 420.116 -48.437292)
			(xy 420.148409 -48.437889) (xy 420.212579 -48.447044) (xy 420.274816 -48.465158) (xy 420.333876 -48.491868)
			(xy 420.388579 -48.52664) (xy 420.437831 -48.568779) (xy 420.459662 -48.59274) (xy 420.46906 -48.603408)
			(xy 420.495984 -48.61179) (xy 420.611046 -48.583596) (xy 420.631112 -48.563784) (xy 420.634668 -48.549814)
			(xy 420.641946 -48.522581) (xy 420.663315 -48.470421) (xy 420.692128 -48.421975) (xy 420.727757 -48.378296)
			(xy 420.769426 -48.340337) (xy 420.816229 -48.308924) (xy 420.867145 -48.284742) (xy 420.921066 -48.268317)
			(xy 420.976817 -48.260006) (xy 421.005 -48.259492) (xy 421.033797 -48.259955) (xy 421.090735 -48.268625)
			(xy 421.145723 -48.285755) (xy 421.197513 -48.310953) (xy 421.244927 -48.343649) (xy 421.286889 -48.383099)
			(xy 421.322445 -48.428408) (xy 421.350789 -48.478545) (xy 421.371275 -48.532373) (xy 421.383439 -48.588669)
			(xy 421.385746 -48.617378) (xy 421.386508 -48.628808) (xy 421.397684 -48.648874) (xy 421.48125 -48.708056)
			(xy 421.503856 -48.711866) (xy 421.515032 -48.708818) (xy 421.545627 -48.700649) (xy 421.608338 -48.691861)
			(xy 421.64 -48.691292) (xy 421.669968 -48.691782) (xy 421.72939 -48.699605) (xy 421.787283 -48.715118)
			(xy 421.842656 -48.738054) (xy 421.894562 -48.768021) (xy 421.942112 -48.804508) (xy 421.984492 -48.846888)
			(xy 422.020979 -48.894438) (xy 422.050946 -48.946344) (xy 422.073882 -49.001717) (xy 422.089395 -49.05961)
			(xy 422.097218 -49.119032) (xy 422.097218 -49.178968) (xy 422.089395 -49.23839) (xy 422.073882 -49.296283)
			(xy 422.050946 -49.351656) (xy 422.020979 -49.403562) (xy 421.984492 -49.451112) (xy 421.942112 -49.493492)
			(xy 421.894562 -49.529979) (xy 421.842656 -49.559946) (xy 421.787283 -49.582882) (xy 421.72939 -49.598395)
			(xy 421.669968 -49.606218) (xy 421.610032 -49.606218) (xy 421.55061 -49.598395) (xy 421.492717 -49.582882)
			(xy 421.437344 -49.559946) (xy 421.385438 -49.529979) (xy 421.337888 -49.493492) (xy 421.295508 -49.451112)
			(xy 421.259021 -49.403562) (xy 421.229054 -49.351656) (xy 421.206118 -49.296283) (xy 421.190605 -49.23839)
			(xy 421.182782 -49.178968) (xy 421.182292 -49.149) (xy 421.183054 -49.1236) (xy 421.183562 -49.111916)
			(xy 421.174926 -49.090834) (xy 421.09898 -49.022254) (xy 421.076882 -49.015904) (xy 421.065452 -49.017682)
			(xy 421.050441 -49.019941) (xy 421.020179 -49.02236) (xy 421.005 -49.022508) (xy 420.975487 -49.021958)
			(xy 420.917166 -49.012867) (xy 420.86094 -48.994903) (xy 420.808152 -48.968492) (xy 420.760062 -48.934267)
			(xy 420.738554 -48.91405) (xy 420.728394 -48.904144) (xy 420.700962 -48.897794) (xy 420.588186 -48.934624)
			(xy 420.569898 -48.956214) (xy 420.567612 -48.970184) (xy 420.562403 -48.998984) (xy 420.545498 -49.055017)
			(xy 420.521589 -49.108439) (xy 420.491066 -49.158378) (xy 420.454427 -49.204019) (xy 420.41227 -49.244619)
			(xy 420.365282 -49.279514) (xy 420.31423 -49.308137) (xy 420.259947 -49.330019) (xy 420.203317 -49.344804)
			(xy 420.145264 -49.352251) (xy 420.116 -49.352708) (xy 420.086032 -49.352218) (xy 420.02661 -49.344395)
			(xy 419.968717 -49.328882) (xy 419.913344 -49.305946) (xy 419.861438 -49.275979) (xy 419.813888 -49.239492)
			(xy 419.771508 -49.197112) (xy 419.735021 -49.149562) (xy 419.705054 -49.097656) (xy 419.682118 -49.042283)
			(xy 419.666605 -48.98439) (xy 419.658782 -48.924968) (xy 414.557968 -48.924968) (xy 416.179 -50.546)
			(xy 421.638982 -50.546) (xy 421.643053 -50.490378) (xy 421.655179 -50.435941) (xy 421.675102 -50.38385)
			(xy 421.702398 -50.335215) (xy 421.736484 -50.291072) (xy 421.776633 -50.252363) (xy 421.821991 -50.219912)
			(xy 421.871591 -50.194411) (xy 421.924375 -50.176404) (xy 421.979218 -50.166274) (xy 422.034952 -50.164237)
			(xy 422.090389 -50.170337) (xy 422.144346 -50.184443) (xy 422.195675 -50.206255) (xy 422.243281 -50.235309)
			(xy 422.286149 -50.270984) (xy 422.323366 -50.312521) (xy 422.354139 -50.359034) (xy 422.377811 -50.409531)
			(xy 422.38066 -50.419) (xy 423.188382 -50.419) (xy 423.192453 -50.363378) (xy 423.204579 -50.308941)
			(xy 423.224502 -50.25685) (xy 423.251798 -50.208215) (xy 423.285884 -50.164072) (xy 423.326033 -50.125363)
			(xy 423.371391 -50.092912) (xy 423.420991 -50.067411) (xy 423.473775 -50.049404) (xy 423.528618 -50.039274)
			(xy 423.584352 -50.037237) (xy 423.639789 -50.043337) (xy 423.693746 -50.057443) (xy 423.745075 -50.079255)
			(xy 423.792681 -50.108309) (xy 423.835549 -50.143984) (xy 423.872766 -50.185521) (xy 423.903539 -50.232034)
			(xy 423.927211 -50.282531) (xy 423.943279 -50.335938) (xy 423.951399 -50.391114) (xy 423.951908 -50.419)
			(xy 423.951399 -50.446886) (xy 423.943279 -50.502062) (xy 423.927211 -50.555469) (xy 423.903539 -50.605966)
			(xy 423.872766 -50.652479) (xy 423.835549 -50.694016) (xy 423.792681 -50.729691) (xy 423.745075 -50.758745)
			(xy 423.693746 -50.780557) (xy 423.639789 -50.794663) (xy 423.584352 -50.800763) (xy 423.528618 -50.798726)
			(xy 423.473775 -50.788596) (xy 423.420991 -50.770589) (xy 423.371391 -50.745088) (xy 423.326033 -50.712637)
			(xy 423.285884 -50.673928) (xy 423.251798 -50.629785) (xy 423.224502 -50.58115) (xy 423.204579 -50.529059)
			(xy 423.192453 -50.474622) (xy 423.188382 -50.419) (xy 422.38066 -50.419) (xy 422.393879 -50.462938)
			(xy 422.401999 -50.518114) (xy 422.402508 -50.546) (xy 422.401999 -50.573886) (xy 422.393879 -50.629062)
			(xy 422.377811 -50.682469) (xy 422.354139 -50.732966) (xy 422.323366 -50.779479) (xy 422.286149 -50.821016)
			(xy 422.243281 -50.856691) (xy 422.195675 -50.885745) (xy 422.144346 -50.907557) (xy 422.090389 -50.921663)
			(xy 422.034952 -50.927763) (xy 421.979218 -50.925726) (xy 421.924375 -50.915596) (xy 421.871591 -50.897589)
			(xy 421.821991 -50.872088) (xy 421.776633 -50.839637) (xy 421.736484 -50.800928) (xy 421.702398 -50.756785)
			(xy 421.675102 -50.70815) (xy 421.655179 -50.656059) (xy 421.643053 -50.601622) (xy 421.638982 -50.546)
			(xy 416.179 -50.546) (xy 417.068 -51.435) (xy 422.198038 -51.435) (xy 422.198733 -51.39808) (xy 422.21061 -51.325201)
			(xy 422.22166 -51.289966) (xy 422.227248 -51.27498) (xy 422.238516 -51.246238) (xy 422.267682 -51.191828)
			(xy 422.303897 -51.141832) (xy 422.346506 -51.097158) (xy 422.394733 -51.058618) (xy 422.447703 -51.026912)
			(xy 422.504455 -51.002614) (xy 422.563958 -50.986166) (xy 422.625133 -50.977867) (xy 422.686867 -50.977867)
			(xy 422.748042 -50.986166) (xy 422.807545 -51.002614) (xy 422.864297 -51.026912) (xy 422.917267 -51.058618)
			(xy 422.965494 -51.097158) (xy 423.008103 -51.141832) (xy 423.036475 -51.181) (xy 432.586128 -51.181)
			(xy 432.590201 -51.125341) (xy 432.602336 -51.070868) (xy 432.622272 -51.018742) (xy 432.649586 -50.970074)
			(xy 432.683694 -50.925902) (xy 432.723871 -50.887167) (xy 432.769259 -50.854695) (xy 432.818891 -50.829177)
			(xy 432.871711 -50.811158) (xy 432.92659 -50.801021) (xy 432.982361 -50.798983) (xy 433.037835 -50.805086)
			(xy 433.091828 -50.819202) (xy 433.143191 -50.841029) (xy 433.190829 -50.870102) (xy 433.233725 -50.905801)
			(xy 433.270967 -50.947365) (xy 433.301761 -50.993909) (xy 433.325449 -51.04444) (xy 433.341527 -51.097882)
			(xy 433.349653 -51.153096) (xy 433.350162 -51.181) (xy 433.349653 -51.208904) (xy 433.341527 -51.264118)
			(xy 433.325449 -51.31756) (xy 433.301761 -51.368091) (xy 433.270967 -51.414635) (xy 433.233725 -51.456199)
			(xy 433.190829 -51.491898) (xy 433.143191 -51.520971) (xy 433.091828 -51.542798) (xy 433.037835 -51.556914)
			(xy 432.982361 -51.563017) (xy 432.92659 -51.560979) (xy 432.871711 -51.550842) (xy 432.818891 -51.532823)
			(xy 432.769259 -51.507305) (xy 432.723871 -51.474833) (xy 432.683694 -51.436098) (xy 432.649586 -51.391926)
			(xy 432.622272 -51.343258) (xy 432.602336 -51.291132) (xy 432.590201 -51.236659) (xy 432.586128 -51.181)
			(xy 423.036475 -51.181) (xy 423.044318 -51.191828) (xy 423.073484 -51.246238) (xy 423.084752 -51.27498)
			(xy 423.09034 -51.289966) (xy 423.101319 -51.325218) (xy 423.113193 -51.398086) (xy 423.113962 -51.435)
			(xy 423.113472 -51.464984) (xy 423.105644 -51.52444) (xy 423.090123 -51.582365) (xy 423.067174 -51.637769)
			(xy 423.03719 -51.689703) (xy 423.000684 -51.737279) (xy 422.958279 -51.779684) (xy 422.910703 -51.81619)
			(xy 422.858769 -51.846174) (xy 422.803365 -51.869123) (xy 422.74544 -51.884644) (xy 422.685984 -51.892472)
			(xy 422.626016 -51.892472) (xy 422.56656 -51.884644) (xy 422.508635 -51.869123) (xy 422.453231 -51.846174)
			(xy 422.401297 -51.81619) (xy 422.353721 -51.779684) (xy 422.311316 -51.737279) (xy 422.27481 -51.689703)
			(xy 422.244826 -51.637769) (xy 422.221877 -51.582365) (xy 422.206356 -51.52444) (xy 422.198528 -51.464984)
			(xy 422.198038 -51.435) (xy 417.068 -51.435) (xy 418.323014 -52.690014) (xy 418.329868 -52.697409)
			(xy 418.33761 -52.716008) (xy 418.338 -52.726082) (xy 418.338 -60.099956) (xy 422.484046 -60.099956)
			(xy 422.488076 -59.957621) (xy 422.500151 -59.815741) (xy 422.520234 -59.674773) (xy 422.548261 -59.535166)
			(xy 422.584141 -59.397368) (xy 422.627759 -59.261821) (xy 422.678976 -59.128959) (xy 422.737627 -58.999207)
			(xy 422.803525 -58.872981) (xy 422.876459 -58.750685) (xy 422.956196 -58.632712) (xy 423.042478 -58.519439)
			(xy 423.135031 -58.411228) (xy 423.233558 -58.308427) (xy 423.337743 -58.211365) (xy 423.447252 -58.120353)
			(xy 423.561735 -58.035681) (xy 423.680825 -57.957623) (xy 423.80414 -57.886427) (xy 423.931286 -57.822321)
			(xy 424.061855 -57.765512) (xy 424.195429 -57.71618) (xy 424.33158 -57.674484) (xy 424.469871 -57.640558)
			(xy 424.609861 -57.61451) (xy 424.7511 -57.596424) (xy 424.893136 -57.586357) (xy 425.035514 -57.584342)
			(xy 425.177778 -57.590385) (xy 425.319472 -57.604467) (xy 425.460142 -57.626543) (xy 425.599339 -57.656543)
			(xy 425.736615 -57.694369) (xy 425.871531 -57.739901) (xy 426.003655 -57.792992) (xy 426.132564 -57.853474)
			(xy 426.257845 -57.921152) (xy 426.379096 -57.995809) (xy 426.495929 -58.077207) (xy 426.60797 -58.165084)
			(xy 426.71486 -58.259159) (xy 426.816257 -58.359131) (xy 426.911835 -58.464679) (xy 427.001289 -58.575465)
			(xy 427.084331 -58.691134) (xy 427.160697 -58.811317) (xy 427.230141 -58.935627) (xy 427.292441 -59.063668)
			(xy 427.347397 -59.195027) (xy 427.394834 -59.329286) (xy 427.434598 -59.466013) (xy 427.466564 -59.604771)
			(xy 427.490629 -59.745115) (xy 427.506715 -59.886596) (xy 427.51477 -60.02876) (xy 427.515274 -60.099956)
			(xy 427.51477 -60.171152) (xy 427.506715 -60.313316) (xy 427.490629 -60.454797) (xy 427.466564 -60.595141)
			(xy 427.434598 -60.733899) (xy 427.394834 -60.870626) (xy 427.347397 -61.004885) (xy 427.292441 -61.136244)
			(xy 427.230141 -61.264285) (xy 427.160697 -61.388595) (xy 427.084331 -61.508778) (xy 427.001289 -61.624447)
			(xy 426.911835 -61.735233) (xy 426.816257 -61.840781) (xy 426.71486 -61.940753) (xy 426.60797 -62.034828)
			(xy 426.495929 -62.122705) (xy 426.379096 -62.204103) (xy 426.257845 -62.27876) (xy 426.132564 -62.346438)
			(xy 426.003655 -62.40692) (xy 425.871531 -62.460011) (xy 425.736615 -62.505543) (xy 425.599339 -62.543369)
			(xy 425.460142 -62.573369) (xy 425.319472 -62.595445) (xy 425.177778 -62.609527) (xy 425.035514 -62.61557)
			(xy 424.893136 -62.613555) (xy 424.7511 -62.603488) (xy 424.609861 -62.585402) (xy 424.469871 -62.559354)
			(xy 424.33158 -62.525428) (xy 424.195429 -62.483732) (xy 424.061855 -62.4344) (xy 423.931286 -62.377591)
			(xy 423.80414 -62.313485) (xy 423.680825 -62.242289) (xy 423.561735 -62.164231) (xy 423.447252 -62.079559)
			(xy 423.337743 -61.988547) (xy 423.233558 -61.891485) (xy 423.135031 -61.788684) (xy 423.042478 -61.680473)
			(xy 422.956196 -61.5672) (xy 422.876459 -61.449227) (xy 422.803525 -61.326931) (xy 422.737627 -61.200705)
			(xy 422.678976 -61.070953) (xy 422.627759 -60.938091) (xy 422.584141 -60.802544) (xy 422.548261 -60.664746)
			(xy 422.520234 -60.525139) (xy 422.500151 -60.384171) (xy 422.488076 -60.242291) (xy 422.484046 -60.099956)
			(xy 418.338 -60.099956) (xy 418.338 -83.697568) (xy 448.944982 -83.697568) (xy 448.944982 -83.637632)
			(xy 448.952805 -83.57821) (xy 448.968318 -83.520317) (xy 448.991254 -83.464944) (xy 449.021221 -83.413038)
			(xy 449.057708 -83.365488) (xy 449.100088 -83.323108) (xy 449.147638 -83.286621) (xy 449.199544 -83.256654)
			(xy 449.254917 -83.233718) (xy 449.31281 -83.218205) (xy 449.372232 -83.210382) (xy 449.432168 -83.210382)
			(xy 449.49159 -83.218205) (xy 449.549483 -83.233718) (xy 449.604856 -83.256654) (xy 449.656762 -83.286621)
			(xy 449.704312 -83.323108) (xy 449.746692 -83.365488) (xy 449.783179 -83.413038) (xy 449.813146 -83.464944)
			(xy 449.836082 -83.520317) (xy 449.851595 -83.57821) (xy 449.859418 -83.637632) (xy 449.859908 -83.6676)
			(xy 449.859418 -83.697568) (xy 449.851595 -83.75699) (xy 449.836082 -83.814883) (xy 449.813146 -83.870256)
			(xy 449.783179 -83.922162) (xy 449.746692 -83.969712) (xy 449.704312 -84.012092) (xy 449.656762 -84.048579)
			(xy 449.604856 -84.078546) (xy 449.549483 -84.101482) (xy 449.49159 -84.116995) (xy 449.432168 -84.124818)
			(xy 449.372232 -84.124818) (xy 449.31281 -84.116995) (xy 449.254917 -84.101482) (xy 449.199544 -84.078546)
			(xy 449.147638 -84.048579) (xy 449.100088 -84.012092) (xy 449.057708 -83.969712) (xy 449.021221 -83.922162)
			(xy 448.991254 -83.870256) (xy 448.968318 -83.814883) (xy 448.952805 -83.75699) (xy 448.944982 -83.697568)
			(xy 418.338 -83.697568) (xy 418.338 -85.030814) (xy 449.04455 -85.030814) (xy 449.04455 -84.970878)
			(xy 449.052373 -84.911456) (xy 449.067886 -84.853563) (xy 449.090822 -84.79819) (xy 449.120789 -84.746284)
			(xy 449.157276 -84.698734) (xy 449.199656 -84.656354) (xy 449.247206 -84.619867) (xy 449.299112 -84.5899)
			(xy 449.354485 -84.566964) (xy 449.412378 -84.551451) (xy 449.4718 -84.543628) (xy 449.531736 -84.543628)
			(xy 449.591158 -84.551451) (xy 449.649051 -84.566964) (xy 449.704424 -84.5899) (xy 449.75633 -84.619867)
			(xy 449.80388 -84.656354) (xy 449.84626 -84.698734) (xy 449.882747 -84.746284) (xy 449.912714 -84.79819)
			(xy 449.93565 -84.853563) (xy 449.951163 -84.911456) (xy 449.958986 -84.970878) (xy 449.959476 -85.000846)
			(xy 449.958986 -85.030814) (xy 449.951163 -85.090236) (xy 449.93565 -85.148129) (xy 449.912714 -85.203502)
			(xy 449.882747 -85.255408) (xy 449.84626 -85.302958) (xy 449.80388 -85.345338) (xy 449.75633 -85.381825)
			(xy 449.704424 -85.411792) (xy 449.649051 -85.434728) (xy 449.591158 -85.450241) (xy 449.531736 -85.458064)
			(xy 449.4718 -85.458064) (xy 449.412378 -85.450241) (xy 449.354485 -85.434728) (xy 449.299112 -85.411792)
			(xy 449.247206 -85.381825) (xy 449.199656 -85.345338) (xy 449.157276 -85.302958) (xy 449.120789 -85.255408)
			(xy 449.090822 -85.203502) (xy 449.067886 -85.148129) (xy 449.052373 -85.090236) (xy 449.04455 -85.030814)
			(xy 418.338 -85.030814) (xy 418.338 -86.542368) (xy 448.944982 -86.542368) (xy 448.944982 -86.482432)
			(xy 448.952805 -86.42301) (xy 448.968318 -86.365117) (xy 448.991254 -86.309744) (xy 449.021221 -86.257838)
			(xy 449.057708 -86.210288) (xy 449.100088 -86.167908) (xy 449.147638 -86.131421) (xy 449.199544 -86.101454)
			(xy 449.254917 -86.078518) (xy 449.31281 -86.063005) (xy 449.372232 -86.055182) (xy 449.432168 -86.055182)
			(xy 449.49159 -86.063005) (xy 449.549483 -86.078518) (xy 449.604856 -86.101454) (xy 449.656762 -86.131421)
			(xy 449.704312 -86.167908) (xy 449.746692 -86.210288) (xy 449.783179 -86.257838) (xy 449.813146 -86.309744)
			(xy 449.836082 -86.365117) (xy 449.851595 -86.42301) (xy 449.859418 -86.482432) (xy 449.859908 -86.5124)
			(xy 449.859418 -86.542368) (xy 449.851595 -86.60179) (xy 449.836082 -86.659683) (xy 449.813146 -86.715056)
			(xy 449.783179 -86.766962) (xy 449.746692 -86.814512) (xy 449.704312 -86.856892) (xy 449.656762 -86.893379)
			(xy 449.604856 -86.923346) (xy 449.549483 -86.946282) (xy 449.49159 -86.961795) (xy 449.432168 -86.969618)
			(xy 449.372232 -86.969618) (xy 449.31281 -86.961795) (xy 449.254917 -86.946282) (xy 449.199544 -86.923346)
			(xy 449.147638 -86.893379) (xy 449.100088 -86.856892) (xy 449.057708 -86.814512) (xy 449.021221 -86.766962)
			(xy 448.991254 -86.715056) (xy 448.968318 -86.659683) (xy 448.952805 -86.60179) (xy 448.944982 -86.542368)
			(xy 418.338 -86.542368) (xy 418.338 -87.964768) (xy 448.538582 -87.964768) (xy 448.538582 -87.904832)
			(xy 448.546405 -87.84541) (xy 448.561918 -87.787517) (xy 448.584854 -87.732144) (xy 448.614821 -87.680238)
			(xy 448.651308 -87.632688) (xy 448.693688 -87.590308) (xy 448.741238 -87.553821) (xy 448.793144 -87.523854)
			(xy 448.848517 -87.500918) (xy 448.90641 -87.485405) (xy 448.965832 -87.477582) (xy 449.025768 -87.477582)
			(xy 449.08519 -87.485405) (xy 449.143083 -87.500918) (xy 449.198456 -87.523854) (xy 449.250362 -87.553821)
			(xy 449.297912 -87.590308) (xy 449.340292 -87.632688) (xy 449.376779 -87.680238) (xy 449.406746 -87.732144)
			(xy 449.429682 -87.787517) (xy 449.445195 -87.84541) (xy 449.453018 -87.904832) (xy 449.453508 -87.9348)
			(xy 449.453018 -87.964768) (xy 449.445195 -88.02419) (xy 449.429682 -88.082083) (xy 449.406746 -88.137456)
			(xy 449.376779 -88.189362) (xy 449.340292 -88.236912) (xy 449.297912 -88.279292) (xy 449.250362 -88.315779)
			(xy 449.198456 -88.345746) (xy 449.143083 -88.368682) (xy 449.08519 -88.384195) (xy 449.025768 -88.392018)
			(xy 448.965832 -88.392018) (xy 448.90641 -88.384195) (xy 448.848517 -88.368682) (xy 448.793144 -88.345746)
			(xy 448.741238 -88.315779) (xy 448.693688 -88.279292) (xy 448.651308 -88.236912) (xy 448.614821 -88.189362)
			(xy 448.584854 -88.137456) (xy 448.561918 -88.082083) (xy 448.546405 -88.02419) (xy 448.538582 -87.964768)
			(xy 418.338 -87.964768) (xy 418.338 -98.935032) (xy 450.554344 -98.935032) (xy 450.55491 -98.881539)
			(xy 450.563934 -98.774933) (xy 450.581887 -98.669464) (xy 450.59473 -98.617532) (xy 450.596141 -98.611258)
			(xy 450.596149 -98.598404) (xy 450.59473 -98.592132) (xy 450.581886 -98.5402) (xy 450.563928 -98.434731)
			(xy 450.554908 -98.328125) (xy 450.554344 -98.274632) (xy 450.554913 -98.224734) (xy 450.56274 -98.125247)
			(xy 450.578349 -98.02668) (xy 450.601643 -97.929642) (xy 450.632478 -97.83473) (xy 450.670666 -97.742531)
			(xy 450.715969 -97.653611) (xy 450.768109 -97.568521) (xy 450.826765 -97.487783) (xy 450.891574 -97.411896)
			(xy 450.962138 -97.341328) (xy 451.03802 -97.276514) (xy 451.118754 -97.217854) (xy 451.203842 -97.165708)
			(xy 451.292758 -97.120399) (xy 451.384955 -97.082206) (xy 451.479865 -97.051364) (xy 451.576902 -97.028064)
			(xy 451.675467 -97.012449) (xy 451.774955 -97.004616) (xy 451.824852 -97.004124) (xy 451.825106 -97.004124)
			(xy 451.88272 -97.004772) (xy 451.997474 -97.015221) (xy 452.110812 -97.036006) (xy 452.166482 -97.05086)
			(xy 452.172989 -97.052428) (xy 452.186365 -97.052565) (xy 452.192898 -97.051114) (xy 452.24471 -97.038339)
			(xy 452.349929 -97.020486) (xy 452.456275 -97.011529) (xy 452.509636 -97.010982) (xy 452.50989 -97.010982)
			(xy 452.561287 -97.01151) (xy 452.663743 -97.019847) (xy 452.765189 -97.036444) (xy 452.815198 -97.04832)
			(xy 452.821225 -97.049633) (xy 452.833555 -97.049633) (xy 452.839582 -97.04832) (xy 452.889594 -97.036457)
			(xy 452.991039 -97.019864) (xy 453.093493 -97.011516) (xy 453.14489 -97.010982) (xy 453.194789 -97.011491)
			(xy 453.294279 -97.019321) (xy 453.392848 -97.034932) (xy 453.489888 -97.058228) (xy 453.584801 -97.089067)
			(xy 453.677002 -97.127257) (xy 453.765923 -97.172563) (xy 453.851015 -97.224707) (xy 453.931753 -97.283365)
			(xy 454.00764 -97.348178) (xy 454.078208 -97.418745) (xy 454.143022 -97.494631) (xy 454.201682 -97.575369)
			(xy 454.253827 -97.66046) (xy 454.299135 -97.749379) (xy 454.337326 -97.84158) (xy 454.368166 -97.936493)
			(xy 454.391464 -98.033533) (xy 454.407077 -98.132101) (xy 454.414908 -98.231591) (xy 454.415398 -98.28149)
			(xy 454.414835 -98.334983) (xy 454.40581 -98.441589) (xy 454.387855 -98.547058) (xy 454.375012 -98.59899)
			(xy 454.373592 -98.605262) (xy 454.37359 -98.618118) (xy 454.375012 -98.62439) (xy 454.387862 -98.67632)
			(xy 454.405817 -98.78179) (xy 454.414835 -98.888396) (xy 454.415398 -98.94189) (xy 454.414921 -98.99179)
			(xy 454.407092 -99.091282) (xy 454.39148 -99.189853) (xy 454.368183 -99.286895) (xy 454.337344 -99.38181)
			(xy 454.299152 -99.474013) (xy 454.253845 -99.562935) (xy 454.2017 -99.648028) (xy 454.143039 -99.728768)
			(xy 454.078225 -99.804656) (xy 454.007656 -99.875225) (xy 453.931768 -99.940039) (xy 453.851028 -99.9987)
			(xy 453.765935 -100.050845) (xy 453.677013 -100.096152) (xy 453.58481 -100.134344) (xy 453.489895 -100.165183)
			(xy 453.392853 -100.18848) (xy 453.294282 -100.204092) (xy 453.19479 -100.211921) (xy 453.14489 -100.212398)
			(xy 453.093493 -100.211872) (xy 452.991037 -100.203533) (xy 452.889591 -100.186936) (xy 452.839582 -100.17506)
			(xy 452.833555 -100.173747) (xy 452.821225 -100.173747) (xy 452.815198 -100.17506) (xy 452.765187 -100.186926)
			(xy 452.663741 -100.203518) (xy 452.561287 -100.211865) (xy 452.50989 -100.212398) (xy 452.509636 -100.212398)
			(xy 452.452022 -100.211744) (xy 452.337269 -100.201298) (xy 452.22393 -100.180515) (xy 452.16826 -100.165662)
			(xy 452.161758 -100.164072) (xy 452.148377 -100.163949) (xy 452.141844 -100.165408) (xy 452.090034 -100.178193)
			(xy 451.984814 -100.196042) (xy 451.878467 -100.204995) (xy 451.825106 -100.20554) (xy 451.824852 -100.20554)
			(xy 451.774953 -100.205064) (xy 451.675463 -100.197231) (xy 451.576894 -100.181616) (xy 451.479854 -100.158316)
			(xy 451.384941 -100.127474) (xy 451.292741 -100.089281) (xy 451.203821 -100.043972) (xy 451.11873 -99.991826)
			(xy 451.037992 -99.933165) (xy 450.962106 -99.868351) (xy 450.891538 -99.797783) (xy 450.826725 -99.721895)
			(xy 450.768065 -99.641157) (xy 450.71592 -99.556065) (xy 450.670612 -99.467145) (xy 450.632421 -99.374944)
			(xy 450.60158 -99.280031) (xy 450.578281 -99.18299) (xy 450.562667 -99.084421) (xy 450.554835 -98.984931)
			(xy 450.554344 -98.935032) (xy 418.338 -98.935032) (xy 418.338 -104.549956) (xy 422.484046 -104.549956)
			(xy 422.488076 -104.407621) (xy 422.500151 -104.265741) (xy 422.520234 -104.124773) (xy 422.548261 -103.985166)
			(xy 422.584141 -103.847368) (xy 422.627759 -103.711821) (xy 422.678976 -103.578959) (xy 422.737627 -103.449207)
			(xy 422.803525 -103.322981) (xy 422.876459 -103.200685) (xy 422.956196 -103.082712) (xy 423.042478 -102.969439)
			(xy 423.135031 -102.861228) (xy 423.233558 -102.758427) (xy 423.337743 -102.661365) (xy 423.447252 -102.570353)
			(xy 423.561735 -102.485681) (xy 423.680825 -102.407623) (xy 423.80414 -102.336427) (xy 423.931286 -102.272321)
			(xy 424.061855 -102.215512) (xy 424.195429 -102.16618) (xy 424.33158 -102.124484) (xy 424.469871 -102.090558)
			(xy 424.609861 -102.06451) (xy 424.7511 -102.046424) (xy 424.893136 -102.036357) (xy 425.035514 -102.034342)
			(xy 425.177778 -102.040385) (xy 425.319472 -102.054467) (xy 425.460142 -102.076543) (xy 425.599339 -102.106543)
			(xy 425.736615 -102.144369) (xy 425.871531 -102.189901) (xy 426.003655 -102.242992) (xy 426.132564 -102.303474)
			(xy 426.257845 -102.371152) (xy 426.379096 -102.445809) (xy 426.495929 -102.527207) (xy 426.60797 -102.615084)
			(xy 426.71486 -102.709159) (xy 426.816257 -102.809131) (xy 426.911835 -102.914679) (xy 426.979946 -102.999032)
			(xy 450.554344 -102.999032) (xy 450.55491 -102.945539) (xy 450.563934 -102.838933) (xy 450.581887 -102.733464)
			(xy 450.59473 -102.681532) (xy 450.596141 -102.675258) (xy 450.596149 -102.662404) (xy 450.59473 -102.656132)
			(xy 450.581886 -102.6042) (xy 450.563928 -102.498731) (xy 450.554908 -102.392125) (xy 450.554344 -102.338632)
			(xy 450.554913 -102.288734) (xy 450.56274 -102.189247) (xy 450.578349 -102.09068) (xy 450.601643 -101.993642)
			(xy 450.632478 -101.89873) (xy 450.670666 -101.806531) (xy 450.715969 -101.717611) (xy 450.768109 -101.632521)
			(xy 450.826765 -101.551783) (xy 450.891574 -101.475896) (xy 450.962138 -101.405328) (xy 451.03802 -101.340514)
			(xy 451.118754 -101.281854) (xy 451.203842 -101.229708) (xy 451.292758 -101.184399) (xy 451.384955 -101.146206)
			(xy 451.479865 -101.115364) (xy 451.576902 -101.092064) (xy 451.675467 -101.076449) (xy 451.774955 -101.068616)
			(xy 451.824852 -101.068124) (xy 451.825106 -101.068124) (xy 451.88272 -101.068772) (xy 451.997474 -101.079221)
			(xy 452.110812 -101.100006) (xy 452.166482 -101.11486) (xy 452.172989 -101.116428) (xy 452.186365 -101.116565)
			(xy 452.192898 -101.115114) (xy 452.24471 -101.102339) (xy 452.349929 -101.084486) (xy 452.456275 -101.075529)
			(xy 452.509636 -101.074982) (xy 452.50989 -101.074982) (xy 452.561287 -101.07551) (xy 452.663743 -101.083847)
			(xy 452.765189 -101.100444) (xy 452.815198 -101.11232) (xy 452.821225 -101.113633) (xy 452.833555 -101.113633)
			(xy 452.839582 -101.11232) (xy 452.889594 -101.100457) (xy 452.991039 -101.083864) (xy 453.093493 -101.075516)
			(xy 453.14489 -101.074982) (xy 453.194789 -101.075491) (xy 453.294279 -101.083321) (xy 453.392848 -101.098932)
			(xy 453.489888 -101.122228) (xy 453.584801 -101.153067) (xy 453.677002 -101.191257) (xy 453.765923 -101.236563)
			(xy 453.851015 -101.288707) (xy 453.931753 -101.347365) (xy 454.00764 -101.412178) (xy 454.078208 -101.482745)
			(xy 454.143022 -101.558631) (xy 454.201682 -101.639369) (xy 454.253827 -101.72446) (xy 454.299135 -101.813379)
			(xy 454.337326 -101.90558) (xy 454.368166 -102.000493) (xy 454.391464 -102.097533) (xy 454.407077 -102.196101)
			(xy 454.414908 -102.295591) (xy 454.415398 -102.34549) (xy 454.414835 -102.398983) (xy 454.40581 -102.505589)
			(xy 454.387855 -102.611058) (xy 454.375012 -102.66299) (xy 454.373592 -102.669262) (xy 454.37359 -102.682118)
			(xy 454.375012 -102.68839) (xy 454.387862 -102.74032) (xy 454.405817 -102.84579) (xy 454.414835 -102.952396)
			(xy 454.415398 -103.00589) (xy 454.414921 -103.05579) (xy 454.407092 -103.155282) (xy 454.39148 -103.253853)
			(xy 454.368183 -103.350895) (xy 454.337344 -103.44581) (xy 454.299152 -103.538013) (xy 454.253845 -103.626935)
			(xy 454.2017 -103.712028) (xy 454.143039 -103.792768) (xy 454.078225 -103.868656) (xy 454.007656 -103.939225)
			(xy 453.931768 -104.004039) (xy 453.851028 -104.0627) (xy 453.765935 -104.114845) (xy 453.677013 -104.160152)
			(xy 453.58481 -104.198344) (xy 453.489895 -104.229183) (xy 453.392853 -104.25248) (xy 453.294282 -104.268092)
			(xy 453.19479 -104.275921) (xy 453.14489 -104.276398) (xy 453.093493 -104.275872) (xy 452.991037 -104.267533)
			(xy 452.889591 -104.250936) (xy 452.839582 -104.23906) (xy 452.833555 -104.237747) (xy 452.821225 -104.237747)
			(xy 452.815198 -104.23906) (xy 452.765187 -104.250926) (xy 452.663741 -104.267518) (xy 452.561287 -104.275865)
			(xy 452.50989 -104.276398) (xy 452.509636 -104.276398) (xy 452.452022 -104.275744) (xy 452.337269 -104.265298)
			(xy 452.22393 -104.244515) (xy 452.16826 -104.229662) (xy 452.161758 -104.228072) (xy 452.148377 -104.227949)
			(xy 452.141844 -104.229408) (xy 452.090034 -104.242193) (xy 451.984814 -104.260042) (xy 451.878467 -104.268995)
			(xy 451.825106 -104.26954) (xy 451.824852 -104.26954) (xy 451.774953 -104.269064) (xy 451.675463 -104.261231)
			(xy 451.576894 -104.245616) (xy 451.479854 -104.222316) (xy 451.384941 -104.191474) (xy 451.292741 -104.153281)
			(xy 451.203821 -104.107972) (xy 451.11873 -104.055826) (xy 451.037992 -103.997165) (xy 450.962106 -103.932351)
			(xy 450.891538 -103.861783) (xy 450.826725 -103.785895) (xy 450.768065 -103.705157) (xy 450.71592 -103.620065)
			(xy 450.670612 -103.531145) (xy 450.632421 -103.438944) (xy 450.60158 -103.344031) (xy 450.578281 -103.24699)
			(xy 450.562667 -103.148421) (xy 450.554835 -103.048931) (xy 450.554344 -102.999032) (xy 426.979946 -102.999032)
			(xy 427.001289 -103.025465) (xy 427.084331 -103.141134) (xy 427.160697 -103.261317) (xy 427.230141 -103.385627)
			(xy 427.292441 -103.513668) (xy 427.347397 -103.645027) (xy 427.394834 -103.779286) (xy 427.434598 -103.916013)
			(xy 427.466564 -104.054771) (xy 427.490629 -104.195115) (xy 427.506715 -104.336596) (xy 427.51477 -104.47876)
			(xy 427.515274 -104.549956) (xy 427.51477 -104.621152) (xy 427.506715 -104.763316) (xy 427.490629 -104.904797)
			(xy 427.466564 -105.045141) (xy 427.434598 -105.183899) (xy 427.394834 -105.320626) (xy 427.347397 -105.454885)
			(xy 427.292441 -105.586244) (xy 427.230141 -105.714285) (xy 427.160697 -105.838595) (xy 427.084331 -105.958778)
			(xy 427.001289 -106.074447) (xy 426.911835 -106.185233) (xy 426.816257 -106.290781) (xy 426.71486 -106.390753)
			(xy 426.60797 -106.484828) (xy 426.495929 -106.572705) (xy 426.379096 -106.654103) (xy 426.257845 -106.72876)
			(xy 426.132564 -106.796438) (xy 426.003655 -106.85692) (xy 425.871531 -106.910011) (xy 425.736615 -106.955543)
			(xy 425.599339 -106.993369) (xy 425.460142 -107.023369) (xy 425.319472 -107.045445) (xy 425.177778 -107.059527)
			(xy 425.035514 -107.06557) (xy 424.893136 -107.063555) (xy 424.7511 -107.053488) (xy 424.609861 -107.035402)
			(xy 424.469871 -107.009354) (xy 424.33158 -106.975428) (xy 424.195429 -106.933732) (xy 424.061855 -106.8844)
			(xy 423.931286 -106.827591) (xy 423.80414 -106.763485) (xy 423.680825 -106.692289) (xy 423.561735 -106.614231)
			(xy 423.447252 -106.529559) (xy 423.337743 -106.438547) (xy 423.233558 -106.341485) (xy 423.135031 -106.238684)
			(xy 423.042478 -106.130473) (xy 422.956196 -106.0172) (xy 422.876459 -105.899227) (xy 422.803525 -105.776931)
			(xy 422.737627 -105.650705) (xy 422.678976 -105.520953) (xy 422.627759 -105.388091) (xy 422.584141 -105.252544)
			(xy 422.548261 -105.114746) (xy 422.520234 -104.975139) (xy 422.500151 -104.834171) (xy 422.488076 -104.692291)
			(xy 422.484046 -104.549956) (xy 418.338 -104.549956) (xy 418.338 -149.330918) (xy 418.337573 -149.340987)
			(xy 418.329854 -149.359586) (xy 418.323014 -149.366986) (xy 415.558986 -152.131014) (xy 415.551591 -152.137868)
			(xy 415.532992 -152.14561) (xy 415.522918 -152.146) (xy 402.92655 -152.146) (xy 402.919664 -152.146268)
			(xy 402.906406 -152.150007) (xy 402.900388 -152.153366) (xy 402.885402 -152.16251) (xy 402.87956 -152.166066)
			(xy 402.860764 -152.185624) (xy 402.857462 -152.19172) (xy 402.822918 -152.25268) (xy 402.82241 -152.253188)
			(xy 402.819108 -152.258776) (xy 402.815806 -152.264618) (xy 402.813774 -152.26792) (xy 402.809964 -152.277572)
			(xy 402.808948 -152.280366) (xy 402.803614 -152.296114) (xy 402.804376 -152.306274) (xy 402.804884 -152.313894)
			(xy 402.805646 -152.31745) (xy 402.814588 -152.361273) (xy 434.682634 -152.361273) (xy 434.682634 -152.247719)
			(xy 434.690555 -152.134443) (xy 434.706358 -152.021995) (xy 434.729967 -151.910924) (xy 434.761267 -151.801769)
			(xy 434.800104 -151.695064) (xy 434.84629 -151.591329) (xy 434.8996 -151.491067) (xy 434.959774 -151.394769)
			(xy 435.026519 -151.302903) (xy 435.099509 -151.215916) (xy 435.17839 -151.134233) (xy 435.262776 -151.058251)
			(xy 435.352257 -150.988341) (xy 435.446397 -150.924843) (xy 435.544737 -150.868066) (xy 435.646797 -150.818288)
			(xy 435.752082 -150.77575) (xy 435.860077 -150.74066) (xy 435.970257 -150.713189) (xy 436.082085 -150.693471)
			(xy 436.195016 -150.681601) (xy 436.3085 -150.677639) (xy 436.421984 -150.681601) (xy 436.534915 -150.693471)
			(xy 436.646743 -150.713189) (xy 436.756923 -150.74066) (xy 436.864918 -150.77575) (xy 436.970203 -150.818288)
			(xy 437.072263 -150.868066) (xy 437.170603 -150.924843) (xy 437.264743 -150.988341) (xy 437.354224 -151.058251)
			(xy 437.43861 -151.134233) (xy 437.517491 -151.215916) (xy 437.590481 -151.302903) (xy 437.657226 -151.394769)
			(xy 437.7174 -151.491067) (xy 437.77071 -151.591329) (xy 437.816896 -151.695064) (xy 437.855733 -151.801769)
			(xy 437.887033 -151.910924) (xy 437.910642 -152.021995) (xy 437.926445 -152.134443) (xy 437.934366 -152.247719)
			(xy 437.934862 -152.304496) (xy 437.934366 -152.361273) (xy 437.926445 -152.474549) (xy 437.910642 -152.586997)
			(xy 437.887033 -152.698068) (xy 437.855733 -152.807223) (xy 437.816896 -152.913928) (xy 437.77071 -153.017663)
			(xy 437.7174 -153.117925) (xy 437.657226 -153.214223) (xy 437.590481 -153.306089) (xy 437.517491 -153.393076)
			(xy 437.43861 -153.474759) (xy 437.354224 -153.550741) (xy 437.264743 -153.620651) (xy 437.170603 -153.684149)
			(xy 437.072263 -153.740926) (xy 436.970203 -153.790704) (xy 436.864918 -153.833242) (xy 436.756923 -153.868332)
			(xy 436.646743 -153.895803) (xy 436.534915 -153.915521) (xy 436.421984 -153.927391) (xy 436.3085 -153.931354)
			(xy 436.195016 -153.927391) (xy 436.082085 -153.915521) (xy 435.970257 -153.895803) (xy 435.860077 -153.868332)
			(xy 435.752082 -153.833242) (xy 435.646797 -153.790704) (xy 435.544737 -153.740926) (xy 435.446397 -153.684149)
			(xy 435.352257 -153.620651) (xy 435.262776 -153.550741) (xy 435.17839 -153.474759) (xy 435.099509 -153.393076)
			(xy 435.026519 -153.306089) (xy 434.959774 -153.214223) (xy 434.8996 -153.117925) (xy 434.84629 -153.017663)
			(xy 434.800104 -152.913928) (xy 434.761267 -152.807223) (xy 434.729967 -152.698068) (xy 434.706358 -152.586997)
			(xy 434.690555 -152.474549) (xy 434.682634 -152.361273) (xy 402.814588 -152.361273) (xy 402.818536 -152.380624)
			(xy 402.838536 -152.508011) (xy 402.851895 -152.636265) (xy 402.858578 -152.76504) (xy 402.858986 -152.829514)
			(xy 402.858986 -152.830784) (xy 402.858402 -152.906908) (xy 402.849061 -153.058868) (xy 402.830426 -153.209971)
			(xy 402.802565 -153.359647) (xy 402.765585 -153.507335) (xy 402.743162 -153.580084) (xy 402.741892 -153.583894)
			(xy 402.739352 -153.600404) (xy 402.740114 -153.607262) (xy 402.74609 -153.663142) (xy 402.75241 -153.77536)
			(xy 402.75228 -153.887756) (xy 402.745702 -153.999958) (xy 402.739606 -154.055826) (xy 402.739132 -154.061209)
			(xy 402.740152 -154.071966) (xy 402.741638 -154.077162) (xy 402.7643 -154.15023) (xy 402.801661 -154.298596)
			(xy 402.829816 -154.448981) (xy 402.848661 -154.600814) (xy 402.858122 -154.753519) (xy 402.858732 -154.830018)
			(xy 402.858118 -154.906516) (xy 402.84865 -155.05922) (xy 402.8298 -155.211052) (xy 402.80164 -155.361435)
			(xy 402.764276 -155.509799) (xy 402.741638 -155.582874) (xy 402.740116 -155.588064) (xy 402.739082 -155.598827)
			(xy 402.739606 -155.60421) (xy 402.745735 -155.66046) (xy 402.752277 -155.773434) (xy 402.752276 -155.886598)
			(xy 402.745733 -155.999572) (xy 402.739606 -156.055822) (xy 402.739132 -156.061206) (xy 402.740151 -156.071963)
			(xy 402.741638 -156.077158) (xy 402.7643 -156.150226) (xy 402.801661 -156.298592) (xy 402.829817 -156.448977)
			(xy 402.848661 -156.60081) (xy 402.858123 -156.753515) (xy 402.858732 -156.830014) (xy 402.858118 -156.906512)
			(xy 402.84865 -157.059216) (xy 402.829801 -157.211048) (xy 402.801641 -157.361431) (xy 402.764277 -157.509796)
			(xy 402.741638 -157.58287) (xy 402.740115 -157.58806) (xy 402.739081 -157.598823) (xy 402.739606 -157.604206)
			(xy 402.745735 -157.660456) (xy 402.752277 -157.77343) (xy 402.752276 -157.886594) (xy 402.745733 -157.999568)
			(xy 402.739606 -158.055818) (xy 402.739131 -158.061202) (xy 402.740149 -158.071959) (xy 402.741638 -158.077154)
			(xy 402.7643 -158.150222) (xy 402.801661 -158.298588) (xy 402.829818 -158.448973) (xy 402.848662 -158.600806)
			(xy 402.858124 -158.753511) (xy 402.858732 -158.83001) (xy 402.858118 -158.906508) (xy 402.848651 -159.059212)
			(xy 402.829801 -159.211044) (xy 402.801641 -159.361427) (xy 402.764278 -159.509792) (xy 402.741638 -159.582866)
			(xy 402.740115 -159.588056) (xy 402.739079 -159.59882) (xy 402.739606 -159.604202) (xy 402.745736 -159.660452)
			(xy 402.752277 -159.773426) (xy 402.752277 -159.88659) (xy 402.745734 -159.999564) (xy 402.739606 -160.055814)
			(xy 402.739131 -160.061198) (xy 402.740148 -160.071955) (xy 402.741638 -160.07715) (xy 402.7643 -160.150218)
			(xy 402.801662 -160.298584) (xy 402.829818 -160.448969) (xy 402.848663 -160.600802) (xy 402.858125 -160.753507)
			(xy 402.858732 -160.830006) (xy 402.858119 -160.906504) (xy 402.848651 -161.059208) (xy 402.829802 -161.21104)
			(xy 402.801642 -161.361423) (xy 402.764279 -161.509788) (xy 402.741638 -161.582862) (xy 402.740114 -161.588052)
			(xy 402.739078 -161.598816) (xy 402.739606 -161.604198) (xy 402.745736 -161.660448) (xy 402.752278 -161.773422)
			(xy 402.752277 -161.886586) (xy 402.745735 -161.99956) (xy 402.739606 -162.05581) (xy 402.73913 -162.061194)
			(xy 402.740147 -162.071952) (xy 402.741638 -162.077146) (xy 402.7643 -162.150214) (xy 402.801662 -162.29858)
			(xy 402.829819 -162.448965) (xy 402.848664 -162.600798) (xy 402.858126 -162.753503) (xy 402.858732 -162.830002)
			(xy 402.858119 -162.9065) (xy 402.848652 -163.059204) (xy 402.829802 -163.211036) (xy 402.801643 -163.36142)
			(xy 402.76428 -163.509784) (xy 402.741638 -163.582858) (xy 402.740124 -163.588048) (xy 402.739109 -163.59881)
			(xy 402.739606 -163.604194) (xy 402.745736 -163.660444) (xy 402.752278 -163.773418) (xy 402.752278 -163.886582)
			(xy 402.745736 -163.999556) (xy 402.739606 -164.055806) (xy 402.73913 -164.06119) (xy 402.740146 -164.071948)
			(xy 402.741638 -164.077142) (xy 402.7643 -164.150209) (xy 402.801662 -164.298576) (xy 402.829819 -164.448961)
			(xy 402.848665 -164.600794) (xy 402.858127 -164.753499) (xy 402.858732 -164.829998) (xy 402.858119 -164.906496)
			(xy 402.848652 -165.059201) (xy 402.829803 -165.211032) (xy 402.801644 -165.361416) (xy 402.764281 -165.509781)
			(xy 402.741638 -165.582854) (xy 402.740124 -165.588044) (xy 402.739107 -165.598806) (xy 402.739606 -165.60419)
			(xy 402.745736 -165.66044) (xy 402.752278 -165.773414) (xy 402.752279 -165.886578) (xy 402.745737 -165.999552)
			(xy 402.739606 -166.055802) (xy 402.73913 -166.061186) (xy 402.740145 -166.071944) (xy 402.741638 -166.077138)
			(xy 402.764301 -166.150205) (xy 402.801663 -166.298572) (xy 402.82982 -166.448957) (xy 402.848666 -166.60079)
			(xy 402.858128 -166.753495) (xy 402.858732 -166.829994) (xy 402.858119 -166.906492) (xy 402.848652 -167.059197)
			(xy 402.829804 -167.211028) (xy 402.801645 -167.361412) (xy 402.764282 -167.509777) (xy 402.741638 -167.58285)
			(xy 402.740124 -167.58804) (xy 402.739106 -167.598802) (xy 402.739606 -167.604186) (xy 402.745736 -167.660436)
			(xy 402.752279 -167.77341) (xy 402.752279 -167.886574) (xy 402.745737 -167.999548) (xy 402.739606 -168.055798)
			(xy 402.739139 -168.061181) (xy 402.740174 -168.071933) (xy 402.741638 -168.077134) (xy 402.764301 -168.150201)
			(xy 402.801663 -168.298568) (xy 402.829821 -168.448953) (xy 402.848667 -168.600786) (xy 402.858129 -168.753491)
			(xy 402.858732 -168.82999) (xy 402.858107 -168.907368) (xy 402.848411 -169.061822) (xy 402.829123 -169.215372)
			(xy 402.815298 -169.291508) (xy 402.814536 -169.29481) (xy 402.81225 -169.307256) (xy 402.81733 -169.328338)
			(xy 402.82368 -169.33672) (xy 402.824442 -169.33799) (xy 402.874988 -169.399458) (xy 402.882562 -169.407776)
			(xy 402.902869 -169.417386) (xy 402.914104 -169.418) (xy 406.658318 -169.418)
		)
		(stroke
			(width 0)
			(type solid)
		)
		(fill yes)
		(layer "B.Cu")
		(net "GND")
	)
	(gr_poly
		(pts
			(arc
				(start 192.800224 -51.05908)
				(mid 192.819747 -51.055179)
				(end 192.836292 -51.044094)
			)
			(arc
				(start 193.053462 -50.826924)
				(mid 193.064573 -50.81039)
				(end 193.068448 -50.790856)
			)
			(arc
				(start 193.068448 -46.88586)
				(mid 193.064547 -46.866337)
				(end 193.053462 -46.849792)
			)
			(arc
				(start 189.652656 -43.448986)
				(mid 189.636122 -43.437875)
				(end 189.616588 -43.434)
			)
			(arc
				(start 186.057794 -43.434)
				(mid 186.038271 -43.437901)
				(end 186.021726 -43.448986)
			)
			(arc
				(start 182.666386 -46.804326)
				(mid 182.655275 -46.82086)
				(end 182.6514 -46.840394)
			)
			(arc
				(start 182.6514 -50.663602)
				(mid 182.655301 -50.683125)
				(end 182.666386 -50.69967)
			)
			(arc
				(start 183.01081 -51.044094)
				(mid 183.027344 -51.055205)
				(end 183.046878 -51.05908)
			)
		)
		(stroke
			(width 0)
			(type solid)
		)
		(fill yes)
		(layer "In1.Cu")
		(net "P52V_2_FUSE_1")
	)
	(gr_poly
		(pts
			(arc
				(start 257.287522 -51.05908)
				(mid 257.307045 -51.055179)
				(end 257.32359 -51.044094)
			)
			(arc
				(start 257.668014 -50.69967)
				(mid 257.679125 -50.683136)
				(end 257.683 -50.663602)
			)
			(arc
				(start 257.683 -46.840394)
				(mid 257.679099 -46.820871)
				(end 257.668014 -46.804326)
			)
			(arc
				(start 254.312674 -43.448986)
				(mid 254.29614 -43.437875)
				(end 254.276606 -43.434)
			)
			(arc
				(start 250.717812 -43.434)
				(mid 250.698289 -43.437901)
				(end 250.681744 -43.448986)
			)
			(arc
				(start 247.280938 -46.849792)
				(mid 247.269827 -46.866326)
				(end 247.265952 -46.88586)
			)
			(arc
				(start 247.265952 -50.790856)
				(mid 247.269853 -50.810379)
				(end 247.280938 -50.826924)
			)
			(arc
				(start 247.498108 -51.044094)
				(mid 247.514642 -51.055205)
				(end 247.534176 -51.05908)
			)
		)
		(stroke
			(width 0)
			(type solid)
		)
		(fill yes)
		(layer "In1.Cu")
		(net "P52V_1_FUSE_1")
	)
	(gr_poly
		(pts
			(arc
				(start 136.007856 -80.01)
				(mid 136.027379 -80.006099)
				(end 136.043924 -79.995014)
			)
			(arc
				(start 136.343644 -79.695294)
				(mid 136.354755 -79.67876)
				(end 136.35863 -79.659226)
			)
			(arc
				(start 136.35863 -68.303902)
				(mid 136.397314 -68.109513)
				(end 136.507474 -67.944746)
			)
			(arc
				(start 137.49655 -66.95567)
				(mid 137.661318 -66.845512)
				(end 137.855706 -66.806826)
			)
			(arc
				(start 139.442444 -66.806826)
				(mid 139.460379 -66.803555)
				(end 139.475972 -66.794126)
			)
			(arc
				(start 139.475972 -66.794126)
				(mid 139.749442 -66.630021)
				(end 140.06322 -66.572892)
			)
			(arc
				(start 140.06322 -66.572892)
				(mid 140.377013 -66.629983)
				(end 140.650468 -66.794126)
			)
			(arc
				(start 140.650468 -66.794126)
				(mid 140.666078 -66.80351)
				(end 140.683996 -66.806826)
			)
			(arc
				(start 142.0876 -66.806826)
				(mid 142.123521 -66.791947)
				(end 142.1384 -66.756026)
			)
			(xy 142.1384 -64.131698)
			(arc
				(start 142.13713 -64.12611)
				(mid 142.120011 -64.026684)
				(end 142.11427 -63.925958)
			)
			(arc
				(start 142.11427 -63.925958)
				(mid 142.12002 -63.825234)
				(end 142.13713 -63.725806)
			)
			(xy 142.1384 -63.720218) (xy 142.1384 -63.025782)
			(arc
				(start 142.13713 -63.020194)
				(mid 142.120011 -62.920768)
				(end 142.11427 -62.820042)
			)
			(arc
				(start 142.11427 -62.820042)
				(mid 142.12002 -62.719318)
				(end 142.13713 -62.61989)
			)
			(xy 142.1384 -62.614302)
			(arc
				(start 142.1384 -47.729394)
				(mid 142.134499 -47.709871)
				(end 142.123414 -47.693326)
			)
			(arc
				(start 141.308074 -46.877986)
				(mid 141.29154 -46.866875)
				(end 141.272006 -46.863)
			)
			(arc
				(start 123.573794 -46.863)
				(mid 123.554271 -46.866901)
				(end 123.537726 -46.877986)
			)
			(arc
				(start 123.357386 -47.058326)
				(mid 123.346275 -47.07486)
				(end 123.3424 -47.094394)
			)
			(arc
				(start 123.3424 -79.651606)
				(mid 123.346301 -79.671129)
				(end 123.357386 -79.687674)
			)
			(arc
				(start 123.664726 -79.995014)
				(mid 123.68126 -80.006125)
				(end 123.700794 -80.01)
			)
		)
		(stroke
			(width 0)
			(type solid)
		)
		(fill yes)
		(layer "In1.Cu")
		(net "P52V_HS2_DRAIN_1")
	)
	(gr_poly
		(pts
			(arc
				(start 323.745606 -80.01)
				(mid 323.765129 -80.006099)
				(end 323.781674 -79.995014)
			)
			(arc
				(start 324.089014 -79.687674)
				(mid 324.100125 -79.67114)
				(end 324.104 -79.651606)
			)
			(arc
				(start 324.104 -47.094394)
				(mid 324.100099 -47.074871)
				(end 324.089014 -47.058326)
			)
			(arc
				(start 323.908674 -46.877986)
				(mid 323.89214 -46.866875)
				(end 323.872606 -46.863)
			)
			(arc
				(start 306.225194 -46.863)
				(mid 306.205671 -46.866901)
				(end 306.189126 -46.877986)
			)
			(arc
				(start 305.322986 -47.744126)
				(mid 305.311875 -47.76066)
				(end 305.308 -47.780194)
			)
			(arc
				(start 305.308 -62.242954)
				(mid 305.310753 -62.259451)
				(end 305.318668 -62.274196)
			)
			(arc
				(start 305.318668 -62.274196)
				(mid 305.457751 -62.531519)
				(end 305.505866 -62.820042)
			)
			(arc
				(start 305.505866 -62.820042)
				(mid 305.462214 -63.095019)
				(end 305.335686 -63.343028)
			)
			(arc
				(start 305.335686 -63.343028)
				(mid 305.325927 -63.373)
				(end 305.335686 -63.402972)
			)
			(arc
				(start 305.335686 -63.402972)
				(mid 305.462208 -63.650983)
				(end 305.505866 -63.925958)
			)
			(arc
				(start 305.505866 -63.925958)
				(mid 305.45777 -64.214488)
				(end 305.318668 -64.471804)
			)
			(arc
				(start 305.318668 -64.471804)
				(mid 305.310697 -64.48653)
				(end 305.308 -64.503046)
			)
			(arc
				(start 305.308 -66.113406)
				(mid 305.311901 -66.132929)
				(end 305.322986 -66.149474)
			)
			(arc
				(start 305.994816 -66.821304)
				(mid 306.01135 -66.832415)
				(end 306.030884 -66.83629)
			)
			(arc
				(start 306.81422 -66.83629)
				(mid 306.833245 -66.832593)
				(end 306.849526 -66.822066)
			)
			(arc
				(start 306.849526 -66.822066)
				(mid 307.467 -66.57292)
				(end 308.084474 -66.822066)
			)
			(arc
				(start 308.084474 -66.822066)
				(mid 308.100741 -66.832627)
				(end 308.11978 -66.83629)
			)
			(arc
				(start 309.808372 -66.83629)
				(mid 310.002761 -66.874974)
				(end 310.167528 -66.985134)
			)
			(arc
				(start 311.081166 -67.898772)
				(mid 311.191324 -68.06354)
				(end 311.23001 -68.257928)
			)
			(arc
				(start 311.23001 -79.613252)
				(mid 311.233911 -79.632775)
				(end 311.244996 -79.64932)
			)
			(arc
				(start 311.59069 -79.995014)
				(mid 311.607224 -80.006125)
				(end 311.626758 -80.01)
			)
		)
		(stroke
			(width 0)
			(type solid)
		)
		(fill yes)
		(layer "In1.Cu")
		(net "P52V_HS1_DRAIN_1")
	)
	(gr_poly
		(pts
			(arc
				(start 141.221206 -45.847)
				(mid 141.240729 -45.843099)
				(end 141.257274 -45.832014)
			)
			(arc
				(start 142.123414 -44.965874)
				(mid 142.134525 -44.94934)
				(end 142.1384 -44.929806)
			)
			(arc
				(start 142.1384 -41.667176)
				(mid 142.131291 -41.641003)
				(end 142.11173 -41.622218)
			)
			(arc
				(start 142.11173 -41.622218)
				(mid 141.769734 -41.29524)
				(end 141.643862 -40.839136)
			)
			(arc
				(start 141.643862 -40.839136)
				(mid 141.647416 -40.759442)
				(end 141.658086 -40.680386)
			)
			(xy 141.660372 -40.66794) (xy 141.653006 -40.644318)
			(arc
				(start 141.511274 -40.502586)
				(mid 141.49474 -40.491475)
				(end 141.475206 -40.4876)
			)
			(arc
				(start 139.1666 -40.4876)
				(mid 138.972211 -40.448916)
				(end 138.807444 -40.338756)
			)
			(arc
				(start 137.689844 -39.221156)
				(mid 137.579686 -39.056388)
				(end 137.541 -38.862)
			)
			(arc
				(start 137.541 -33.8328)
				(mid 137.579684 -33.638411)
				(end 137.689844 -33.473644)
			)
			(arc
				(start 137.989564 -33.173924)
				(mid 138.154332 -33.063766)
				(end 138.34872 -33.02508)
			)
			(arc
				(start 139.38885 -33.02508)
				(mid 139.408704 -33.02104)
				(end 139.425426 -33.009586)
			)
			(arc
				(start 139.425426 -33.009586)
				(mid 140.06322 -32.740107)
				(end 140.701014 -33.009586)
			)
			(arc
				(start 140.701014 -33.009586)
				(mid 140.717722 -33.021073)
				(end 140.73759 -33.02508)
			)
			(arc
				(start 141.520926 -33.02508)
				(mid 141.540449 -33.021179)
				(end 141.556994 -33.010094)
			)
			(arc
				(start 142.123414 -32.443674)
				(mid 142.134525 -32.42714)
				(end 142.1384 -32.407606)
			)
			(xy 142.1384 -30.298898)
			(arc
				(start 142.13713 -30.29331)
				(mid 142.120011 -30.193884)
				(end 142.11427 -30.093158)
			)
			(arc
				(start 142.11427 -30.093158)
				(mid 142.12002 -29.992434)
				(end 142.13713 -29.893006)
			)
			(xy 142.1384 -29.887418) (xy 142.1384 -29.192982)
			(arc
				(start 142.13713 -29.187394)
				(mid 142.120011 -29.087968)
				(end 142.11427 -28.987242)
			)
			(arc
				(start 142.11427 -28.987242)
				(mid 142.12002 -28.886518)
				(end 142.13713 -28.78709)
			)
			(xy 142.1384 -28.781502)
			(arc
				(start 142.1384 -13.439394)
				(mid 142.134499 -13.419871)
				(end 142.123414 -13.403326)
			)
			(arc
				(start 141.689074 -12.968986)
				(mid 141.67254 -12.957875)
				(end 141.653006 -12.954)
			)
			(arc
				(start 123.700794 -12.954)
				(mid 123.681271 -12.957901)
				(end 123.664726 -12.968986)
			)
			(arc
				(start 123.357386 -13.276326)
				(mid 123.346275 -13.29286)
				(end 123.3424 -13.312394)
			)
			(arc
				(start 123.3424 -45.615606)
				(mid 123.346301 -45.635129)
				(end 123.357386 -45.651674)
			)
			(arc
				(start 123.537726 -45.832014)
				(mid 123.55426 -45.843125)
				(end 123.573794 -45.847)
			)
		)
		(stroke
			(width 0)
			(type solid)
		)
		(fill yes)
		(layer "In1.Cu")
		(net "P52V_HS2_DRAIN_2")
	)
	(gr_poly
		(pts
			(arc
				(start 323.872606 -45.847)
				(mid 323.892129 -45.843099)
				(end 323.908674 -45.832014)
			)
			(arc
				(start 324.089014 -45.651674)
				(mid 324.100125 -45.63514)
				(end 324.104 -45.615606)
			)
			(arc
				(start 324.104 -13.312394)
				(mid 324.100099 -13.292871)
				(end 324.089014 -13.276326)
			)
			(arc
				(start 323.781674 -12.968986)
				(mid 323.76514 -12.957875)
				(end 323.745606 -12.954)
			)
			(arc
				(start 305.793394 -12.954)
				(mid 305.773871 -12.957901)
				(end 305.757326 -12.968986)
			)
			(arc
				(start 305.322986 -13.403326)
				(mid 305.311875 -13.41986)
				(end 305.308 -13.439394)
			)
			(arc
				(start 305.308 -28.410154)
				(mid 305.310753 -28.426651)
				(end 305.318668 -28.441396)
			)
			(arc
				(start 305.318668 -28.441396)
				(mid 305.457751 -28.698719)
				(end 305.505866 -28.987242)
			)
			(arc
				(start 305.505866 -28.987242)
				(mid 305.462214 -29.262219)
				(end 305.335686 -29.510228)
			)
			(arc
				(start 305.335686 -29.510228)
				(mid 305.325927 -29.5402)
				(end 305.335686 -29.570172)
			)
			(arc
				(start 305.335686 -29.570172)
				(mid 305.462208 -29.818183)
				(end 305.505866 -30.093158)
			)
			(arc
				(start 305.505866 -30.093158)
				(mid 305.45777 -30.381688)
				(end 305.318668 -30.639004)
			)
			(arc
				(start 305.318668 -30.639004)
				(mid 305.310697 -30.65373)
				(end 305.308 -30.670246)
			)
			(arc
				(start 305.308 -32.712406)
				(mid 305.311901 -32.731929)
				(end 305.322986 -32.748474)
			)
			(arc
				(start 305.53152 -32.957008)
				(mid 305.548054 -32.968119)
				(end 305.567588 -32.971994)
			)
			(arc
				(start 306.848764 -32.971994)
				(mid 306.866531 -32.968786)
				(end 306.882038 -32.959548)
			)
			(arc
				(start 306.882038 -32.959548)
				(mid 307.467 -32.740071)
				(end 308.051962 -32.959548)
			)
			(arc
				(start 308.051962 -32.959548)
				(mid 308.067477 -32.968763)
				(end 308.085236 -32.971994)
			)
			(arc
				(start 309.723028 -32.971994)
				(mid 309.917417 -33.010678)
				(end 310.082184 -33.120838)
			)
			(arc
				(start 311.103518 -34.142172)
				(mid 311.213676 -34.30694)
				(end 311.252362 -34.501328)
			)
			(arc
				(start 311.252362 -39.039038)
				(mid 311.213678 -39.233427)
				(end 311.103518 -39.398194)
			)
			(arc
				(start 309.629556 -40.872156)
				(mid 309.464788 -40.982314)
				(end 309.2704 -41.021)
			)
			(arc
				(start 305.844194 -41.021)
				(mid 305.824671 -41.024901)
				(end 305.808126 -41.035986)
			)
			(xy 305.748944 -41.095168)
			(arc
				(start 305.745134 -41.102788)
				(mid 305.574995 -41.341081)
				(end 305.336702 -41.51122)
			)
			(xy 305.329082 -41.51503)
			(arc
				(start 305.322986 -41.521126)
				(mid 305.311875 -41.53766)
				(end 305.308 -41.557194)
			)
			(arc
				(start 305.308 -44.980606)
				(mid 305.311901 -45.000129)
				(end 305.322986 -45.016674)
			)
			(arc
				(start 306.138326 -45.832014)
				(mid 306.15486 -45.843125)
				(end 306.174394 -45.847)
			)
		)
		(stroke
			(width 0)
			(type solid)
		)
		(fill yes)
		(layer "In1.Cu")
		(net "P52V_HS1_DRAIN_2")
	)
	(gr_poly
		(pts
			(arc
				(start 301.02302 -66.83629)
				(mid 301.042045 -66.832593)
				(end 301.058326 -66.822066)
			)
			(arc
				(start 301.058326 -66.822066)
				(mid 301.6758 -66.57292)
				(end 302.293274 -66.822066)
			)
			(arc
				(start 302.293274 -66.822066)
				(mid 302.309541 -66.832627)
				(end 302.32858 -66.83629)
			)
			(arc
				(start 303.696116 -66.83629)
				(mid 303.715639 -66.832389)
				(end 303.732184 -66.821304)
			)
			(arc
				(start 304.277014 -66.276474)
				(mid 304.288125 -66.25994)
				(end 304.292 -66.240406)
			)
			(arc
				(start 304.292 -64.788288)
				(mid 304.283781 -64.760329)
				(end 304.26152 -64.741552)
			)
			(arc
				(start 304.26152 -64.741552)
				(mid 303.872479 -64.413552)
				(end 303.72685 -63.925958)
			)
			(arc
				(start 303.72685 -63.925958)
				(mid 303.770502 -63.650981)
				(end 303.89703 -63.402972)
			)
			(arc
				(start 303.89703 -63.402972)
				(mid 303.906789 -63.373)
				(end 303.89703 -63.343028)
			)
			(arc
				(start 303.89703 -63.343028)
				(mid 303.770508 -63.095017)
				(end 303.72685 -62.820042)
			)
			(arc
				(start 303.72685 -62.820042)
				(mid 303.872423 -62.33241)
				(end 304.26152 -62.004448)
			)
			(arc
				(start 304.26152 -62.004448)
				(mid 304.283721 -61.985633)
				(end 304.292 -61.957712)
			)
			(arc
				(start 304.292 -42.065194)
				(mid 304.288099 -42.045671)
				(end 304.277014 -42.029126)
			)
			(xy 303.762918 -41.51503)
			(arc
				(start 303.755298 -41.51122)
				(mid 303.517005 -41.341081)
				(end 303.346866 -41.102788)
			)
			(arc
				(start 303.346866 -41.102788)
				(mid 303.342572 -41.095678)
				(end 303.337214 -41.089326)
			)
			(arc
				(start 303.283874 -41.035986)
				(mid 303.26734 -41.024875)
				(end 303.247806 -41.021)
			)
			(arc
				(start 300.6852 -41.021)
				(mid 300.490811 -40.982316)
				(end 300.326044 -40.872156)
			)
			(arc
				(start 298.809156 -39.355268)
				(mid 298.698998 -39.1905)
				(end 298.660312 -38.996112)
			)
			(arc
				(start 298.660312 -33.576768)
				(mid 298.698996 -33.382379)
				(end 298.809156 -33.217612)
			)
			(arc
				(start 298.90593 -33.120838)
				(mid 299.070698 -33.01068)
				(end 299.265086 -32.971994)
			)
			(arc
				(start 301.057564 -32.971994)
				(mid 301.075331 -32.968786)
				(end 301.090838 -32.959548)
			)
			(arc
				(start 301.090838 -32.959548)
				(mid 301.6758 -32.740071)
				(end 302.260762 -32.959548)
			)
			(arc
				(start 302.260762 -32.959548)
				(mid 302.276277 -32.968763)
				(end 302.294036 -32.971994)
			)
			(arc
				(start 304.007012 -32.971994)
				(mid 304.026535 -32.968093)
				(end 304.04308 -32.957008)
			)
			(arc
				(start 304.277014 -32.723074)
				(mid 304.288125 -32.70654)
				(end 304.292 -32.687006)
			)
			(arc
				(start 304.292 -30.955488)
				(mid 304.283781 -30.927529)
				(end 304.26152 -30.908752)
			)
			(arc
				(start 304.26152 -30.908752)
				(mid 303.872479 -30.580752)
				(end 303.72685 -30.093158)
			)
			(arc
				(start 303.72685 -30.093158)
				(mid 303.770502 -29.818181)
				(end 303.89703 -29.570172)
			)
			(arc
				(start 303.89703 -29.570172)
				(mid 303.906789 -29.5402)
				(end 303.89703 -29.510228)
			)
			(arc
				(start 303.89703 -29.510228)
				(mid 303.770508 -29.262217)
				(end 303.72685 -28.987242)
			)
			(arc
				(start 303.72685 -28.987242)
				(mid 303.872423 -28.49961)
				(end 304.26152 -28.171648)
			)
			(arc
				(start 304.26152 -28.171648)
				(mid 304.283721 -28.152833)
				(end 304.292 -28.124912)
			)
			(arc
				(start 304.292 -13.439394)
				(mid 304.288099 -13.419871)
				(end 304.277014 -13.403326)
			)
			(arc
				(start 303.842674 -12.968986)
				(mid 303.82614 -12.957875)
				(end 303.806606 -12.954)
			)
			(arc
				(start 283.585412 -12.954)
				(mid 283.565889 -12.957901)
				(end 283.549344 -12.968986)
			)
			(arc
				(start 280.176986 -16.341344)
				(mid 280.165875 -16.357878)
				(end 280.162 -16.377412)
			)
			(arc
				(start 280.162 -27.182318)
				(mid 280.123316 -27.376707)
				(end 280.013156 -27.541474)
			)
			(arc
				(start 278.747474 -28.807156)
				(mid 278.582706 -28.917314)
				(end 278.388318 -28.956)
			)
			(arc
				(start 231.371394 -28.956)
				(mid 231.351871 -28.959901)
				(end 231.335326 -28.970986)
			)
			(arc
				(start 229.884986 -30.421326)
				(mid 229.873875 -30.43786)
				(end 229.87 -30.457394)
			)
			(arc
				(start 229.87 -46.758606)
				(mid 229.873901 -46.778129)
				(end 229.884986 -46.794674)
			)
			(arc
				(start 230.446326 -47.356014)
				(mid 230.46286 -47.367125)
				(end 230.482394 -47.371)
			)
			(arc
				(start 242.73256 -47.371)
				(mid 242.752083 -47.367099)
				(end 242.768628 -47.356014)
			)
			(arc
				(start 248.63425 -41.490392)
				(mid 248.799018 -41.380234)
				(end 248.993406 -41.341548)
			)
			(arc
				(start 255.891538 -41.341548)
				(mid 256.085927 -41.380232)
				(end 256.250694 -41.490392)
			)
			(arc
				(start 258.814316 -44.054014)
				(mid 258.83085 -44.065125)
				(end 258.850384 -44.069)
			)
			(arc
				(start 268.097 -44.069)
				(mid 268.291389 -44.107684)
				(end 268.456156 -44.217844)
			)
			(arc
				(start 282.440126 -58.201814)
				(mid 282.45666 -58.212925)
				(end 282.476194 -58.2168)
			)
			(arc
				(start 293.4208 -58.2168)
				(mid 293.615189 -58.255484)
				(end 293.779956 -58.365644)
			)
			(arc
				(start 297.081956 -61.667644)
				(mid 297.192114 -61.832412)
				(end 297.2308 -62.0268)
			)
			(arc
				(start 297.2308 -65.478406)
				(mid 297.234701 -65.497929)
				(end 297.245786 -65.514474)
			)
			(arc
				(start 298.552616 -66.821304)
				(mid 298.56915 -66.832415)
				(end 298.588684 -66.83629)
			)
		)
		(stroke
			(width 0)
			(type solid)
		)
		(fill yes)
		(layer "In1.Cu")
		(net "P52V_1")
	)
	(gr_poly
		(pts
			(xy 145.801842 -66.806826) (xy 145.811034 -66.806436) (xy 145.828224 -66.799921) (xy 145.83537 -66.794126)
			(xy 145.865785 -66.768004) (xy 145.930547 -66.720732) (xy 145.999299 -66.679479) (xy 146.071485 -66.644579)
			(xy 146.146518 -66.616315) (xy 146.223789 -66.594916) (xy 146.302673 -66.580557) (xy 146.382528 -66.573354)
			(xy 146.422618 -66.572892) (xy 146.462709 -66.573322) (xy 146.542568 -66.580516) (xy 146.621455 -66.594871)
			(xy 146.69873 -66.61627) (xy 146.773763 -66.644539) (xy 146.845947 -66.679449) (xy 146.914695 -66.720717)
			(xy 146.979448 -66.768006) (xy 147.009866 -66.794126) (xy 147.017023 -66.799901) (xy 147.034207 -66.806413)
			(xy 147.043394 -66.806826) (xy 148.436838 -66.806826) (xy 148.446906 -66.806397) (xy 148.465503 -66.798675)
			(xy 148.472906 -66.79184) (xy 160.253934 -55.010812) (xy 160.277812 -54.987653) (xy 160.330574 -54.94714)
			(xy 160.388174 -54.913864) (xy 160.449626 -54.888395) (xy 160.513878 -54.871169) (xy 160.579829 -54.862481)
			(xy 160.61309 -54.861968) (xy 175.379888 -54.861968) (xy 175.389959 -54.861546) (xy 175.408563 -54.853831)
			(xy 175.415956 -54.846982) (xy 175.779176 -54.483762) (xy 175.786019 -54.476363) (xy 175.793744 -54.457764)
			(xy 175.794162 -54.447694) (xy 175.794162 -53.658516) (xy 175.793723 -53.648453) (xy 175.785983 -53.629875)
			(xy 175.779176 -53.622448) (xy 173.785022 -51.628294) (xy 173.777619 -51.62146) (xy 173.759021 -51.613755)
			(xy 173.748954 -51.613308) (xy 172.583348 -51.613308) (xy 172.550087 -51.61279) (xy 172.484133 -51.604108)
			(xy 172.419878 -51.586888) (xy 172.358423 -51.561423) (xy 172.300819 -51.528151) (xy 172.248054 -51.48764)
			(xy 172.224192 -51.464464) (xy 171.815506 -51.055778) (xy 171.792346 -51.0319) (xy 171.751833 -50.979138)
			(xy 171.718556 -50.921538) (xy 171.693086 -50.860086) (xy 171.675859 -50.795834) (xy 171.667169 -50.729883)
			(xy 171.666662 -50.696622) (xy 171.666662 -43.570398) (xy 171.667183 -43.537138) (xy 171.67587 -43.471187)
			(xy 171.693095 -43.406936) (xy 171.718563 -43.345483) (xy 171.751837 -43.287883) (xy 171.792348 -43.235122)
			(xy 171.815506 -43.211242) (xy 173.556676 -41.470072) (xy 173.580556 -41.446916) (xy 173.63332 -41.406411)
			(xy 173.690921 -41.373143) (xy 173.752373 -41.347681) (xy 173.816624 -41.330462) (xy 173.882573 -41.32178)
			(xy 173.915832 -41.321228) (xy 191.747394 -41.321228) (xy 191.780655 -41.321749) (xy 191.846606 -41.330434)
			(xy 191.910859 -41.347657) (xy 191.972313 -41.373123) (xy 192.029915 -41.406395) (xy 192.08268 -41.446904)
			(xy 192.10655 -41.470072) (xy 197.992492 -47.356014) (xy 197.999886 -47.362871) (xy 198.018485 -47.370622)
			(xy 198.02856 -47.371) (xy 209.852006 -47.371) (xy 209.862076 -47.370576) (xy 209.880679 -47.36286)
			(xy 209.888074 -47.356014) (xy 210.449414 -46.794674) (xy 210.456266 -46.787278) (xy 210.464004 -46.768679)
			(xy 210.4644 -46.758606) (xy 210.4644 -30.457394) (xy 210.463976 -30.447324) (xy 210.45626 -30.428721)
			(xy 210.449414 -30.421326) (xy 208.999074 -28.970986) (xy 208.991678 -28.964134) (xy 208.973079 -28.956396)
			(xy 208.963006 -28.956) (xy 161.946082 -28.956) (xy 161.912822 -28.955477) (xy 161.846873 -28.946788)
			(xy 161.782624 -28.929561) (xy 161.721174 -28.90409) (xy 161.663577 -28.870813) (xy 161.610819 -28.830299)
			(xy 161.586926 -28.807156) (xy 160.321244 -27.541474) (xy 160.298087 -27.517595) (xy 160.257578 -27.464831)
			(xy 160.224306 -27.407231) (xy 160.19884 -27.345779) (xy 160.181615 -27.281528) (xy 160.172927 -27.215578)
			(xy 160.1724 -27.182318) (xy 160.1724 -16.377412) (xy 160.171979 -16.367341) (xy 160.164268 -16.348733)
			(xy 160.157414 -16.341344) (xy 156.785056 -12.968986) (xy 156.777659 -12.962137) (xy 156.75906 -12.954405)
			(xy 156.748988 -12.954) (xy 143.639794 -12.954) (xy 143.629724 -12.954424) (xy 143.611121 -12.96214)
			(xy 143.603726 -12.968986) (xy 143.169386 -13.403326) (xy 143.162534 -13.410722) (xy 143.154796 -13.429321)
			(xy 143.1544 -13.439394) (xy 143.1544 -28.086812) (xy 143.176752 -28.114498) (xy 143.194278 -28.118308)
			(xy 143.236229 -28.128019) (xy 143.318173 -28.154495) (xy 143.397174 -28.188768) (xy 143.472493 -28.230517)
			(xy 143.543424 -28.279349) (xy 143.609303 -28.334808) (xy 143.669514 -28.396375) (xy 143.723492 -28.463473)
			(xy 143.770733 -28.535474) (xy 143.810793 -28.611704) (xy 143.843298 -28.691449) (xy 143.867943 -28.773962)
			(xy 143.884498 -28.858471) (xy 143.892807 -28.944184) (xy 143.893286 -28.987242) (xy 143.89284 -29.027188)
			(xy 143.885653 -29.106756) (xy 143.87136 -29.185359) (xy 143.850075 -29.262363) (xy 143.82197 -29.337149)
			(xy 143.787272 -29.409112) (xy 143.746259 -29.477674) (xy 143.723106 -29.510228) (xy 143.717172 -29.519192)
			(xy 143.712701 -29.5402) (xy 143.717172 -29.561208) (xy 143.723106 -29.570172) (xy 143.746249 -29.602733)
			(xy 143.787257 -29.671295) (xy 143.821951 -29.743258) (xy 143.850052 -29.818043) (xy 143.871334 -29.895046)
			(xy 143.885626 -29.973647) (xy 143.892811 -30.053213) (xy 143.893286 -30.093158) (xy 143.892778 -30.136213)
			(xy 143.884453 -30.22192) (xy 143.867886 -30.306421) (xy 143.843233 -30.388926) (xy 143.810723 -30.468664)
			(xy 143.770662 -30.544888) (xy 143.723424 -30.616884) (xy 143.669451 -30.68398) (xy 143.609247 -30.745547)
			(xy 143.543378 -30.80101) (xy 143.472457 -30.849849) (xy 143.39715 -30.891608) (xy 143.318161 -30.925895)
			(xy 143.236229 -30.95239) (xy 143.194278 -30.962092) (xy 143.176752 -30.965902) (xy 143.1544 -30.993588)
			(xy 143.1544 -32.458406) (xy 143.154824 -32.468476) (xy 143.16254 -32.487079) (xy 143.169386 -32.494474)
			(xy 143.685006 -33.010094) (xy 143.692405 -33.01694) (xy 143.711003 -33.024673) (xy 143.721074 -33.02508)
			(xy 145.18005 -33.02508) (xy 145.190294 -33.024611) (xy 145.209156 -33.016612) (xy 145.216626 -33.009586)
			(xy 145.246136 -32.979918) (xy 145.309846 -32.925658) (xy 145.37837 -32.877621) (xy 145.451103 -32.836233)
			(xy 145.527403 -32.801859) (xy 145.606593 -32.774803) (xy 145.687975 -32.755305) (xy 145.770828 -32.743537)
			(xy 145.85442 -32.739602) (xy 145.938012 -32.743537) (xy 146.020865 -32.755305) (xy 146.102247 -32.774803)
			(xy 146.181437 -32.801859) (xy 146.257737 -32.836233) (xy 146.33047 -32.877621) (xy 146.398994 -32.925658)
			(xy 146.462704 -32.979918) (xy 146.492214 -33.009586) (xy 146.499661 -33.016649) (xy 146.518536 -33.024665)
			(xy 146.52879 -33.02508) (xy 147.35048 -33.02508) (xy 147.383741 -33.0256) (xy 147.449692 -33.034285)
			(xy 147.513945 -33.051508) (xy 147.575399 -33.076974) (xy 147.633 -33.110248) (xy 147.685763 -33.150759)
			(xy 147.709636 -33.173924) (xy 148.212556 -33.676844) (xy 148.235712 -33.700724) (xy 148.276218 -33.753488)
			(xy 148.309489 -33.811089) (xy 148.334953 -33.87254) (xy 148.352175 -33.936791) (xy 148.360861 -34.002741)
			(xy 148.3614 -34.036) (xy 148.3614 -38.3794) (xy 148.360879 -38.41266) (xy 148.352191 -38.47861)
			(xy 148.334966 -38.542861) (xy 148.309497 -38.604312) (xy 148.276221 -38.661911) (xy 148.235708 -38.714671)
			(xy 148.212556 -38.738556) (xy 146.612356 -40.338756) (xy 146.588476 -40.361912) (xy 146.535712 -40.402418)
			(xy 146.478111 -40.435689) (xy 146.41666 -40.461153) (xy 146.352409 -40.478375) (xy 146.286459 -40.487061)
			(xy 146.2532 -40.4876) (xy 144.292574 -40.4876) (xy 144.280913 -40.48818) (xy 144.260011 -40.49852)
			(xy 144.252442 -40.507412) (xy 144.1958 -40.58031) (xy 144.191228 -40.60317) (xy 144.194276 -40.614854)
			(xy 144.203403 -40.65153) (xy 144.216167 -40.72603) (xy 144.222575 -40.801343) (xy 144.222978 -40.839136)
			(xy 144.222502 -40.880237) (xy 144.214914 -40.962088) (xy 144.199806 -41.042889) (xy 144.177307 -41.121952)
			(xy 144.14761 -41.198602) (xy 144.110966 -41.272185) (xy 144.06769 -41.342073) (xy 144.01815 -41.407669)
			(xy 143.962768 -41.468415) (xy 143.902019 -41.523792) (xy 143.836418 -41.573327) (xy 143.766527 -41.616598)
			(xy 143.692942 -41.653236) (xy 143.61629 -41.682928) (xy 143.537225 -41.705421) (xy 143.456422 -41.720523)
			(xy 143.374571 -41.728105) (xy 143.33347 -41.728644) (xy 143.316052 -41.728547) (xy 143.281244 -41.727151)
			(xy 143.263874 -41.72585) (xy 143.253206 -41.725088) (xy 143.233394 -41.731946) (xy 143.170656 -41.789858)
			(xy 143.16328 -41.797381) (xy 143.154871 -41.816672) (xy 143.1544 -41.827196) (xy 143.1544 -60.8863)
			(xy 149.598912 -60.8863) (xy 149.602942 -60.801701) (xy 149.614995 -60.717868) (xy 149.634963 -60.635561)
			(xy 149.662664 -60.555524) (xy 149.697848 -60.478483) (xy 149.740195 -60.405135) (xy 149.789323 -60.336145)
			(xy 149.844787 -60.272137) (xy 149.906083 -60.213691) (xy 149.972658 -60.161336) (xy 150.043908 -60.115546)
			(xy 150.119188 -60.076737) (xy 150.197816 -60.04526) (xy 150.279081 -60.021399) (xy 150.362245 -60.00537)
			(xy 150.446557 -59.99732) (xy 150.488904 -59.996832) (xy 150.528495 -59.997261) (xy 150.607366 -60.004283)
			(xy 150.685298 -60.018299) (xy 150.7236 -60.028328) (xy 150.727765 -60.029405) (xy 150.73632 -60.030297)
			(xy 150.740618 -60.030106) (xy 150.755901 -60.02907) (xy 150.786515 -60.027929) (xy 150.801832 -60.02782)
			(xy 150.832093 -60.028115) (xy 150.892471 -60.032308) (xy 150.922482 -60.036202) (xy 150.927916 -60.036809)
			(xy 150.938811 -60.035912) (xy 150.944072 -60.034424) (xy 150.985684 -60.022469) (xy 151.070635 -60.005731)
			(xy 151.156812 -59.997337) (xy 151.200104 -59.996832) (xy 151.241719 -59.997325) (xy 151.324585 -60.005093)
			(xy 151.406363 -60.02057) (xy 151.446484 -60.03163) (xy 151.451259 -60.032927) (xy 151.461111 -60.033821)
			(xy 151.466042 -60.033408) (xy 151.490408 -60.030832) (xy 151.539331 -60.028037) (xy 151.563832 -60.02782)
			(xy 151.606191 -60.028361) (xy 151.690524 -60.036417) (xy 151.77371 -60.052453) (xy 151.854996 -60.076323)
			(xy 151.933644 -60.107811) (xy 152.008943 -60.146633) (xy 152.080211 -60.192436) (xy 152.146802 -60.244807)
			(xy 152.208114 -60.303269) (xy 152.263591 -60.367296) (xy 152.312731 -60.436305) (xy 152.355089 -60.509673)
			(xy 152.390281 -60.586735) (xy 152.417989 -60.666794) (xy 152.437961 -60.749123) (xy 152.450018 -60.832978)
			(xy 152.454049 -60.9176) (xy 152.450018 -61.002222) (xy 152.437961 -61.086077) (xy 152.417989 -61.168406)
			(xy 152.390281 -61.248465) (xy 152.355089 -61.325527) (xy 152.312731 -61.398895) (xy 152.263591 -61.467904)
			(xy 152.208114 -61.531931) (xy 152.146802 -61.590393) (xy 152.080211 -61.642764) (xy 152.008943 -61.688567)
			(xy 151.933644 -61.727389) (xy 151.854996 -61.758877) (xy 151.77371 -61.782747) (xy 151.690524 -61.798783)
			(xy 151.606191 -61.806839) (xy 151.563832 -61.807344) (xy 151.522083 -61.806861) (xy 151.438953 -61.799037)
			(xy 151.356924 -61.783444) (xy 151.31669 -61.772292) (xy 151.311917 -61.770986) (xy 151.302063 -61.770098)
			(xy 151.297132 -61.770514) (xy 151.272952 -61.773004) (xy 151.224411 -61.775674) (xy 151.200104 -61.775848)
			(xy 151.169974 -61.775594) (xy 151.109852 -61.771527) (xy 151.079962 -61.76772) (xy 151.074527 -61.767126)
			(xy 151.063633 -61.768014) (xy 151.058372 -61.769498) (xy 151.016682 -61.781509) (xy 150.931565 -61.798338)
			(xy 150.845214 -61.806808) (xy 150.801832 -61.807344) (xy 150.762109 -61.806904) (xy 150.68298 -61.7998)
			(xy 150.604797 -61.785683) (xy 150.566374 -61.775594) (xy 150.562211 -61.774509) (xy 150.553654 -61.773623)
			(xy 150.549356 -61.773816) (xy 150.534261 -61.774769) (xy 150.504029 -61.775786) (xy 150.488904 -61.775848)
			(xy 150.446557 -61.77528) (xy 150.362245 -61.76723) (xy 150.279081 -61.751201) (xy 150.197816 -61.72734)
			(xy 150.119188 -61.695863) (xy 150.043908 -61.657054) (xy 149.972658 -61.611264) (xy 149.906083 -61.558909)
			(xy 149.844787 -61.500463) (xy 149.789323 -61.436455) (xy 149.740195 -61.367465) (xy 149.697848 -61.294117)
			(xy 149.662664 -61.217076) (xy 149.634963 -61.137039) (xy 149.614995 -61.054732) (xy 149.602942 -60.970899)
			(xy 149.598912 -60.8863) (xy 143.1544 -60.8863) (xy 143.1544 -61.919612) (xy 143.176752 -61.947298)
			(xy 143.194278 -61.951108) (xy 143.236229 -61.960819) (xy 143.318173 -61.987295) (xy 143.397174 -62.021568)
			(xy 143.472493 -62.063317) (xy 143.543424 -62.112149) (xy 143.609303 -62.167608) (xy 143.669514 -62.229175)
			(xy 143.723492 -62.296273) (xy 143.770733 -62.368274) (xy 143.810793 -62.444504) (xy 143.843298 -62.524249)
			(xy 143.867943 -62.606762) (xy 143.884498 -62.691271) (xy 143.892807 -62.776984) (xy 143.893286 -62.820042)
			(xy 143.89284 -62.859988) (xy 143.885653 -62.939556) (xy 143.87136 -63.018159) (xy 143.850075 -63.095163)
			(xy 143.82197 -63.169949) (xy 143.787272 -63.241912) (xy 143.746259 -63.310474) (xy 143.723106 -63.343028)
			(xy 143.717172 -63.351992) (xy 143.712701 -63.373) (xy 143.717172 -63.394008) (xy 143.723106 -63.402972)
			(xy 143.746249 -63.435533) (xy 143.787257 -63.504095) (xy 143.821951 -63.576058) (xy 143.850052 -63.650843)
			(xy 143.871334 -63.727846) (xy 143.885626 -63.806447) (xy 143.892811 -63.886013) (xy 143.893286 -63.925958)
			(xy 143.892778 -63.969013) (xy 143.884453 -64.05472) (xy 143.867886 -64.139221) (xy 143.843233 -64.221726)
			(xy 143.810723 -64.301464) (xy 143.770662 -64.377688) (xy 143.723424 -64.449684) (xy 143.669451 -64.51678)
			(xy 143.609247 -64.578347) (xy 143.543378 -64.63381) (xy 143.472457 -64.682649) (xy 143.39715 -64.724408)
			(xy 143.318161 -64.758695) (xy 143.236229 -64.78519) (xy 143.194278 -64.794892) (xy 143.176752 -64.798702)
			(xy 143.1544 -64.826388) (xy 143.1544 -66.756026) (xy 143.154893 -66.76603) (xy 143.162557 -66.784513)
			(xy 143.176709 -66.798658) (xy 143.195196 -66.806312) (xy 143.2052 -66.806826)
		)
		(stroke
			(width 0)
			(type solid)
		)
		(fill yes)
		(layer "In1.Cu")
		(net "P52V_2")
	)
	(gr_poly
		(pts
			(xy 474.000068 -199.098154) (xy 474.055876 -199.097646) (xy 474.167179 -199.089307) (xy 474.277548 -199.072673)
			(xy 474.386365 -199.047838) (xy 474.493022 -199.01494) (xy 474.596923 -198.974164) (xy 474.697485 -198.925736)
			(xy 474.794147 -198.869929) (xy 474.886368 -198.807054) (xy 474.973633 -198.737463) (xy 475.055452 -198.661545)
			(xy 475.13137 -198.579725) (xy 475.20096 -198.49246) (xy 475.263834 -198.400239) (xy 475.319641 -198.303576)
			(xy 475.368068 -198.203014) (xy 475.408844 -198.099113) (xy 475.441741 -197.992456) (xy 475.466575 -197.883638)
			(xy 475.483208 -197.773269) (xy 475.491546 -197.661966) (xy 475.492064 -197.606158) (xy 475.492064 -135.770112)
			(xy 475.491555 -135.714305) (xy 475.483215 -135.603002) (xy 475.46658 -135.492634) (xy 475.441744 -135.383817)
			(xy 475.408845 -135.277161) (xy 475.368068 -135.173262) (xy 475.31964 -135.072701) (xy 475.263833 -134.97604)
			(xy 475.200958 -134.88382) (xy 475.131367 -134.796556) (xy 475.055449 -134.714737) (xy 474.973629 -134.63882)
			(xy 474.886364 -134.569231) (xy 474.794143 -134.506357) (xy 474.697481 -134.450551) (xy 474.596919 -134.402124)
			(xy 474.49302 -134.361348) (xy 474.386363 -134.328451) (xy 474.277546 -134.303616) (xy 474.167178 -134.286983)
			(xy 474.055875 -134.278644) (xy 474.000068 -134.278116) (xy 444.999872 -134.278116) (xy 444.929968 -134.278612)
			(xy 444.790381 -134.286463) (xy 444.651454 -134.302127) (xy 444.513624 -134.325555) (xy 444.377323 -134.356674)
			(xy 444.242982 -134.395385) (xy 444.111022 -134.441566) (xy 443.981859 -134.495074) (xy 443.855899 -134.555738)
			(xy 443.733538 -134.623368) (xy 443.615161 -134.697752) (xy 443.50114 -134.778656) (xy 443.391834 -134.865825)
			(xy 443.287587 -134.958985) (xy 443.188727 -135.057842) (xy 443.095565 -135.162087) (xy 443.008393 -135.27139)
			(xy 442.927487 -135.385409) (xy 442.8531 -135.503784) (xy 442.785466 -135.626144) (xy 442.724799 -135.752102)
			(xy 442.671289 -135.881264) (xy 442.625104 -136.013223) (xy 442.586389 -136.147563) (xy 442.555267 -136.283863)
			(xy 442.531836 -136.421693) (xy 442.516168 -136.56062) (xy 442.508314 -136.700206) (xy 442.507878 -136.77011)
			(xy 442.507878 -153.299922) (xy 442.507375 -153.422774) (xy 442.499335 -153.668345) (xy 442.483265 -153.913522)
			(xy 442.459181 -154.158042) (xy 442.42711 -154.401643) (xy 442.387085 -154.644065) (xy 442.33915 -154.885047)
			(xy 442.283356 -155.124331) (xy 442.219763 -155.361662) (xy 442.148438 -155.596785) (xy 442.069459 -155.829449)
			(xy 441.982909 -156.059404) (xy 441.888882 -156.286404) (xy 441.787478 -156.510205) (xy 441.678806 -156.73057)
			(xy 441.562982 -156.94726) (xy 441.44013 -157.160045) (xy 441.310381 -157.368697) (xy 441.173875 -157.572991)
			(xy 441.030758 -157.77271) (xy 440.881183 -157.967639) (xy 440.72531 -158.15757) (xy 440.563307 -158.342299)
			(xy 440.395346 -158.521628) (xy 440.221607 -158.695366) (xy 440.042277 -158.863327) (xy 439.857547 -159.02533)
			(xy 439.667615 -159.181202) (xy 439.472686 -159.330776) (xy 439.272966 -159.473893) (xy 439.068671 -159.610398)
			(xy 438.860019 -159.740145) (xy 438.647234 -159.862996) (xy 438.430543 -159.97882) (xy 438.210178 -160.087491)
			(xy 437.986376 -160.188894) (xy 437.759376 -160.28292) (xy 437.52942 -160.369469) (xy 437.296757 -160.448447)
			(xy 437.061633 -160.519771) (xy 436.824302 -160.583363) (xy 436.585017 -160.639156) (xy 436.344035 -160.68709)
			(xy 436.101614 -160.727114) (xy 435.858012 -160.759184) (xy 435.613492 -160.783267) (xy 435.368315 -160.799337)
			(xy 435.122744 -160.807376) (xy 434.999892 -160.807908) (xy 416.576256 -160.807908) (xy 416.506352 -160.808399)
			(xy 416.366764 -160.816241) (xy 416.227835 -160.831897) (xy 416.090003 -160.855317) (xy 415.9537 -160.88643)
			(xy 415.819357 -160.925136) (xy 415.687395 -160.971313) (xy 415.55823 -161.024817) (xy 415.432268 -161.085479)
			(xy 415.309905 -161.153108) (xy 415.191527 -161.227492) (xy 415.077506 -161.308396) (xy 414.968201 -161.395567)
			(xy 414.863955 -161.488728) (xy 414.765097 -161.587588) (xy 414.671937 -161.691836) (xy 414.584769 -161.801143)
			(xy 414.503867 -161.915166) (xy 414.429485 -162.033545) (xy 414.361858 -162.155909) (xy 414.301198 -162.281872)
			(xy 414.247697 -162.411038) (xy 414.201522 -162.543001) (xy 414.162818 -162.677345) (xy 414.131708 -162.813648)
			(xy 414.10829 -162.951481) (xy 414.092637 -163.09041) (xy 414.084798 -163.229998) (xy 414.084262 -163.299902)
			(xy 414.084262 -187.606178) (xy 414.083778 -187.676532) (xy 414.07589 -187.817019) (xy 414.060137 -187.956842)
			(xy 414.036568 -188.095562) (xy 414.005258 -188.232743) (xy 413.966306 -188.367952) (xy 413.919834 -188.500764)
			(xy 413.865987 -188.630762) (xy 413.804937 -188.757535) (xy 413.736874 -188.880686) (xy 413.662013 -188.999827)
			(xy 413.580589 -189.114583) (xy 413.492859 -189.224593) (xy 413.399098 -189.329511) (xy 413.299602 -189.429006)
			(xy 413.194684 -189.522766) (xy 413.084674 -189.610496) (xy 412.969917 -189.691919) (xy 412.850776 -189.76678)
			(xy 412.727625 -189.834842) (xy 412.600851 -189.895892) (xy 412.470853 -189.949738) (xy 412.33804 -189.99621)
			(xy 412.202831 -190.035161) (xy 412.065651 -190.06647) (xy 411.92693 -190.090038) (xy 411.787107 -190.105791)
			(xy 411.64662 -190.113679) (xy 411.576266 -190.114174) (xy 351.499932 -190.114174) (xy 351.429578 -190.113691)
			(xy 351.28909 -190.105803) (xy 351.149266 -190.09005) (xy 351.010545 -190.066482) (xy 350.873364 -190.035172)
			(xy 350.738154 -189.996221) (xy 350.605341 -189.949748) (xy 350.475343 -189.895903) (xy 350.348569 -189.834852)
			(xy 350.225417 -189.766789) (xy 350.106275 -189.691929) (xy 349.991518 -189.610505) (xy 349.881507 -189.522775)
			(xy 349.776589 -189.429014) (xy 349.677092 -189.329519) (xy 349.583332 -189.2246) (xy 349.495601 -189.11459)
			(xy 349.414177 -188.999833) (xy 349.339316 -188.880692) (xy 349.271252 -188.75754) (xy 349.210202 -188.630766)
			(xy 349.156355 -188.500768) (xy 349.109883 -188.367955) (xy 349.07093 -188.232746) (xy 349.03962 -188.095565)
			(xy 349.016052 -187.956844) (xy 349.000298 -187.81702) (xy 348.99241 -187.676532) (xy 348.991936 -187.606178)
			(xy 348.991936 -110.499906) (xy 348.991437 -110.399374) (xy 348.983341 -110.198474) (xy 348.967162 -109.998063)
			(xy 348.942927 -109.798466) (xy 348.910674 -109.600006) (xy 348.870457 -109.403006) (xy 348.822339 -109.207786)
			(xy 348.7664 -109.014661) (xy 348.702729 -108.823945) (xy 348.631431 -108.635948) (xy 348.552621 -108.450974)
			(xy 348.466427 -108.269323) (xy 348.372988 -108.09129) (xy 348.272456 -107.917165) (xy 348.164995 -107.747228)
			(xy 348.050777 -107.581757) (xy 347.92999 -107.421018) (xy 347.802828 -107.265274) (xy 347.669498 -107.114776)
			(xy 347.530217 -106.969769) (xy 347.385209 -106.830488) (xy 347.234711 -106.697159) (xy 347.078966 -106.569998)
			(xy 346.918227 -106.449211) (xy 346.752755 -106.334994) (xy 346.582818 -106.227533) (xy 346.408692 -106.127002)
			(xy 346.230659 -106.033564) (xy 346.049008 -105.947371) (xy 345.864034 -105.868561) (xy 345.676036 -105.797264)
			(xy 345.48532 -105.733594) (xy 345.292195 -105.677656) (xy 345.096974 -105.629539) (xy 344.899974 -105.589322)
			(xy 344.701514 -105.55707) (xy 344.501917 -105.532836) (xy 344.301506 -105.516658) (xy 344.100606 -105.508563)
			(xy 344.000074 -105.508044) (xy 293.310056 -105.508044) (xy 293.254251 -105.508567) (xy 293.142952 -105.516911)
			(xy 293.032588 -105.533549) (xy 292.923776 -105.558388) (xy 292.817125 -105.591289) (xy 292.713231 -105.632068)
			(xy 292.612674 -105.680497) (xy 292.516018 -105.736305) (xy 292.423802 -105.799181) (xy 292.336543 -105.868771)
			(xy 292.254729 -105.944688) (xy 292.178817 -106.026507) (xy 292.109231 -106.11377) (xy 292.046361 -106.205989)
			(xy 291.990558 -106.302648) (xy 291.942135 -106.403208) (xy 291.901361 -106.507104) (xy 291.868466 -106.613758)
			(xy 291.843634 -106.722571) (xy 291.827002 -106.832936) (xy 291.818664 -106.944235) (xy 291.81806 -107.00004)
			(xy 291.81806 -121.780046) (xy 291.817562 -121.863539) (xy 291.809615 -122.030336) (xy 291.793739 -122.196566)
			(xy 291.769973 -122.361852) (xy 291.738368 -122.52582) (xy 291.698998 -122.688098) (xy 291.65195 -122.848319)
			(xy 291.597333 -123.006121) (xy 291.535268 -123.161144) (xy 291.465898 -123.313039) (xy 291.389379 -123.461461)
			(xy 291.305884 -123.606075) (xy 291.215603 -123.746551) (xy 291.11874 -123.882573) (xy 291.015514 -124.013832)
			(xy 290.90616 -124.14003) (xy 290.790925 -124.260882) (xy 290.670071 -124.376114) (xy 290.54387 -124.485465)
			(xy 290.412609 -124.588688) (xy 290.276585 -124.685548) (xy 290.136106 -124.775826) (xy 289.991491 -124.859317)
			(xy 289.843067 -124.935833) (xy 289.691171 -125.0052) (xy 289.536146 -125.067261) (xy 289.378343 -125.121875)
			(xy 289.218121 -125.168919) (xy 289.055841 -125.208285) (xy 288.891873 -125.239886) (xy 288.726586 -125.263649)
			(xy 288.560356 -125.27952) (xy 288.393559 -125.287464) (xy 288.310066 -125.28804) (xy 139.910058 -125.28804)
			(xy 139.826564 -125.287542) (xy 139.659766 -125.279595) (xy 139.493535 -125.26372) (xy 139.328247 -125.239954)
			(xy 139.164277 -125.20835) (xy 139.001997 -125.168979) (xy 138.841774 -125.121932) (xy 138.683971 -125.067315)
			(xy 138.528946 -125.005251) (xy 138.377049 -124.935881) (xy 138.228625 -124.859362) (xy 138.08401 -124.775868)
			(xy 137.943531 -124.685588) (xy 137.807507 -124.588725) (xy 137.676246 -124.4855) (xy 137.550046 -124.376146)
			(xy 137.429191 -124.260912) (xy 137.313956 -124.140057) (xy 137.204603 -124.013857) (xy 137.101377 -123.882596)
			(xy 137.004515 -123.746572) (xy 136.914234 -123.606094) (xy 136.830739 -123.461479) (xy 136.75422 -123.313055)
			(xy 136.68485 -123.161158) (xy 136.622786 -123.006132) (xy 136.568169 -122.848329) (xy 136.521122 -122.688106)
			(xy 136.481751 -122.525826) (xy 136.450147 -122.361857) (xy 136.42638 -122.196569) (xy 136.410505 -122.030338)
			(xy 136.402558 -121.86354) (xy 136.402064 -121.780046) (xy 136.402064 -107.00004) (xy 136.401556 -106.944232)
			(xy 136.393218 -106.832928) (xy 136.376585 -106.722558) (xy 136.35175 -106.61374) (xy 136.318853 -106.507082)
			(xy 136.278076 -106.403181) (xy 136.229649 -106.302618) (xy 136.173842 -106.205955) (xy 136.110967 -106.113733)
			(xy 136.041377 -106.026468) (xy 135.965459 -105.944647) (xy 135.883638 -105.868729) (xy 135.796373 -105.799137)
			(xy 135.704152 -105.736262) (xy 135.607489 -105.680455) (xy 135.506926 -105.632027) (xy 135.403025 -105.59125)
			(xy 135.296368 -105.558352) (xy 135.18755 -105.533517) (xy 135.07718 -105.516883) (xy 134.965876 -105.508544)
			(xy 134.910068 -105.508044) (xy 95.999808 -105.508044) (xy 95.899276 -105.508543) (xy 95.698376 -105.516639)
			(xy 95.497964 -105.532817) (xy 95.298366 -105.557053) (xy 95.099907 -105.589305) (xy 94.902906 -105.629523)
			(xy 94.707685 -105.67764) (xy 94.51456 -105.73358) (xy 94.323844 -105.79725) (xy 94.135846 -105.868548)
			(xy 93.950872 -105.947358) (xy 93.769221 -106.033552) (xy 93.591188 -106.126991) (xy 93.417061 -106.227522)
			(xy 93.247124 -106.334984) (xy 93.081652 -106.449201) (xy 92.920913 -106.569988) (xy 92.765169 -106.69715)
			(xy 92.61467 -106.83048) (xy 92.469663 -106.969761) (xy 92.330381 -107.114769) (xy 92.197051 -107.265267)
			(xy 92.06989 -107.421012) (xy 91.949102 -107.581751) (xy 91.834885 -107.747223) (xy 91.727424 -107.91716)
			(xy 91.626892 -108.091286) (xy 91.533453 -108.269319) (xy 91.447259 -108.45097) (xy 91.368448 -108.635944)
			(xy 91.29715 -108.823942) (xy 91.23348 -109.014658) (xy 91.177541 -109.207783) (xy 91.129423 -109.403004)
			(xy 91.089206 -109.600005) (xy 91.056953 -109.798465) (xy 91.032718 -109.998062) (xy 91.016539 -110.198474)
			(xy 91.008443 -110.399374) (xy 91.007946 -110.499906) (xy 91.007946 -187.606178) (xy 91.007462 -187.676532)
			(xy 90.999574 -187.817018) (xy 90.983821 -187.956841) (xy 90.960252 -188.095561) (xy 90.928942 -188.232741)
			(xy 90.88999 -188.36795) (xy 90.843517 -188.500762) (xy 90.789671 -188.630759) (xy 90.72862 -188.757532)
			(xy 90.660557 -188.880683) (xy 90.585696 -188.999823) (xy 90.504272 -189.114579) (xy 90.416542 -189.224588)
			(xy 90.322781 -189.329506) (xy 90.223285 -189.429) (xy 90.118367 -189.52276) (xy 90.008357 -189.610489)
			(xy 89.8936 -189.691911) (xy 89.774459 -189.766771) (xy 89.651307 -189.834833) (xy 89.524533 -189.895882)
			(xy 89.394536 -189.949727) (xy 89.261723 -189.996198) (xy 89.126514 -190.035149) (xy 88.989334 -190.066457)
			(xy 88.850614 -190.090024) (xy 88.71079 -190.105776) (xy 88.570304 -190.113663) (xy 88.49995 -190.114174)
			(xy 28.42387 -190.114174) (xy 28.353517 -190.11368) (xy 28.213033 -190.105789) (xy 28.073211 -190.090033)
			(xy 27.934494 -190.066462) (xy 27.797316 -190.035151) (xy 27.66211 -189.996197) (xy 27.5293 -189.949723)
			(xy 27.399305 -189.895876) (xy 27.272534 -189.834824) (xy 27.149386 -189.766761) (xy 27.030248 -189.691899)
			(xy 26.915494 -189.610476) (xy 26.805487 -189.522746) (xy 26.700572 -189.428986) (xy 26.601078 -189.329491)
			(xy 26.507321 -189.224573) (xy 26.419593 -189.114564) (xy 26.338172 -188.999809) (xy 26.263313 -188.880669)
			(xy 26.195252 -188.757519) (xy 26.134203 -188.630747) (xy 26.080358 -188.500751) (xy 26.033887 -188.367941)
			(xy 25.994936 -188.232734) (xy 25.963628 -188.095555) (xy 25.94006 -187.956837) (xy 25.924307 -187.817016)
			(xy 25.916419 -187.676531) (xy 25.915874 -187.606178) (xy 25.915874 -163.299902) (xy 25.915393 -163.229997)
			(xy 25.907553 -163.090407) (xy 25.8919 -162.951476) (xy 25.868481 -162.813642) (xy 25.83737 -162.677337)
			(xy 25.798666 -162.542992) (xy 25.752489 -162.411028) (xy 25.698986 -162.28186) (xy 25.638325 -162.155896)
			(xy 25.570696 -162.033531) (xy 25.496312 -161.915151) (xy 25.415408 -161.801128) (xy 25.328237 -161.69182)
			(xy 25.235075 -161.587572) (xy 25.136214 -161.488712) (xy 25.031966 -161.395551) (xy 24.922658 -161.308381)
			(xy 24.808634 -161.227478) (xy 24.690253 -161.153095) (xy 24.567888 -161.085467) (xy 24.441923 -161.024807)
			(xy 24.312756 -160.971304) (xy 24.180791 -160.925129) (xy 24.046445 -160.886426) (xy 23.91014 -160.855316)
			(xy 23.772306 -160.831898) (xy 23.633375 -160.816245) (xy 23.493785 -160.808407) (xy 23.42388 -160.807908)
			(xy 1.999996 -160.807908) (xy 1.944189 -160.80843) (xy 1.832887 -160.816771) (xy 1.72252 -160.833407)
			(xy 1.613705 -160.858243) (xy 1.50705 -160.891142) (xy 1.403152 -160.93192) (xy 1.302591 -160.980347)
			(xy 1.205931 -161.036154) (xy 1.113712 -161.099029) (xy 1.026449 -161.168619) (xy 0.94463 -161.244536)
			(xy 0.868714 -161.326355) (xy 0.799124 -161.413618) (xy 0.73625 -161.505838) (xy 0.680444 -161.602499)
			(xy 0.632016 -161.703059) (xy 0.59124 -161.806958) (xy 0.558341 -161.913613) (xy 0.533505 -162.022428)
			(xy 0.51687 -162.132795) (xy 0.50853 -162.244097) (xy 0.508 -162.299904) (xy 0.508 -194.670734) (xy 2.904225 -194.670734)
			(xy 2.904225 -194.541594) (xy 2.912175 -194.412699) (xy 2.928045 -194.284539) (xy 2.951774 -194.157598)
			(xy 2.983273 -194.032359) (xy 3.022422 -193.909296) (xy 3.069073 -193.788877) (xy 3.123048 -193.671558)
			(xy 3.184143 -193.557784) (xy 3.252126 -193.447987) (xy 3.32674 -193.342584) (xy 3.407701 -193.241974)
			(xy 3.494701 -193.146539) (xy 3.587412 -193.05664) (xy 3.685482 -192.972619) (xy 3.788537 -192.894795)
			(xy 3.896188 -192.823463) (xy 4.008027 -192.758893) (xy 4.123628 -192.701331) (xy 4.242553 -192.650994)
			(xy 4.364352 -192.608074) (xy 4.488562 -192.572733) (xy 4.614711 -192.545106) (xy 4.742323 -192.525297)
			(xy 4.870912 -192.513381) (xy 4.99999 -192.509405) (xy 5.129068 -192.513381) (xy 5.257657 -192.525297)
			(xy 5.385269 -192.545106) (xy 5.511418 -192.572733) (xy 5.635628 -192.608074) (xy 5.757427 -192.650994)
			(xy 5.876352 -192.701331) (xy 5.991953 -192.758893) (xy 6.103792 -192.823463) (xy 6.211443 -192.894795)
			(xy 6.314498 -192.972619) (xy 6.412568 -193.05664) (xy 6.505279 -193.146539) (xy 6.592279 -193.241974)
			(xy 6.67324 -193.342584) (xy 6.747854 -193.447987) (xy 6.815837 -193.557784) (xy 6.876932 -193.671558)
			(xy 6.930907 -193.788877) (xy 6.977558 -193.909296) (xy 7.016707 -194.032359) (xy 7.048206 -194.157598)
			(xy 7.071935 -194.284539) (xy 7.087805 -194.412699) (xy 7.095755 -194.541594) (xy 7.096252 -194.606164)
			(xy 7.095755 -194.670734) (xy 468.904309 -194.670734) (xy 468.904309 -194.541594) (xy 468.912259 -194.412699)
			(xy 468.928129 -194.284539) (xy 468.951858 -194.157598) (xy 468.983357 -194.032359) (xy 469.022506 -193.909296)
			(xy 469.069157 -193.788877) (xy 469.123132 -193.671558) (xy 469.184227 -193.557784) (xy 469.25221 -193.447987)
			(xy 469.326824 -193.342584) (xy 469.407785 -193.241974) (xy 469.494785 -193.146539) (xy 469.587496 -193.05664)
			(xy 469.685566 -192.972619) (xy 469.788621 -192.894795) (xy 469.896272 -192.823463) (xy 470.008111 -192.758893)
			(xy 470.123712 -192.701331) (xy 470.242637 -192.650994) (xy 470.364436 -192.608074) (xy 470.488646 -192.572733)
			(xy 470.614795 -192.545106) (xy 470.742407 -192.525297) (xy 470.870996 -192.513381) (xy 471.000074 -192.509405)
			(xy 471.129152 -192.513381) (xy 471.257741 -192.525297) (xy 471.385353 -192.545106) (xy 471.511502 -192.572733)
			(xy 471.635712 -192.608074) (xy 471.757511 -192.650994) (xy 471.876436 -192.701331) (xy 471.992037 -192.758893)
			(xy 472.103876 -192.823463) (xy 472.211527 -192.894795) (xy 472.314582 -192.972619) (xy 472.412652 -193.05664)
			(xy 472.505363 -193.146539) (xy 472.592363 -193.241974) (xy 472.673324 -193.342584) (xy 472.747938 -193.447987)
			(xy 472.815921 -193.557784) (xy 472.877016 -193.671558) (xy 472.930991 -193.788877) (xy 472.977642 -193.909296)
			(xy 473.016791 -194.032359) (xy 473.04829 -194.157598) (xy 473.072019 -194.284539) (xy 473.087889 -194.412699)
			(xy 473.095839 -194.541594) (xy 473.096336 -194.606164) (xy 473.095839 -194.670734) (xy 473.087889 -194.799629)
			(xy 473.072019 -194.927789) (xy 473.04829 -195.05473) (xy 473.016791 -195.179969) (xy 472.977642 -195.303032)
			(xy 472.930991 -195.423451) (xy 472.877016 -195.54077) (xy 472.815921 -195.654544) (xy 472.747938 -195.764341)
			(xy 472.673324 -195.869744) (xy 472.592363 -195.970354) (xy 472.505363 -196.065789) (xy 472.412652 -196.155688)
			(xy 472.314582 -196.239709) (xy 472.211527 -196.317533) (xy 472.103876 -196.388865) (xy 471.992037 -196.453435)
			(xy 471.876436 -196.510997) (xy 471.757511 -196.561334) (xy 471.635712 -196.604254) (xy 471.511502 -196.639595)
			(xy 471.385353 -196.667222) (xy 471.257741 -196.687031) (xy 471.129152 -196.698947) (xy 471.000074 -196.702924)
			(xy 470.870996 -196.698947) (xy 470.742407 -196.687031) (xy 470.614795 -196.667222) (xy 470.488646 -196.639595)
			(xy 470.364436 -196.604254) (xy 470.242637 -196.561334) (xy 470.123712 -196.510997) (xy 470.008111 -196.453435)
			(xy 469.896272 -196.388865) (xy 469.788621 -196.317533) (xy 469.685566 -196.239709) (xy 469.587496 -196.155688)
			(xy 469.494785 -196.065789) (xy 469.407785 -195.970354) (xy 469.326824 -195.869744) (xy 469.25221 -195.764341)
			(xy 469.184227 -195.654544) (xy 469.123132 -195.54077) (xy 469.069157 -195.423451) (xy 469.022506 -195.303032)
			(xy 468.983357 -195.179969) (xy 468.951858 -195.05473) (xy 468.928129 -194.927789) (xy 468.912259 -194.799629)
			(xy 468.904309 -194.670734) (xy 7.095755 -194.670734) (xy 7.087805 -194.799629) (xy 7.071935 -194.927789)
			(xy 7.048206 -195.05473) (xy 7.016707 -195.179969) (xy 6.977558 -195.303032) (xy 6.930907 -195.423451)
			(xy 6.876932 -195.54077) (xy 6.815837 -195.654544) (xy 6.747854 -195.764341) (xy 6.67324 -195.869744)
			(xy 6.592279 -195.970354) (xy 6.505279 -196.065789) (xy 6.412568 -196.155688) (xy 6.314498 -196.239709)
			(xy 6.211443 -196.317533) (xy 6.103792 -196.388865) (xy 5.991953 -196.453435) (xy 5.876352 -196.510997)
			(xy 5.757427 -196.561334) (xy 5.635628 -196.604254) (xy 5.511418 -196.639595) (xy 5.385269 -196.667222)
			(xy 5.257657 -196.687031) (xy 5.129068 -196.698947) (xy 4.99999 -196.702924) (xy 4.870912 -196.698947)
			(xy 4.742323 -196.687031) (xy 4.614711 -196.667222) (xy 4.488562 -196.639595) (xy 4.364352 -196.604254)
			(xy 4.242553 -196.561334) (xy 4.123628 -196.510997) (xy 4.008027 -196.453435) (xy 3.896188 -196.388865)
			(xy 3.788537 -196.317533) (xy 3.685482 -196.239709) (xy 3.587412 -196.155688) (xy 3.494701 -196.065789)
			(xy 3.407701 -195.970354) (xy 3.32674 -195.869744) (xy 3.252126 -195.764341) (xy 3.184143 -195.654544)
			(xy 3.123048 -195.54077) (xy 3.069073 -195.423451) (xy 3.022422 -195.303032) (xy 2.983273 -195.179969)
			(xy 2.951774 -195.05473) (xy 2.928045 -194.927789) (xy 2.912175 -194.799629) (xy 2.904225 -194.670734)
			(xy 0.508 -194.670734) (xy 0.508 -197.606158) (xy 0.508522 -197.661965) (xy 0.516863 -197.773267)
			(xy 0.533498 -197.883634) (xy 0.558335 -197.99245) (xy 0.591234 -198.099105) (xy 0.632011 -198.203004)
			(xy 0.680438 -198.303564) (xy 0.736246 -198.400225) (xy 0.79912 -198.492445) (xy 0.86871 -198.579708)
			(xy 0.944627 -198.661527) (xy 1.026446 -198.737444) (xy 1.113709 -198.807034) (xy 1.205929 -198.869908)
			(xy 1.30259 -198.925716) (xy 1.40315 -198.974143) (xy 1.507049 -199.01492) (xy 1.613704 -199.047819)
			(xy 1.72252 -199.072656) (xy 1.832887 -199.089291) (xy 1.944189 -199.097632) (xy 1.999996 -199.098154)
		)
		(stroke
			(width 0)
			(type solid)
		)
		(fill yes)
		(layer "In1.Cu")
		(net "GND3")
	)
	(gr_poly
		(pts
			(xy 75.000104 -171.140882) (xy 75.095437 -171.140376) (xy 75.285932 -171.132284) (xy 75.475912 -171.116114)
			(xy 75.665035 -171.091896) (xy 75.852959 -171.059673) (xy 76.039346 -171.019503) (xy 76.223861 -170.971459)
			(xy 76.40617 -170.915628) (xy 76.585945 -170.852109) (xy 76.762863 -170.781017) (xy 76.936604 -170.702482)
			(xy 77.106855 -170.616643) (xy 77.27331 -170.523655) (xy 77.435668 -170.423687) (xy 77.593638 -170.316919)
			(xy 77.746933 -170.203542) (xy 77.895279 -170.083761) (xy 78.038407 -169.957793) (xy 78.17606 -169.825863)
			(xy 78.30799 -169.68821) (xy 78.433959 -169.545082) (xy 78.55374 -169.396736) (xy 78.667117 -169.243441)
			(xy 78.773885 -169.085472) (xy 78.873853 -168.923113) (xy 78.966841 -168.756659) (xy 79.05268 -168.586408)
			(xy 79.131216 -168.412667) (xy 79.202307 -168.235749) (xy 79.265826 -168.055974) (xy 79.321658 -167.873665)
			(xy 79.369702 -167.68915) (xy 79.409872 -167.502763) (xy 79.442095 -167.314839) (xy 79.466314 -167.125716)
			(xy 79.482484 -166.935736) (xy 79.490576 -166.745241) (xy 79.491078 -166.649908) (xy 79.491078 -161.28111)
			(xy 79.497763 -161.194561) (xy 79.518105 -161.022146) (xy 79.546364 -160.850851) (xy 79.582482 -160.681039)
			(xy 79.626381 -160.51307) (xy 79.677968 -160.347301) (xy 79.737135 -160.184083) (xy 79.803755 -160.023764)
			(xy 79.877687 -159.866682) (xy 79.958774 -159.713171) (xy 80.046845 -159.563557) (xy 80.141711 -159.418158)
			(xy 80.243173 -159.277281) (xy 80.351014 -159.141227) (xy 80.465007 -159.010282) (xy 80.584908 -158.884726)
			(xy 80.710464 -158.764825) (xy 80.841408 -158.650833) (xy 80.977463 -158.542992) (xy 81.11834 -158.44153)
			(xy 81.263739 -158.346663) (xy 81.413353 -158.258593) (xy 81.566864 -158.177506) (xy 81.723946 -158.103574)
			(xy 81.884265 -158.036954) (xy 82.047483 -157.977788) (xy 82.213252 -157.9262) (xy 82.381221 -157.882301)
			(xy 82.551033 -157.846184) (xy 82.722328 -157.817924) (xy 82.894743 -157.797583) (xy 82.981292 -157.790896)
			(xy 83.49996 -157.790896) (xy 83.595294 -157.790398) (xy 83.785791 -157.782307) (xy 83.975773 -157.766139)
			(xy 84.164897 -157.741923) (xy 84.352823 -157.709701) (xy 84.539213 -157.669533) (xy 84.723729 -157.62149)
			(xy 84.90604 -157.565659) (xy 85.085818 -157.502142) (xy 85.262738 -157.431051) (xy 85.436481 -157.352516)
			(xy 85.606734 -157.266677) (xy 85.773191 -157.173691) (xy 85.935552 -157.073723) (xy 86.093523 -156.966955)
			(xy 86.246821 -156.853578) (xy 86.395169 -156.733797) (xy 86.538299 -156.607828) (xy 86.675955 -156.475898)
			(xy 86.807886 -156.338245) (xy 86.933857 -156.195116) (xy 87.05364 -156.04677) (xy 87.167019 -155.893474)
			(xy 87.273789 -155.735504) (xy 87.373759 -155.573145) (xy 87.466748 -155.406689) (xy 87.552589 -155.236437)
			(xy 87.631127 -155.062695) (xy 87.70222 -154.885776) (xy 87.76574 -154.705999) (xy 87.821573 -154.523689)
			(xy 87.869618 -154.339173) (xy 87.909789 -154.152784) (xy 87.942013 -153.964858) (xy 87.966233 -153.775734)
			(xy 87.982404 -153.585753) (xy 87.990497 -153.395256) (xy 87.990934 -153.299922) (xy 87.990934 -110.499906)
			(xy 87.991432 -110.374101) (xy 87.999343 -110.122617) (xy 88.015149 -109.871504) (xy 88.038834 -109.621013)
			(xy 88.070376 -109.371388) (xy 88.109743 -109.122878) (xy 88.156896 -108.875727) (xy 88.211788 -108.630178)
			(xy 88.274366 -108.386475) (xy 88.344568 -108.144858) (xy 88.422324 -107.905565) (xy 88.507557 -107.668832)
			(xy 88.600185 -107.434893) (xy 88.700114 -107.203979) (xy 88.807248 -106.976318) (xy 88.921479 -106.752134)
			(xy 89.042695 -106.531649) (xy 89.170776 -106.315079) (xy 89.305597 -106.10264) (xy 89.447024 -105.89454)
			(xy 89.594918 -105.690985) (xy 89.749132 -105.492175) (xy 89.909514 -105.298308) (xy 90.075907 -105.109574)
			(xy 90.248145 -104.926159) (xy 90.42606 -104.748244) (xy 90.609475 -104.576006) (xy 90.798209 -104.409613)
			(xy 90.992077 -104.249231) (xy 91.190887 -104.095017) (xy 91.394442 -103.947123) (xy 91.602542 -103.805696)
			(xy 91.814981 -103.670875) (xy 92.03155 -103.542794) (xy 92.252036 -103.421578) (xy 92.47622 -103.307347)
			(xy 92.703881 -103.200214) (xy 92.934795 -103.100284) (xy 93.168734 -103.007657) (xy 93.405467 -102.922423)
			(xy 93.64476 -102.844667) (xy 93.886377 -102.774465) (xy 94.13008 -102.711888) (xy 94.375628 -102.656995)
			(xy 94.62278 -102.609842) (xy 94.87129 -102.570476) (xy 95.120915 -102.538934) (xy 95.371406 -102.515249)
			(xy 95.622519 -102.499443) (xy 95.874003 -102.491532) (xy 95.999808 -102.491032) (xy 318.10579 -102.491032)
			(xy 318.106806 -102.492048) (xy 319.051686 -102.492048) (xy 319.052702 -102.491032) (xy 344.000074 -102.491032)
			(xy 344.12588 -102.491521) (xy 344.377368 -102.499423) (xy 344.628483 -102.515221) (xy 344.878979 -102.538899)
			(xy 345.128607 -102.570434) (xy 345.377121 -102.609794) (xy 345.624276 -102.656941) (xy 345.869829 -102.711827)
			(xy 346.113536 -102.7744) (xy 346.355158 -102.844597) (xy 346.594455 -102.922349) (xy 346.831192 -103.007579)
			(xy 347.065135 -103.100203) (xy 347.296054 -103.20013) (xy 347.523719 -103.30726) (xy 347.747907 -103.421489)
			(xy 347.968397 -103.542704) (xy 348.18497 -103.670784) (xy 348.397413 -103.805604) (xy 348.605517 -103.947031)
			(xy 348.809076 -104.094924) (xy 349.007888 -104.249139) (xy 349.201759 -104.409522) (xy 349.36105 -104.549956)
			(xy 422.484046 -104.549956) (xy 422.488076 -104.407621) (xy 422.500151 -104.265741) (xy 422.520234 -104.124773)
			(xy 422.548261 -103.985166) (xy 422.584141 -103.847368) (xy 422.627759 -103.711821) (xy 422.678976 -103.578959)
			(xy 422.737627 -103.449207) (xy 422.803525 -103.322981) (xy 422.876459 -103.200685) (xy 422.956196 -103.082712)
			(xy 423.042478 -102.969439) (xy 423.135031 -102.861228) (xy 423.233558 -102.758427) (xy 423.337743 -102.661365)
			(xy 423.447252 -102.570353) (xy 423.561735 -102.485681) (xy 423.680825 -102.407623) (xy 423.80414 -102.336427)
			(xy 423.931286 -102.272321) (xy 424.061855 -102.215512) (xy 424.195429 -102.16618) (xy 424.33158 -102.124484)
			(xy 424.469871 -102.090558) (xy 424.609861 -102.06451) (xy 424.7511 -102.046424) (xy 424.893136 -102.036357)
			(xy 425.035514 -102.034342) (xy 425.177778 -102.040385) (xy 425.319472 -102.054467) (xy 425.460142 -102.076543)
			(xy 425.599339 -102.106543) (xy 425.736615 -102.144369) (xy 425.871531 -102.189901) (xy 426.003655 -102.242992)
			(xy 426.132564 -102.303474) (xy 426.257845 -102.371152) (xy 426.379096 -102.445809) (xy 426.495929 -102.527207)
			(xy 426.60797 -102.615084) (xy 426.71486 -102.709159) (xy 426.816257 -102.809131) (xy 426.911835 -102.914679)
			(xy 427.001289 -103.025465) (xy 427.084331 -103.141134) (xy 427.160697 -103.261317) (xy 427.230141 -103.385627)
			(xy 427.292441 -103.513668) (xy 427.347397 -103.645027) (xy 427.394834 -103.779286) (xy 427.434598 -103.916013)
			(xy 427.466564 -104.054771) (xy 427.490629 -104.195115) (xy 427.506715 -104.336596) (xy 427.51477 -104.47876)
			(xy 427.515274 -104.549956) (xy 427.51477 -104.621152) (xy 427.506715 -104.763316) (xy 427.490629 -104.904797)
			(xy 427.466564 -105.045141) (xy 427.434598 -105.183899) (xy 427.394834 -105.320626) (xy 427.347397 -105.454885)
			(xy 427.292441 -105.586244) (xy 427.230141 -105.714285) (xy 427.160697 -105.838595) (xy 427.084331 -105.958778)
			(xy 427.001289 -106.074447) (xy 426.911835 -106.185233) (xy 426.816257 -106.290781) (xy 426.71486 -106.390753)
			(xy 426.60797 -106.484828) (xy 426.495929 -106.572705) (xy 426.379096 -106.654103) (xy 426.257845 -106.72876)
			(xy 426.132564 -106.796438) (xy 426.003655 -106.85692) (xy 425.871531 -106.910011) (xy 425.736615 -106.955543)
			(xy 425.599339 -106.993369) (xy 425.460142 -107.023369) (xy 425.319472 -107.045445) (xy 425.177778 -107.059527)
			(xy 425.035514 -107.06557) (xy 424.893136 -107.063555) (xy 424.7511 -107.053488) (xy 424.609861 -107.035402)
			(xy 424.469871 -107.009354) (xy 424.33158 -106.975428) (xy 424.195429 -106.933732) (xy 424.061855 -106.8844)
			(xy 423.931286 -106.827591) (xy 423.80414 -106.763485) (xy 423.680825 -106.692289) (xy 423.561735 -106.614231)
			(xy 423.447252 -106.529559) (xy 423.337743 -106.438547) (xy 423.233558 -106.341485) (xy 423.135031 -106.238684)
			(xy 423.042478 -106.130473) (xy 422.956196 -106.0172) (xy 422.876459 -105.899227) (xy 422.803525 -105.776931)
			(xy 422.737627 -105.650705) (xy 422.678976 -105.520953) (xy 422.627759 -105.388091) (xy 422.584141 -105.252544)
			(xy 422.548261 -105.114746) (xy 422.520234 -104.975139) (xy 422.500151 -104.834171) (xy 422.488076 -104.692291)
			(xy 422.484046 -104.549956) (xy 349.36105 -104.549956) (xy 349.390496 -104.575916) (xy 349.573914 -104.748156)
			(xy 349.75183 -104.926072) (xy 349.924071 -105.109489) (xy 350.090465 -105.298226) (xy 350.250849 -105.492096)
			(xy 350.405064 -105.690908) (xy 350.552958 -105.894467) (xy 350.694385 -106.10257) (xy 350.829205 -106.315013)
			(xy 350.957286 -106.531586) (xy 351.078501 -106.752075) (xy 351.192731 -106.976263) (xy 351.299862 -107.203928)
			(xy 351.399789 -107.434846) (xy 351.492414 -107.668789) (xy 351.577645 -107.905526) (xy 351.655397 -108.144823)
			(xy 351.725595 -108.386444) (xy 351.788168 -108.630152) (xy 351.843055 -108.875704) (xy 351.890203 -109.122859)
			(xy 351.929563 -109.371373) (xy 351.961098 -109.621001) (xy 351.984777 -109.871497) (xy 352.000576 -110.122612)
			(xy 352.008479 -110.3741) (xy 352.008948 -110.499906) (xy 352.008948 -111.879888) (xy 377.061232 -111.879888)
			(xy 377.065214 -111.789938) (xy 377.077131 -111.700691) (xy 377.096889 -111.612847) (xy 377.124333 -111.527093)
			(xy 377.159249 -111.4441) (xy 377.201363 -111.364518) (xy 377.250346 -111.288969) (xy 377.305814 -111.218045)
			(xy 377.367334 -111.1523) (xy 377.434423 -111.09225) (xy 377.506557 -111.038365) (xy 377.583171 -110.991065)
			(xy 377.663665 -110.950722) (xy 377.74741 -110.91765) (xy 377.833751 -110.89211) (xy 377.92201 -110.8743)
			(xy 378.011499 -110.86436) (xy 378.101515 -110.862369) (xy 378.191356 -110.86834) (xy 378.280317 -110.882229)
			(xy 378.367702 -110.903925) (xy 378.452828 -110.93326) (xy 378.535028 -110.970003) (xy 378.613659 -111.013867)
			(xy 378.688106 -111.064509) (xy 378.757786 -111.121533) (xy 378.822153 -111.184492) (xy 378.880704 -111.252893)
			(xy 378.932981 -111.326201) (xy 378.978574 -111.403843) (xy 379.017127 -111.48521) (xy 379.048338 -111.569666)
			(xy 379.071962 -111.65655) (xy 379.087815 -111.745182) (xy 379.095772 -111.834869) (xy 379.09627 -111.879888)
			(xy 396.619232 -111.879888) (xy 396.623214 -111.789938) (xy 396.635131 -111.700691) (xy 396.654889 -111.612847)
			(xy 396.682333 -111.527093) (xy 396.717249 -111.4441) (xy 396.759363 -111.364518) (xy 396.808346 -111.288969)
			(xy 396.863814 -111.218045) (xy 396.925334 -111.1523) (xy 396.992423 -111.09225) (xy 397.064557 -111.038365)
			(xy 397.141171 -110.991065) (xy 397.221665 -110.950722) (xy 397.30541 -110.91765) (xy 397.391751 -110.89211)
			(xy 397.48001 -110.8743) (xy 397.569499 -110.86436) (xy 397.659515 -110.862369) (xy 397.749356 -110.86834)
			(xy 397.838317 -110.882229) (xy 397.925702 -110.903925) (xy 398.010828 -110.93326) (xy 398.093028 -110.970003)
			(xy 398.171659 -111.013867) (xy 398.246106 -111.064509) (xy 398.315786 -111.121533) (xy 398.380153 -111.184492)
			(xy 398.438704 -111.252893) (xy 398.490981 -111.326201) (xy 398.536574 -111.403843) (xy 398.575127 -111.48521)
			(xy 398.606338 -111.569666) (xy 398.629962 -111.65655) (xy 398.645815 -111.745182) (xy 398.653772 -111.834869)
			(xy 398.65427 -111.879888) (xy 398.653772 -111.924907) (xy 398.645815 -112.014594) (xy 398.629962 -112.103226)
			(xy 398.606338 -112.19011) (xy 398.575127 -112.274566) (xy 398.536574 -112.355933) (xy 398.490981 -112.433575)
			(xy 398.438704 -112.506883) (xy 398.380153 -112.575284) (xy 398.315786 -112.638243) (xy 398.246106 -112.695267)
			(xy 398.171659 -112.745909) (xy 398.093028 -112.789773) (xy 398.010828 -112.826516) (xy 397.925702 -112.855851)
			(xy 397.838317 -112.877547) (xy 397.749356 -112.891436) (xy 397.659515 -112.897407) (xy 397.569499 -112.895416)
			(xy 397.48001 -112.885476) (xy 397.391751 -112.867666) (xy 397.30541 -112.842126) (xy 397.221665 -112.809054)
			(xy 397.141171 -112.768711) (xy 397.064557 -112.721411) (xy 396.992423 -112.667526) (xy 396.925334 -112.607476)
			(xy 396.863814 -112.541731) (xy 396.808346 -112.470807) (xy 396.759363 -112.395258) (xy 396.717249 -112.315676)
			(xy 396.682333 -112.232683) (xy 396.654889 -112.146929) (xy 396.635131 -112.059085) (xy 396.623214 -111.969838)
			(xy 396.619232 -111.879888) (xy 379.09627 -111.879888) (xy 379.095772 -111.924907) (xy 379.087815 -112.014594)
			(xy 379.071962 -112.103226) (xy 379.048338 -112.19011) (xy 379.017127 -112.274566) (xy 378.978574 -112.355933)
			(xy 378.932981 -112.433575) (xy 378.880704 -112.506883) (xy 378.822153 -112.575284) (xy 378.757786 -112.638243)
			(xy 378.688106 -112.695267) (xy 378.613659 -112.745909) (xy 378.535028 -112.789773) (xy 378.452828 -112.826516)
			(xy 378.367702 -112.855851) (xy 378.280317 -112.877547) (xy 378.191356 -112.891436) (xy 378.101515 -112.897407)
			(xy 378.011499 -112.895416) (xy 377.92201 -112.885476) (xy 377.833751 -112.867666) (xy 377.74741 -112.842126)
			(xy 377.663665 -112.809054) (xy 377.583171 -112.768711) (xy 377.506557 -112.721411) (xy 377.434423 -112.667526)
			(xy 377.367334 -112.607476) (xy 377.305814 -112.541731) (xy 377.250346 -112.470807) (xy 377.201363 -112.395258)
			(xy 377.159249 -112.315676) (xy 377.124333 -112.232683) (xy 377.096889 -112.146929) (xy 377.077131 -112.059085)
			(xy 377.065214 -111.969838) (xy 377.061232 -111.879888) (xy 352.008948 -111.879888) (xy 352.008948 -119.38)
			(xy 376.553741 -119.38) (xy 376.557716 -119.269941) (xy 376.569624 -119.160455) (xy 376.5894 -119.052114)
			(xy 376.616943 -118.945483) (xy 376.652108 -118.841117) (xy 376.694712 -118.73956) (xy 376.744533 -118.641343)
			(xy 376.801312 -118.546976) (xy 376.864751 -118.456952) (xy 376.934522 -118.371741) (xy 377.010259 -118.291786)
			(xy 377.091568 -118.217505) (xy 377.178025 -118.149285) (xy 377.269179 -118.08748) (xy 377.364556 -118.032415)
			(xy 377.463657 -117.984375) (xy 377.565966 -117.943611) (xy 377.67095 -117.910336) (xy 377.778061 -117.884723)
			(xy 377.886741 -117.866906) (xy 377.996424 -117.856977) (xy 378.106537 -117.854989) (xy 378.216507 -117.860951)
			(xy 378.32576 -117.874833) (xy 378.433726 -117.896563) (xy 378.539843 -117.926026) (xy 378.643557 -117.963069)
			(xy 378.744328 -118.0075) (xy 378.84163 -118.059087) (xy 378.934956 -118.117559) (xy 379.023819 -118.182614)
			(xy 379.107757 -118.253912) (xy 379.186332 -118.33108) (xy 379.259133 -118.413717) (xy 379.325781 -118.501391)
			(xy 379.38593 -118.593647) (xy 379.439264 -118.690002) (xy 379.485507 -118.789954) (xy 379.524417 -118.892982)
			(xy 379.555791 -118.99855) (xy 379.579466 -119.106106) (xy 379.595318 -119.21509) (xy 379.603265 -119.324934)
			(xy 379.603762 -119.38) (xy 396.111741 -119.38) (xy 396.115716 -119.269941) (xy 396.127624 -119.160455)
			(xy 396.1474 -119.052114) (xy 396.174943 -118.945483) (xy 396.210108 -118.841117) (xy 396.252712 -118.73956)
			(xy 396.302533 -118.641343) (xy 396.359312 -118.546976) (xy 396.422751 -118.456952) (xy 396.492522 -118.371741)
			(xy 396.568259 -118.291786) (xy 396.649568 -118.217505) (xy 396.736025 -118.149285) (xy 396.827179 -118.08748)
			(xy 396.922556 -118.032415) (xy 397.021657 -117.984375) (xy 397.123966 -117.943611) (xy 397.22895 -117.910336)
			(xy 397.336061 -117.884723) (xy 397.444741 -117.866906) (xy 397.554424 -117.856977) (xy 397.664537 -117.854989)
			(xy 397.774507 -117.860951) (xy 397.88376 -117.874833) (xy 397.991726 -117.896563) (xy 398.097843 -117.926026)
			(xy 398.201557 -117.963069) (xy 398.302328 -118.0075) (xy 398.39963 -118.059087) (xy 398.492956 -118.117559)
			(xy 398.581819 -118.182614) (xy 398.665757 -118.253912) (xy 398.744332 -118.33108) (xy 398.817133 -118.413717)
			(xy 398.883781 -118.501391) (xy 398.94393 -118.593647) (xy 398.997264 -118.690002) (xy 399.043507 -118.789954)
			(xy 399.082417 -118.892982) (xy 399.113791 -118.99855) (xy 399.137466 -119.106106) (xy 399.153318 -119.21509)
			(xy 399.161265 -119.324934) (xy 399.161762 -119.38) (xy 399.161265 -119.435066) (xy 399.153318 -119.54491)
			(xy 399.137466 -119.653894) (xy 399.113791 -119.76145) (xy 399.082417 -119.867018) (xy 399.043507 -119.970046)
			(xy 398.997264 -120.069998) (xy 398.94393 -120.166353) (xy 398.883781 -120.258609) (xy 398.817133 -120.346283)
			(xy 398.744332 -120.42892) (xy 398.665757 -120.506088) (xy 398.581819 -120.577386) (xy 398.492956 -120.642441)
			(xy 398.39963 -120.700913) (xy 398.302328 -120.7525) (xy 398.201557 -120.796931) (xy 398.097843 -120.833974)
			(xy 397.991726 -120.863437) (xy 397.88376 -120.885167) (xy 397.774507 -120.899049) (xy 397.664537 -120.905011)
			(xy 397.554424 -120.903023) (xy 397.444741 -120.893094) (xy 397.336061 -120.875277) (xy 397.22895 -120.849664)
			(xy 397.123966 -120.816389) (xy 397.021657 -120.775625) (xy 396.922556 -120.727585) (xy 396.827179 -120.67252)
			(xy 396.736025 -120.610715) (xy 396.649568 -120.542495) (xy 396.568259 -120.468214) (xy 396.492522 -120.388259)
			(xy 396.422751 -120.303048) (xy 396.359312 -120.213024) (xy 396.302533 -120.118657) (xy 396.252712 -120.02044)
			(xy 396.210108 -119.918883) (xy 396.174943 -119.814517) (xy 396.1474 -119.707886) (xy 396.127624 -119.599545)
			(xy 396.115716 -119.490059) (xy 396.111741 -119.38) (xy 379.603762 -119.38) (xy 379.603265 -119.435066)
			(xy 379.595318 -119.54491) (xy 379.579466 -119.653894) (xy 379.555791 -119.76145) (xy 379.524417 -119.867018)
			(xy 379.485507 -119.970046) (xy 379.439264 -120.069998) (xy 379.38593 -120.166353) (xy 379.325781 -120.258609)
			(xy 379.259133 -120.346283) (xy 379.186332 -120.42892) (xy 379.107757 -120.506088) (xy 379.023819 -120.577386)
			(xy 378.934956 -120.642441) (xy 378.84163 -120.700913) (xy 378.744328 -120.7525) (xy 378.643557 -120.796931)
			(xy 378.539843 -120.833974) (xy 378.433726 -120.863437) (xy 378.32576 -120.885167) (xy 378.216507 -120.899049)
			(xy 378.106537 -120.905011) (xy 377.996424 -120.903023) (xy 377.886741 -120.893094) (xy 377.778061 -120.875277)
			(xy 377.67095 -120.849664) (xy 377.565966 -120.816389) (xy 377.463657 -120.775625) (xy 377.364556 -120.727585)
			(xy 377.269179 -120.67252) (xy 377.178025 -120.610715) (xy 377.091568 -120.542495) (xy 377.010259 -120.468214)
			(xy 376.934522 -120.388259) (xy 376.864751 -120.303048) (xy 376.801312 -120.213024) (xy 376.744533 -120.118657)
			(xy 376.694712 -120.02044) (xy 376.652108 -119.918883) (xy 376.616943 -119.814517) (xy 376.5894 -119.707886)
			(xy 376.569624 -119.599545) (xy 376.557716 -119.490059) (xy 376.553741 -119.38) (xy 352.008948 -119.38)
			(xy 352.008948 -132.199888) (xy 377.061232 -132.199888) (xy 377.065214 -132.109938) (xy 377.077131 -132.020691)
			(xy 377.096889 -131.932847) (xy 377.124333 -131.847093) (xy 377.159249 -131.7641) (xy 377.201363 -131.684518)
			(xy 377.250346 -131.608969) (xy 377.305814 -131.538045) (xy 377.367334 -131.4723) (xy 377.434423 -131.41225)
			(xy 377.506557 -131.358365) (xy 377.583171 -131.311065) (xy 377.663665 -131.270722) (xy 377.74741 -131.23765)
			(xy 377.833751 -131.21211) (xy 377.92201 -131.1943) (xy 378.011499 -131.18436) (xy 378.101515 -131.182369)
			(xy 378.191356 -131.18834) (xy 378.280317 -131.202229) (xy 378.367702 -131.223925) (xy 378.452828 -131.25326)
			(xy 378.535028 -131.290003) (xy 378.613659 -131.333867) (xy 378.688106 -131.384509) (xy 378.757786 -131.441533)
			(xy 378.822153 -131.504492) (xy 378.880704 -131.572893) (xy 378.932981 -131.646201) (xy 378.978574 -131.723843)
			(xy 379.017127 -131.80521) (xy 379.048338 -131.889666) (xy 379.071962 -131.97655) (xy 379.087815 -132.065182)
			(xy 379.095772 -132.154869) (xy 379.09627 -132.199888) (xy 396.619232 -132.199888) (xy 396.623214 -132.109938)
			(xy 396.635131 -132.020691) (xy 396.654889 -131.932847) (xy 396.682333 -131.847093) (xy 396.717249 -131.7641)
			(xy 396.759363 -131.684518) (xy 396.808346 -131.608969) (xy 396.863814 -131.538045) (xy 396.925334 -131.4723)
			(xy 396.992423 -131.41225) (xy 397.064557 -131.358365) (xy 397.141171 -131.311065) (xy 397.221665 -131.270722)
			(xy 397.30541 -131.23765) (xy 397.391751 -131.21211) (xy 397.48001 -131.1943) (xy 397.569499 -131.18436)
			(xy 397.659515 -131.182369) (xy 397.749356 -131.18834) (xy 397.838317 -131.202229) (xy 397.925702 -131.223925)
			(xy 398.010828 -131.25326) (xy 398.093028 -131.290003) (xy 398.171659 -131.333867) (xy 398.246106 -131.384509)
			(xy 398.315786 -131.441533) (xy 398.380153 -131.504492) (xy 398.438704 -131.572893) (xy 398.490981 -131.646201)
			(xy 398.536574 -131.723843) (xy 398.575127 -131.80521) (xy 398.606338 -131.889666) (xy 398.629962 -131.97655)
			(xy 398.645815 -132.065182) (xy 398.653772 -132.154869) (xy 398.65427 -132.199888) (xy 398.653772 -132.244907)
			(xy 398.645815 -132.334594) (xy 398.629962 -132.423226) (xy 398.606338 -132.51011) (xy 398.575127 -132.594566)
			(xy 398.536574 -132.675933) (xy 398.490981 -132.753575) (xy 398.438704 -132.826883) (xy 398.380153 -132.895284)
			(xy 398.315786 -132.958243) (xy 398.246106 -133.015267) (xy 398.171659 -133.065909) (xy 398.093028 -133.109773)
			(xy 398.010828 -133.146516) (xy 397.925702 -133.175851) (xy 397.838317 -133.197547) (xy 397.749356 -133.211436)
			(xy 397.659515 -133.217407) (xy 397.569499 -133.215416) (xy 397.48001 -133.205476) (xy 397.391751 -133.187666)
			(xy 397.30541 -133.162126) (xy 397.221665 -133.129054) (xy 397.141171 -133.088711) (xy 397.064557 -133.041411)
			(xy 396.992423 -132.987526) (xy 396.925334 -132.927476) (xy 396.863814 -132.861731) (xy 396.808346 -132.790807)
			(xy 396.759363 -132.715258) (xy 396.717249 -132.635676) (xy 396.682333 -132.552683) (xy 396.654889 -132.466929)
			(xy 396.635131 -132.379085) (xy 396.623214 -132.289838) (xy 396.619232 -132.199888) (xy 379.09627 -132.199888)
			(xy 379.095772 -132.244907) (xy 379.087815 -132.334594) (xy 379.071962 -132.423226) (xy 379.048338 -132.51011)
			(xy 379.017127 -132.594566) (xy 378.978574 -132.675933) (xy 378.932981 -132.753575) (xy 378.880704 -132.826883)
			(xy 378.822153 -132.895284) (xy 378.757786 -132.958243) (xy 378.688106 -133.015267) (xy 378.613659 -133.065909)
			(xy 378.535028 -133.109773) (xy 378.452828 -133.146516) (xy 378.367702 -133.175851) (xy 378.280317 -133.197547)
			(xy 378.191356 -133.211436) (xy 378.101515 -133.217407) (xy 378.011499 -133.215416) (xy 377.92201 -133.205476)
			(xy 377.833751 -133.187666) (xy 377.74741 -133.162126) (xy 377.663665 -133.129054) (xy 377.583171 -133.088711)
			(xy 377.506557 -133.041411) (xy 377.434423 -132.987526) (xy 377.367334 -132.927476) (xy 377.305814 -132.861731)
			(xy 377.250346 -132.790807) (xy 377.201363 -132.715258) (xy 377.159249 -132.635676) (xy 377.124333 -132.552683)
			(xy 377.096889 -132.466929) (xy 377.077131 -132.379085) (xy 377.065214 -132.289838) (xy 377.061232 -132.199888)
			(xy 352.008948 -132.199888) (xy 352.008948 -139.7) (xy 376.553741 -139.7) (xy 376.557716 -139.589941)
			(xy 376.569624 -139.480455) (xy 376.5894 -139.372114) (xy 376.616943 -139.265483) (xy 376.652108 -139.161117)
			(xy 376.694712 -139.05956) (xy 376.744533 -138.961343) (xy 376.801312 -138.866976) (xy 376.864751 -138.776952)
			(xy 376.934522 -138.691741) (xy 377.010259 -138.611786) (xy 377.091568 -138.537505) (xy 377.178025 -138.469285)
			(xy 377.269179 -138.40748) (xy 377.364556 -138.352415) (xy 377.463657 -138.304375) (xy 377.565966 -138.263611)
			(xy 377.67095 -138.230336) (xy 377.778061 -138.204723) (xy 377.886741 -138.186906) (xy 377.996424 -138.176977)
			(xy 378.106537 -138.174989) (xy 378.216507 -138.180951) (xy 378.32576 -138.194833) (xy 378.433726 -138.216563)
			(xy 378.539843 -138.246026) (xy 378.643557 -138.283069) (xy 378.744328 -138.3275) (xy 378.84163 -138.379087)
			(xy 378.934956 -138.437559) (xy 379.023819 -138.502614) (xy 379.107757 -138.573912) (xy 379.186332 -138.65108)
			(xy 379.259133 -138.733717) (xy 379.325781 -138.821391) (xy 379.38593 -138.913647) (xy 379.439264 -139.010002)
			(xy 379.485507 -139.109954) (xy 379.524417 -139.212982) (xy 379.555791 -139.31855) (xy 379.579466 -139.426106)
			(xy 379.595318 -139.53509) (xy 379.603265 -139.644934) (xy 379.603762 -139.7) (xy 396.111741 -139.7)
			(xy 396.115716 -139.589941) (xy 396.127624 -139.480455) (xy 396.1474 -139.372114) (xy 396.174943 -139.265483)
			(xy 396.210108 -139.161117) (xy 396.252712 -139.05956) (xy 396.302533 -138.961343) (xy 396.359312 -138.866976)
			(xy 396.422751 -138.776952) (xy 396.492522 -138.691741) (xy 396.568259 -138.611786) (xy 396.649568 -138.537505)
			(xy 396.736025 -138.469285) (xy 396.827179 -138.40748) (xy 396.922556 -138.352415) (xy 397.021657 -138.304375)
			(xy 397.123966 -138.263611) (xy 397.22895 -138.230336) (xy 397.336061 -138.204723) (xy 397.444741 -138.186906)
			(xy 397.554424 -138.176977) (xy 397.664537 -138.174989) (xy 397.774507 -138.180951) (xy 397.88376 -138.194833)
			(xy 397.991726 -138.216563) (xy 398.097843 -138.246026) (xy 398.201557 -138.283069) (xy 398.302328 -138.3275)
			(xy 398.39963 -138.379087) (xy 398.492956 -138.437559) (xy 398.581819 -138.502614) (xy 398.665757 -138.573912)
			(xy 398.744332 -138.65108) (xy 398.817133 -138.733717) (xy 398.883781 -138.821391) (xy 398.94393 -138.913647)
			(xy 398.997264 -139.010002) (xy 399.043507 -139.109954) (xy 399.082417 -139.212982) (xy 399.113791 -139.31855)
			(xy 399.137466 -139.426106) (xy 399.153318 -139.53509) (xy 399.161265 -139.644934) (xy 399.161762 -139.7)
			(xy 399.161265 -139.755066) (xy 399.153318 -139.86491) (xy 399.137466 -139.973894) (xy 399.113791 -140.08145)
			(xy 399.082417 -140.187018) (xy 399.043507 -140.290046) (xy 398.997264 -140.389998) (xy 398.94393 -140.486353)
			(xy 398.883781 -140.578609) (xy 398.817133 -140.666283) (xy 398.744332 -140.74892) (xy 398.665757 -140.826088)
			(xy 398.581819 -140.897386) (xy 398.492956 -140.962441) (xy 398.39963 -141.020913) (xy 398.302328 -141.0725)
			(xy 398.201557 -141.116931) (xy 398.097843 -141.153974) (xy 397.991726 -141.183437) (xy 397.88376 -141.205167)
			(xy 397.774507 -141.219049) (xy 397.664537 -141.225011) (xy 397.554424 -141.223023) (xy 397.444741 -141.213094)
			(xy 397.336061 -141.195277) (xy 397.22895 -141.169664) (xy 397.123966 -141.136389) (xy 397.021657 -141.095625)
			(xy 396.922556 -141.047585) (xy 396.827179 -140.99252) (xy 396.736025 -140.930715) (xy 396.649568 -140.862495)
			(xy 396.568259 -140.788214) (xy 396.492522 -140.708259) (xy 396.422751 -140.623048) (xy 396.359312 -140.533024)
			(xy 396.302533 -140.438657) (xy 396.252712 -140.34044) (xy 396.210108 -140.238883) (xy 396.174943 -140.134517)
			(xy 396.1474 -140.027886) (xy 396.127624 -139.919545) (xy 396.115716 -139.810059) (xy 396.111741 -139.7)
			(xy 379.603762 -139.7) (xy 379.603265 -139.755066) (xy 379.595318 -139.86491) (xy 379.579466 -139.973894)
			(xy 379.555791 -140.08145) (xy 379.524417 -140.187018) (xy 379.485507 -140.290046) (xy 379.439264 -140.389998)
			(xy 379.38593 -140.486353) (xy 379.325781 -140.578609) (xy 379.259133 -140.666283) (xy 379.186332 -140.74892)
			(xy 379.107757 -140.826088) (xy 379.023819 -140.897386) (xy 378.934956 -140.962441) (xy 378.84163 -141.020913)
			(xy 378.744328 -141.0725) (xy 378.643557 -141.116931) (xy 378.539843 -141.153974) (xy 378.433726 -141.183437)
			(xy 378.32576 -141.205167) (xy 378.216507 -141.219049) (xy 378.106537 -141.225011) (xy 377.996424 -141.223023)
			(xy 377.886741 -141.213094) (xy 377.778061 -141.195277) (xy 377.67095 -141.169664) (xy 377.565966 -141.136389)
			(xy 377.463657 -141.095625) (xy 377.364556 -141.047585) (xy 377.269179 -140.99252) (xy 377.178025 -140.930715)
			(xy 377.091568 -140.862495) (xy 377.010259 -140.788214) (xy 376.934522 -140.708259) (xy 376.864751 -140.623048)
			(xy 376.801312 -140.533024) (xy 376.744533 -140.438657) (xy 376.694712 -140.34044) (xy 376.652108 -140.238883)
			(xy 376.616943 -140.134517) (xy 376.5894 -140.027886) (xy 376.569624 -139.919545) (xy 376.557716 -139.810059)
			(xy 376.553741 -139.7) (xy 352.008948 -139.7) (xy 352.008948 -153.299922) (xy 352.009454 -153.395255)
			(xy 352.017547 -153.585749) (xy 352.033718 -153.775728) (xy 352.057937 -153.964849) (xy 352.09016 -154.152772)
			(xy 352.130331 -154.339159) (xy 352.178375 -154.523672) (xy 352.234207 -154.70598) (xy 352.297727 -154.885754)
			(xy 352.368818 -155.062671) (xy 352.447355 -155.23641) (xy 352.533194 -155.40666) (xy 352.626182 -155.573114)
			(xy 352.72615 -155.735471) (xy 352.832919 -155.893439) (xy 352.946296 -156.046733) (xy 353.066077 -156.195077)
			(xy 353.192045 -156.338204) (xy 353.323975 -156.475856) (xy 353.461628 -156.607784) (xy 353.604756 -156.733752)
			(xy 353.753102 -156.853531) (xy 353.906397 -156.966907) (xy 354.064366 -157.073674) (xy 354.226724 -157.173641)
			(xy 354.393179 -157.266627) (xy 354.563429 -157.352464) (xy 354.73717 -157.430999) (xy 354.914087 -157.502089)
			(xy 355.093862 -157.565606) (xy 355.27617 -157.621437) (xy 355.460684 -157.66948) (xy 355.647071 -157.709648)
			(xy 355.834994 -157.74187) (xy 356.024116 -157.766087) (xy 356.214095 -157.782255) (xy 356.404589 -157.790347)
			(xy 356.499922 -157.790896) (xy 357.000048 -157.790896) (xy 357.083565 -157.791394) (xy 357.250411 -157.799344)
			(xy 357.416689 -157.815224) (xy 357.582024 -157.838998) (xy 357.746039 -157.870611) (xy 357.908365 -157.909993)
			(xy 358.068633 -157.957054) (xy 358.226481 -158.011687) (xy 358.38155 -158.07377) (xy 358.53349 -158.14316)
			(xy 358.681955 -158.219701) (xy 358.826611 -158.30322) (xy 358.967129 -158.393527) (xy 359.10319 -158.490418)
			(xy 359.234488 -158.593673) (xy 359.360723 -158.703059) (xy 359.481611 -158.818327) (xy 359.492747 -158.830006)
			(xy 361.785893 -158.830006) (xy 361.789998 -158.730238) (xy 361.802285 -158.631143) (xy 361.822671 -158.533393)
			(xy 361.85102 -158.437649) (xy 361.887138 -158.344557) (xy 361.930782 -158.254747) (xy 361.981657 -158.168826)
			(xy 362.039419 -158.087375) (xy 362.103677 -158.010945) (xy 362.173997 -157.940052) (xy 362.21162 -157.907228)
			(xy 362.219631 -157.899646) (xy 362.228855 -157.879636) (xy 362.2294 -157.86862) (xy 362.2294 -157.791404)
			(xy 362.22886 -157.780385) (xy 362.219642 -157.760369) (xy 362.21162 -157.752796) (xy 362.175695 -157.72148)
			(xy 362.108323 -157.65406) (xy 362.046446 -157.581563) (xy 361.990445 -157.504438) (xy 361.940665 -157.423158)
			(xy 361.897412 -157.338225) (xy 361.860953 -157.250162) (xy 361.831512 -157.15951) (xy 361.809271 -157.066829)
			(xy 361.794367 -156.972689) (xy 361.786891 -156.87767) (xy 361.786424 -156.830014) (xy 361.786965 -156.779837)
			(xy 361.79525 -156.679825) (xy 361.811765 -156.580838) (xy 361.836396 -156.483554) (xy 361.868976 -156.388635)
			(xy 361.909282 -156.29673) (xy 361.957039 -156.208467) (xy 362.01192 -156.124449) (xy 362.073551 -156.045249)
			(xy 362.141512 -155.971408) (xy 362.215337 -155.903431) (xy 362.294523 -155.841782) (xy 362.378528 -155.786881)
			(xy 362.46678 -155.739104) (xy 362.558676 -155.698777) (xy 362.653587 -155.666176) (xy 362.750866 -155.641522)
			(xy 362.849849 -155.624985) (xy 362.949859 -155.616677) (xy 363.000036 -155.616148) (xy 363.047698 -155.616657)
			(xy 363.142727 -155.624138) (xy 363.236876 -155.639052) (xy 363.329565 -155.661306) (xy 363.420222 -155.690763)
			(xy 363.508289 -155.727242) (xy 363.593222 -155.770518) (xy 363.674499 -155.820323) (xy 363.751617 -155.876352)
			(xy 363.824103 -155.938258) (xy 363.891508 -156.005661) (xy 363.922818 -156.041598) (xy 363.930385 -156.049627)
			(xy 363.950406 -156.058842) (xy 363.961426 -156.059378) (xy 364.038642 -156.059378) (xy 364.049665 -156.05887)
			(xy 364.069681 -156.04963) (xy 364.07725 -156.041598) (xy 364.108538 -156.005641) (xy 364.175953 -155.938249)
			(xy 364.248446 -155.876351) (xy 364.32557 -155.820329) (xy 364.406849 -155.770527) (xy 364.491784 -155.727252)
			(xy 364.579851 -155.690771) (xy 364.670507 -155.661309) (xy 364.763194 -155.639047) (xy 364.857342 -155.624122)
			(xy 364.95237 -155.616626) (xy 365.000032 -155.616148) (xy 365.050199 -155.616675) (xy 365.150189 -155.624962)
			(xy 365.249154 -155.641476) (xy 365.346418 -155.666105) (xy 365.441316 -155.69868) (xy 365.5332 -155.738979)
			(xy 365.621444 -155.786728) (xy 365.705443 -155.841599) (xy 365.784626 -155.903218) (xy 365.85845 -155.971164)
			(xy 365.926413 -156.044974) (xy 365.988049 -156.124143) (xy 366.042938 -156.208131) (xy 366.090705 -156.296364)
			(xy 366.131025 -156.38824) (xy 366.16362 -156.483131) (xy 366.18827 -156.580389) (xy 366.204806 -156.679351)
			(xy 366.213114 -156.779339) (xy 366.213644 -156.829506) (xy 366.213644 -156.830014) (xy 366.21318 -156.877671)
			(xy 366.205711 -156.972691) (xy 366.190811 -157.066833) (xy 366.168573 -157.159516) (xy 366.139134 -157.250169)
			(xy 366.102675 -157.338233) (xy 366.059421 -157.423167) (xy 366.009638 -157.504446) (xy 365.953632 -157.58157)
			(xy 365.891751 -157.654063) (xy 365.824373 -157.721479) (xy 365.788448 -157.752796) (xy 365.780421 -157.760364)
			(xy 365.771207 -157.780384) (xy 365.770668 -157.791404) (xy 365.770668 -157.86862) (xy 365.771205 -157.879639)
			(xy 365.780426 -157.899654) (xy 365.788448 -157.907228) (xy 365.826082 -157.94004) (xy 365.896405 -158.010933)
			(xy 365.960665 -158.087364) (xy 366.018429 -158.168815) (xy 366.069306 -158.254737) (xy 366.112952 -158.344548)
			(xy 366.149072 -158.437642) (xy 366.177421 -158.533388) (xy 366.197809 -158.63114) (xy 366.210097 -158.730236)
			(xy 366.214202 -158.830006) (xy 367.785885 -158.830006) (xy 367.78999 -158.730238) (xy 367.802277 -158.631144)
			(xy 367.822663 -158.533394) (xy 367.851011 -158.43765) (xy 367.887129 -158.344558) (xy 367.930773 -158.254748)
			(xy 367.981647 -158.168827) (xy 368.039408 -158.087376) (xy 368.103666 -158.010945) (xy 368.173985 -157.940052)
			(xy 368.211608 -157.907228) (xy 368.219618 -157.899644) (xy 368.228843 -157.879636) (xy 368.229388 -157.86862)
			(xy 368.229388 -157.791404) (xy 368.228852 -157.780385) (xy 368.219631 -157.760368) (xy 368.211608 -157.752796)
			(xy 368.17568 -157.721483) (xy 368.108309 -157.654062) (xy 368.046432 -157.581565) (xy 367.990432 -157.504439)
			(xy 367.940652 -157.423159) (xy 367.897399 -157.338226) (xy 367.86094 -157.250162) (xy 367.8315 -157.15951)
			(xy 367.809259 -157.066829) (xy 367.794355 -156.972689) (xy 367.786879 -156.87767) (xy 367.786412 -156.830014)
			(xy 367.786965 -156.779837) (xy 367.79525 -156.679826) (xy 367.811765 -156.58084) (xy 367.836396 -156.483556)
			(xy 367.868975 -156.388637) (xy 367.909281 -156.296733) (xy 367.957037 -156.208471) (xy 368.011917 -156.124453)
			(xy 368.073548 -156.045253) (xy 368.141507 -155.971413) (xy 368.215332 -155.903435) (xy 368.294517 -155.841786)
			(xy 368.378521 -155.786885) (xy 368.466772 -155.739108) (xy 368.558667 -155.698781) (xy 368.653578 -155.666178)
			(xy 368.750856 -155.641524) (xy 368.849838 -155.624986) (xy 368.949847 -155.616677) (xy 369.000024 -155.616148)
			(xy 369.047687 -155.616593) (xy 369.142718 -155.624081) (xy 369.236868 -155.639002) (xy 369.329558 -155.661263)
			(xy 369.420216 -155.690726) (xy 369.508283 -155.727212) (xy 369.593216 -155.770493) (xy 369.674492 -155.820305)
			(xy 369.751609 -155.876339) (xy 369.824093 -155.938251) (xy 369.891497 -156.005658) (xy 369.922806 -156.041598)
			(xy 369.930378 -156.049622) (xy 369.950395 -156.05884) (xy 369.961414 -156.059378) (xy 370.03863 -156.059378)
			(xy 370.049652 -156.058864) (xy 370.069669 -156.049628) (xy 370.077238 -156.041598) (xy 370.108532 -156.005647)
			(xy 370.175947 -155.938254) (xy 370.248439 -155.876356) (xy 370.325562 -155.820334) (xy 370.406841 -155.770531)
			(xy 370.491775 -155.727256) (xy 370.579841 -155.690775) (xy 370.670497 -155.661312) (xy 370.763183 -155.639049)
			(xy 370.857331 -155.624123) (xy 370.952359 -155.616626) (xy 371.00002 -155.616148) (xy 371.050186 -155.616687)
			(xy 371.150177 -155.624972) (xy 371.249142 -155.641486) (xy 371.346405 -155.666113) (xy 371.441303 -155.698688)
			(xy 371.533187 -155.738987) (xy 371.621431 -155.786734) (xy 371.70543 -155.841604) (xy 371.784613 -155.903223)
			(xy 371.858438 -155.971169) (xy 371.9264 -156.044978) (xy 371.988036 -156.124147) (xy 372.042926 -156.208134)
			(xy 372.090693 -156.296366) (xy 372.131012 -156.388242) (xy 372.163608 -156.483132) (xy 372.188258 -156.58039)
			(xy 372.204794 -156.679351) (xy 372.213102 -156.77934) (xy 372.213632 -156.829506) (xy 372.213632 -156.830014)
			(xy 372.213173 -156.877671) (xy 372.205703 -156.972691) (xy 372.190803 -157.066833) (xy 372.168565 -157.159516)
			(xy 372.139126 -157.250169) (xy 372.102666 -157.338234) (xy 372.059411 -157.423168) (xy 372.009628 -157.504447)
			(xy 371.953622 -157.58157) (xy 371.89174 -157.654063) (xy 371.824361 -157.721479) (xy 371.788436 -157.752796)
			(xy 371.780407 -157.760362) (xy 371.771194 -157.780384) (xy 371.770656 -157.791404) (xy 371.770656 -157.86862)
			(xy 371.771165 -157.879643) (xy 371.780403 -157.89966) (xy 371.788436 -157.907228) (xy 371.82687 -157.940727)
			(xy 371.898577 -158.013215) (xy 371.963952 -158.091462) (xy 372.022533 -158.174916) (xy 372.073908 -158.26299)
			(xy 372.096284 -158.308802) (xy 372.100856 -158.318454) (xy 372.116858 -158.332424) (xy 372.199154 -158.357316)
			(xy 372.209416 -158.359985) (xy 372.230452 -158.357503) (xy 372.239794 -158.35249) (xy 372.285756 -158.325685)
			(xy 372.380859 -158.27795) (xy 372.479133 -158.237137) (xy 372.580073 -158.203457) (xy 372.683163 -158.17708)
			(xy 372.787875 -158.158142) (xy 372.893673 -158.146741) (xy 373.000016 -158.142934) (xy 373.106359 -158.146741)
			(xy 373.212157 -158.158142) (xy 373.316869 -158.17708) (xy 373.419959 -158.203457) (xy 373.520899 -158.237137)
			(xy 373.619173 -158.27795) (xy 373.714276 -158.325685) (xy 373.760238 -158.35249) (xy 373.769622 -158.357377)
			(xy 373.79061 -158.359868) (xy 373.800878 -158.357316) (xy 373.883174 -158.332424) (xy 373.899176 -158.318454)
			(xy 373.903748 -158.308802) (xy 373.926127 -158.262992) (xy 373.977496 -158.174915) (xy 374.036076 -158.091459)
			(xy 374.101453 -158.013214) (xy 374.173165 -157.940731) (xy 374.211596 -157.907228) (xy 374.219604 -157.899642)
			(xy 374.228831 -157.879636) (xy 374.229376 -157.86862) (xy 374.229376 -157.791404) (xy 374.228843 -157.780384)
			(xy 374.219621 -157.760367) (xy 374.211596 -157.752796) (xy 374.175666 -157.721486) (xy 374.108295 -157.654064)
			(xy 374.046419 -157.581567) (xy 373.990418 -157.504441) (xy 373.940639 -157.423161) (xy 373.897386 -157.338227)
			(xy 373.860928 -157.250163) (xy 373.831488 -157.159511) (xy 373.809247 -157.066829) (xy 373.794343 -156.972689)
			(xy 373.786867 -156.87767) (xy 373.7864 -156.830014) (xy 373.786965 -156.779837) (xy 373.79525 -156.679827)
			(xy 373.811764 -156.580841) (xy 373.836395 -156.483558) (xy 373.868974 -156.38864) (xy 373.909279 -156.296736)
			(xy 373.957035 -156.208474) (xy 374.011915 -156.124457) (xy 374.073545 -156.045257) (xy 374.141503 -155.971417)
			(xy 374.215327 -155.90344) (xy 374.294511 -155.84179) (xy 374.378515 -155.786889) (xy 374.466765 -155.739112)
			(xy 374.558659 -155.698784) (xy 374.653568 -155.666181) (xy 374.750846 -155.641526) (xy 374.849827 -155.624988)
			(xy 374.949835 -155.616678) (xy 375.000012 -155.616148) (xy 375.047675 -155.616602) (xy 375.142705 -155.624089)
			(xy 375.236856 -155.639009) (xy 375.329545 -155.661268) (xy 375.420203 -155.690731) (xy 375.50827 -155.727216)
			(xy 375.593203 -155.770497) (xy 375.674479 -155.820308) (xy 375.751597 -155.876341) (xy 375.824081 -155.938252)
			(xy 375.891484 -156.005658) (xy 375.922794 -156.041598) (xy 375.930371 -156.049616) (xy 375.950384 -156.058837)
			(xy 375.961402 -156.059378) (xy 376.038618 -156.059378) (xy 376.049639 -156.058857) (xy 376.069656 -156.049626)
			(xy 376.077226 -156.041598) (xy 376.108527 -156.005653) (xy 376.175941 -155.93826) (xy 376.248432 -155.876362)
			(xy 376.325555 -155.820339) (xy 376.406833 -155.770536) (xy 376.491766 -155.72726) (xy 376.579831 -155.690779)
			(xy 376.670486 -155.661315) (xy 376.763173 -155.639051) (xy 376.857319 -155.624124) (xy 376.952347 -155.616626)
			(xy 377.000008 -155.616148) (xy 377.050174 -155.616698) (xy 377.150164 -155.624983) (xy 377.249129 -155.641495)
			(xy 377.346392 -155.666122) (xy 377.44129 -155.698696) (xy 377.533174 -155.738994) (xy 377.621418 -155.78674)
			(xy 377.705417 -155.84161) (xy 377.7846 -155.903228) (xy 377.858425 -155.971173) (xy 377.926387 -156.044982)
			(xy 377.988024 -156.12415) (xy 378.042913 -156.208137) (xy 378.090681 -156.296369) (xy 378.131 -156.388243)
			(xy 378.163596 -156.483134) (xy 378.188246 -156.580391) (xy 378.204782 -156.679352) (xy 378.21309 -156.77934)
			(xy 378.21362 -156.829506) (xy 378.21362 -156.830014) (xy 378.213165 -156.877671) (xy 378.205695 -156.972692)
			(xy 378.190795 -157.066834) (xy 378.168557 -157.159517) (xy 378.139117 -157.25017) (xy 378.102657 -157.338235)
			(xy 378.059402 -157.423168) (xy 378.009618 -157.504447) (xy 377.953612 -157.581571) (xy 377.891728 -157.654064)
			(xy 377.82435 -157.721479) (xy 377.788424 -157.752796) (xy 377.780393 -157.76036) (xy 377.771182 -157.780384)
			(xy 377.770644 -157.791404) (xy 377.770644 -157.86862) (xy 377.771157 -157.879642) (xy 377.780393 -157.899659)
			(xy 377.788424 -157.907228) (xy 377.826059 -157.94004) (xy 377.896383 -158.010932) (xy 377.960645 -158.087362)
			(xy 378.01841 -158.168813) (xy 378.069288 -158.254735) (xy 378.112934 -158.344547) (xy 378.149055 -158.43764)
			(xy 378.177405 -158.533387) (xy 378.197793 -158.631139) (xy 378.210081 -158.730235) (xy 378.214186 -158.830006)
			(xy 378.21008 -158.929778) (xy 378.197791 -159.028874) (xy 378.177402 -159.126626) (xy 378.149051 -159.222372)
			(xy 378.112929 -159.315465) (xy 378.069281 -159.405276) (xy 378.018403 -159.491197) (xy 377.960637 -159.572648)
			(xy 377.896374 -159.649078) (xy 377.82605 -159.719969) (xy 377.788424 -159.752792) (xy 377.780395 -159.760358)
			(xy 377.771183 -159.78038) (xy 377.770644 -159.7914) (xy 377.770644 -159.868616) (xy 377.771159 -159.879638)
			(xy 377.780393 -159.899655) (xy 377.788424 -159.907224) (xy 377.824368 -159.938518) (xy 377.891738 -160.005942)
			(xy 377.953613 -160.078441) (xy 378.009613 -160.155569) (xy 378.059391 -160.236851) (xy 378.102642 -160.321787)
			(xy 378.139099 -160.409852) (xy 378.168538 -160.500505) (xy 378.190777 -160.593188) (xy 378.205679 -160.687329)
			(xy 378.213153 -160.782349) (xy 378.21362 -160.830006) (xy 381.986028 -160.830006) (xy 381.986502 -160.782344)
			(xy 381.993988 -160.687314) (xy 382.008905 -160.593164) (xy 382.031164 -160.500475) (xy 382.060625 -160.409817)
			(xy 382.097107 -160.321751) (xy 382.140386 -160.236817) (xy 382.190195 -160.155541) (xy 382.246226 -160.078423)
			(xy 382.308135 -160.005939) (xy 382.375539 -159.938534) (xy 382.411478 -159.907224) (xy 382.4195 -159.899652)
			(xy 382.428716 -159.879634) (xy 382.429258 -159.868616) (xy 382.429258 -159.7914) (xy 382.428734 -159.780379)
			(xy 382.419506 -159.760362) (xy 382.411478 -159.752792) (xy 382.375537 -159.721486) (xy 382.308145 -159.654072)
			(xy 382.246247 -159.581581) (xy 382.190224 -159.504459) (xy 382.140421 -159.423182) (xy 382.097145 -159.338249)
			(xy 382.060663 -159.250184) (xy 382.031199 -159.15953) (xy 382.008934 -159.066844) (xy 381.994006 -158.972698)
			(xy 381.986507 -158.877671) (xy 381.986028 -158.83001) (xy 381.986505 -158.782348) (xy 381.99399 -158.687318)
			(xy 382.008908 -158.593168) (xy 382.031165 -158.500479) (xy 382.060626 -158.409822) (xy 382.097108 -158.321755)
			(xy 382.140387 -158.236822) (xy 382.190196 -158.155546) (xy 382.246227 -158.078427) (xy 382.308135 -158.005943)
			(xy 382.37554 -157.938538) (xy 382.411478 -157.907228) (xy 382.419499 -157.899655) (xy 382.428715 -157.879638)
			(xy 382.429258 -157.86862) (xy 382.429258 -157.791404) (xy 382.428731 -157.780383) (xy 382.419505 -157.760366)
			(xy 382.411478 -157.752796) (xy 382.375539 -157.721488) (xy 382.308147 -157.654074) (xy 382.246249 -157.581583)
			(xy 382.190226 -157.504462) (xy 382.140423 -157.423184) (xy 382.097147 -157.338252) (xy 382.060664 -157.250187)
			(xy 382.0312 -157.159533) (xy 382.008935 -157.066848) (xy 381.994007 -156.972702) (xy 381.986507 -156.877675)
			(xy 381.986028 -156.830014) (xy 381.986552 -156.779829) (xy 381.994839 -156.679803) (xy 382.011358 -156.580802)
			(xy 382.035996 -156.483504) (xy 382.068585 -156.388573) (xy 382.108902 -156.296657) (xy 382.156672 -156.208384)
			(xy 382.211568 -156.124358) (xy 382.273215 -156.045152) (xy 382.341193 -155.971307) (xy 382.415037 -155.903328)
			(xy 382.494242 -155.84168) (xy 382.578267 -155.786782) (xy 382.666539 -155.739011) (xy 382.758454 -155.698693)
			(xy 382.853385 -155.666102) (xy 382.950683 -155.641462) (xy 383.049683 -155.624942) (xy 383.149709 -155.616653)
			(xy 383.199894 -155.616148) (xy 383.247556 -155.616615) (xy 383.342587 -155.624101) (xy 383.436737 -155.639019)
			(xy 383.529426 -155.661277) (xy 383.620084 -155.690739) (xy 383.708151 -155.727222) (xy 383.793084 -155.770502)
			(xy 383.87436 -155.820311) (xy 383.951478 -155.876344) (xy 384.023962 -155.938253) (xy 384.091366 -156.005659)
			(xy 384.122676 -156.041598) (xy 384.13026 -156.049608) (xy 384.150268 -156.058834) (xy 384.161284 -156.059378)
			(xy 384.2385 -156.059378) (xy 384.24952 -156.058847) (xy 384.269537 -156.049623) (xy 384.277108 -156.041598)
			(xy 384.308419 -156.005661) (xy 384.375832 -155.938269) (xy 384.448322 -155.87637) (xy 384.525443 -155.820346)
			(xy 384.60672 -155.770543) (xy 384.691652 -155.727267) (xy 384.779717 -155.690784) (xy 384.870371 -155.661319)
			(xy 384.963056 -155.639054) (xy 385.057202 -155.624126) (xy 385.152229 -155.616627) (xy 385.19989 -155.616148)
			(xy 385.250075 -155.616648) (xy 385.350103 -155.624936) (xy 385.449105 -155.641456) (xy 385.546404 -155.666095)
			(xy 385.641336 -155.698684) (xy 385.733253 -155.739003) (xy 385.821526 -155.786773) (xy 385.905553 -155.841671)
			(xy 385.984759 -155.90332) (xy 386.058604 -155.971299) (xy 386.126583 -156.045144) (xy 386.188232 -156.12435)
			(xy 386.243129 -156.208377) (xy 386.290899 -156.296651) (xy 386.331217 -156.388568) (xy 386.363807 -156.4835)
			(xy 386.388445 -156.580799) (xy 386.404965 -156.679801) (xy 386.413252 -156.779829) (xy 386.413756 -156.830014)
			(xy 386.413302 -156.877677) (xy 386.405815 -156.972707) (xy 386.390895 -157.066858) (xy 386.368635 -157.159547)
			(xy 386.339172 -157.250205) (xy 386.302688 -157.338272) (xy 386.259407 -157.423205) (xy 386.209596 -157.504481)
			(xy 386.153563 -157.581599) (xy 386.091652 -157.654083) (xy 386.024245 -157.721486) (xy 385.988306 -157.752796)
			(xy 385.980288 -157.760372) (xy 385.971066 -157.780386) (xy 385.970526 -157.791404) (xy 385.970526 -157.86862)
			(xy 385.971045 -157.879641) (xy 385.980277 -157.899658) (xy 385.988306 -157.907228) (xy 386.024253 -157.938527)
			(xy 386.091646 -158.005941) (xy 386.153544 -158.078433) (xy 386.209567 -158.155555) (xy 386.259369 -158.236834)
			(xy 386.302644 -158.321767) (xy 386.339126 -158.409833) (xy 386.36859 -158.500488) (xy 386.390853 -158.593174)
			(xy 386.40578 -158.687321) (xy 386.413278 -158.782349) (xy 386.413756 -158.83001) (xy 386.413299 -158.877672)
			(xy 386.405812 -158.972703) (xy 386.390893 -159.066853) (xy 386.368633 -159.159543) (xy 386.339171 -159.250201)
			(xy 386.302686 -159.338268) (xy 386.259406 -159.423201) (xy 386.209595 -159.504477) (xy 386.153562 -159.581594)
			(xy 386.091652 -159.654079) (xy 386.024245 -159.721482) (xy 385.988306 -159.752792) (xy 385.980289 -159.76037)
			(xy 385.971067 -159.780382) (xy 385.970526 -159.7914) (xy 385.970526 -159.868616) (xy 385.971047 -159.879637)
			(xy 385.980278 -159.899654) (xy 385.988306 -159.907224) (xy 386.024251 -159.938525) (xy 386.091644 -160.005939)
			(xy 386.153542 -160.078431) (xy 386.209565 -160.155553) (xy 386.259368 -160.236831) (xy 386.302643 -160.321764)
			(xy 386.339125 -160.409829) (xy 386.368589 -160.500484) (xy 386.390852 -160.593171) (xy 386.405779 -160.687317)
			(xy 386.413277 -160.782345) (xy 386.413756 -160.830006) (xy 386.41359 -160.852381) (xy 386.411813 -160.897097)
			(xy 386.4102 -160.919414) (xy 386.4102 -160.919668) (xy 386.409958 -160.928551) (xy 386.414832 -160.945627)
			(xy 386.425194 -160.960048) (xy 386.432298 -160.965388) (xy 386.50545 -161.014664) (xy 386.512994 -161.019448)
			(xy 386.530299 -161.023851) (xy 386.548064 -161.022055) (xy 386.55625 -161.018474) (xy 386.556504 -161.01822)
			(xy 386.606586 -160.994237) (xy 386.709718 -160.953049) (xy 386.815678 -160.919811) (xy 386.923857 -160.894713)
			(xy 387.033629 -160.877899) (xy 387.14436 -160.869468) (xy 387.255412 -160.869468) (xy 387.366143 -160.877899)
			(xy 387.475915 -160.894713) (xy 387.584094 -160.919811) (xy 387.690054 -160.953049) (xy 387.793186 -160.994237)
			(xy 387.843268 -161.01822) (xy 387.843522 -161.018474) (xy 387.851694 -161.022085) (xy 387.869464 -161.023863)
			(xy 387.886764 -161.019431) (xy 387.894322 -161.014664) (xy 387.967474 -160.965388) (xy 387.974676 -160.960145)
			(xy 387.985104 -160.945713) (xy 387.989919 -160.928571) (xy 387.989572 -160.919668) (xy 387.989572 -160.91916)
			(xy 387.987965 -160.896906) (xy 387.986188 -160.852317) (xy 387.986016 -160.830006) (xy 387.986494 -160.782344)
			(xy 387.99398 -160.687314) (xy 388.008897 -160.593165) (xy 388.031155 -160.500476) (xy 388.060616 -160.409818)
			(xy 388.097098 -160.321752) (xy 388.140377 -160.236818) (xy 388.190185 -160.155542) (xy 388.246216 -160.078424)
			(xy 388.308124 -160.005939) (xy 388.375528 -159.938534) (xy 388.411466 -159.907224) (xy 388.419487 -159.89965)
			(xy 388.428704 -159.879634) (xy 388.429246 -159.868616) (xy 388.429246 -159.7914) (xy 388.428725 -159.780379)
			(xy 388.419496 -159.760361) (xy 388.411466 -159.752792) (xy 388.375523 -159.721489) (xy 388.308131 -159.654075)
			(xy 388.246233 -159.581583) (xy 388.19021 -159.504461) (xy 388.140408 -159.423183) (xy 388.097133 -159.33825)
			(xy 388.06065 -159.250185) (xy 388.031186 -159.15953) (xy 388.008922 -159.066845) (xy 387.993994 -158.972698)
			(xy 387.986495 -158.877671) (xy 387.986016 -158.83001) (xy 387.986497 -158.782348) (xy 387.993982 -158.687318)
			(xy 388.0089 -158.593169) (xy 388.031157 -158.50048) (xy 388.060618 -158.409823) (xy 388.097099 -158.321756)
			(xy 388.140378 -158.236823) (xy 388.190186 -158.155546) (xy 388.246216 -158.078428) (xy 388.308124 -158.005943)
			(xy 388.375528 -157.938538) (xy 388.411466 -157.907228) (xy 388.419485 -157.899653) (xy 388.428703 -157.879638)
			(xy 388.429246 -157.86862) (xy 388.429246 -157.791404) (xy 388.428723 -157.780383) (xy 388.419495 -157.760366)
			(xy 388.411466 -157.752796) (xy 388.375525 -157.721491) (xy 388.308133 -157.654077) (xy 388.246235 -157.581585)
			(xy 388.190212 -157.504463) (xy 388.14041 -157.423186) (xy 388.097134 -157.338253) (xy 388.060652 -157.250188)
			(xy 388.031187 -157.159534) (xy 388.008923 -157.066848) (xy 387.993995 -156.972702) (xy 387.986495 -156.877675)
			(xy 387.986016 -156.830014) (xy 387.986566 -156.77983) (xy 387.994853 -156.679805) (xy 388.011372 -156.580807)
			(xy 388.036009 -156.48351) (xy 388.068597 -156.38858) (xy 388.108913 -156.296666) (xy 388.156682 -156.208395)
			(xy 388.211577 -156.12437) (xy 388.273223 -156.045165) (xy 388.341199 -155.971321) (xy 388.415041 -155.903343)
			(xy 388.494244 -155.841695) (xy 388.578267 -155.786798) (xy 388.666537 -155.739027) (xy 388.758451 -155.698709)
			(xy 388.853379 -155.666118) (xy 388.950675 -155.641478) (xy 389.049674 -155.624957) (xy 389.149698 -155.616667)
			(xy 389.199882 -155.616148) (xy 389.247544 -155.616624) (xy 389.342574 -155.624108) (xy 389.436724 -155.639026)
			(xy 389.529414 -155.661283) (xy 389.620071 -155.690744) (xy 389.708138 -155.727226) (xy 389.793071 -155.770505)
			(xy 389.874347 -155.820314) (xy 389.951465 -155.876345) (xy 390.02395 -155.938254) (xy 390.091354 -156.005659)
			(xy 390.122664 -156.041598) (xy 390.130253 -156.049603) (xy 390.150257 -156.058831) (xy 390.161272 -156.059378)
			(xy 390.238488 -156.059378) (xy 390.249507 -156.05884) (xy 390.269524 -156.049622) (xy 390.277096 -156.041598)
			(xy 390.308413 -156.005667) (xy 390.375826 -155.938274) (xy 390.448315 -155.876375) (xy 390.525436 -155.820351)
			(xy 390.606712 -155.770548) (xy 390.691643 -155.727271) (xy 390.779707 -155.690787) (xy 390.870361 -155.661322)
			(xy 390.963045 -155.639057) (xy 391.057191 -155.624128) (xy 391.152217 -155.616628) (xy 391.199878 -155.616148)
			(xy 391.250063 -155.61666) (xy 391.35009 -155.624946) (xy 391.449092 -155.641465) (xy 391.546391 -155.666103)
			(xy 391.641323 -155.698692) (xy 391.73324 -155.73901) (xy 391.821513 -155.78678) (xy 391.90554 -155.841676)
			(xy 391.984746 -155.903324) (xy 392.058591 -155.971303) (xy 392.12657 -156.045147) (xy 392.188219 -156.124354)
			(xy 392.243116 -156.20838) (xy 392.290887 -156.296653) (xy 392.331205 -156.388569) (xy 392.363794 -156.483501)
			(xy 392.388433 -156.5808) (xy 392.404953 -156.679802) (xy 392.41324 -156.779829) (xy 392.413744 -156.830014)
			(xy 392.413294 -156.877677) (xy 392.405807 -156.972708) (xy 392.390887 -157.066858) (xy 392.368627 -157.159548)
			(xy 392.339164 -157.250206) (xy 392.302679 -157.338273) (xy 392.259397 -157.423206) (xy 392.209586 -157.504482)
			(xy 392.153552 -157.581599) (xy 392.091641 -157.654083) (xy 392.024234 -157.721487) (xy 391.988294 -157.752796)
			(xy 391.980274 -157.760371) (xy 391.971054 -157.780386) (xy 391.970514 -157.791404) (xy 391.970514 -157.86862)
			(xy 391.971036 -157.879641) (xy 391.980266 -157.899658) (xy 391.988294 -157.907228) (xy 392.024239 -157.93853)
			(xy 392.091631 -158.005944) (xy 392.15353 -158.078435) (xy 392.209553 -158.155557) (xy 392.259356 -158.236835)
			(xy 392.302632 -158.321768) (xy 392.339114 -158.409833) (xy 392.368577 -158.500488) (xy 392.390841 -158.593175)
			(xy 392.405768 -158.687321) (xy 392.413266 -158.782349) (xy 392.413744 -158.83001) (xy 392.413291 -158.877673)
			(xy 392.405804 -158.972703) (xy 392.390885 -159.066854) (xy 392.368625 -159.159544) (xy 392.339162 -159.250202)
			(xy 392.302678 -159.338268) (xy 392.259396 -159.423202) (xy 392.209585 -159.504478) (xy 392.153552 -159.581595)
			(xy 392.091641 -159.654079) (xy 392.024234 -159.721482) (xy 391.988294 -159.752792) (xy 391.980276 -159.760368)
			(xy 391.971055 -159.780382) (xy 391.970514 -159.7914) (xy 391.970514 -159.868616) (xy 391.971038 -159.879637)
			(xy 391.980267 -159.899653) (xy 391.988294 -159.907224) (xy 392.024237 -159.938528) (xy 392.09163 -160.005941)
			(xy 392.153528 -160.078433) (xy 392.209552 -160.155554) (xy 392.259354 -160.236832) (xy 392.30263 -160.321765)
			(xy 392.339112 -160.40983) (xy 392.368576 -160.500485) (xy 392.39084 -160.593171) (xy 392.405767 -160.687318)
			(xy 392.413265 -160.782345) (xy 392.413744 -160.830006) (xy 392.413267 -160.880192) (xy 392.404978 -160.98022)
			(xy 392.388457 -161.079222) (xy 392.363817 -161.176522) (xy 392.331225 -161.271455) (xy 392.290906 -161.363372)
			(xy 392.243134 -161.451646) (xy 392.188235 -161.535673) (xy 392.126585 -161.614879) (xy 392.058604 -161.688724)
			(xy 391.984758 -161.756703) (xy 391.90555 -161.818351) (xy 391.821522 -161.873248) (xy 391.733247 -161.921018)
			(xy 391.641329 -161.961335) (xy 391.546395 -161.993925) (xy 391.449095 -162.018563) (xy 391.350092 -162.035082)
			(xy 391.250064 -162.043368) (xy 391.199878 -162.043872) (xy 391.152216 -162.043418) (xy 391.057185 -162.03593)
			(xy 390.963035 -162.02101) (xy 390.870345 -161.99875) (xy 390.779688 -161.969287) (xy 390.691621 -161.932803)
			(xy 390.606688 -161.889522) (xy 390.525412 -161.839711) (xy 390.448294 -161.783678) (xy 390.37581 -161.721767)
			(xy 390.308406 -161.654361) (xy 390.277096 -161.618422) (xy 390.269535 -161.610387) (xy 390.249509 -161.601178)
			(xy 390.238488 -161.600642) (xy 390.161272 -161.600642) (xy 390.150249 -161.601151) (xy 390.130232 -161.61039)
			(xy 390.122664 -161.618422) (xy 390.091374 -161.654377) (xy 390.023958 -161.721768) (xy 389.951465 -161.783666)
			(xy 389.874341 -161.839688) (xy 389.793062 -161.88949) (xy 389.708128 -161.932764) (xy 389.620062 -161.969245)
			(xy 389.529406 -161.998708) (xy 389.436719 -162.020971) (xy 389.342571 -162.035897) (xy 389.247544 -162.043394)
			(xy 389.199882 -162.043872) (xy 389.145602 -162.043262) (xy 389.037477 -162.03354) (xy 388.930654 -162.014192)
			(xy 388.825987 -161.985374) (xy 388.77494 -161.96691) (xy 388.761986 -161.962084) (xy 388.73557 -161.966656)
			(xy 388.646416 -162.040316) (xy 388.637018 -162.06597) (xy 388.639304 -162.079432) (xy 388.648117 -162.132911)
			(xy 388.65875 -162.240785) (xy 388.66136 -162.34915) (xy 388.655931 -162.457411) (xy 388.642494 -162.564971)
			(xy 388.621122 -162.67124) (xy 388.591933 -162.775633) (xy 388.555087 -162.877575) (xy 388.510788 -162.976507)
			(xy 388.459279 -163.071883) (xy 388.400842 -163.163179) (xy 388.335801 -163.249894) (xy 388.264511 -163.331549)
			(xy 388.187366 -163.407697) (xy 388.10479 -163.477918) (xy 388.017236 -163.541825) (xy 387.925187 -163.599069)
			(xy 387.829149 -163.649333) (xy 387.729649 -163.692341) (xy 387.627236 -163.727856) (xy 387.522472 -163.755684)
			(xy 387.415934 -163.775672) (xy 387.308208 -163.787708) (xy 387.199886 -163.791727) (xy 387.091564 -163.787708)
			(xy 386.983838 -163.775672) (xy 386.8773 -163.755684) (xy 386.772536 -163.727856) (xy 386.670123 -163.692341)
			(xy 386.570623 -163.649333) (xy 386.474585 -163.599069) (xy 386.382536 -163.541825) (xy 386.294982 -163.477918)
			(xy 386.212406 -163.407697) (xy 386.135261 -163.331549) (xy 386.063971 -163.249894) (xy 385.99893 -163.163179)
			(xy 385.940493 -163.071883) (xy 385.888984 -162.976507) (xy 385.844685 -162.877575) (xy 385.807839 -162.775633)
			(xy 385.77865 -162.67124) (xy 385.757278 -162.564971) (xy 385.743841 -162.457411) (xy 385.738412 -162.34915)
			(xy 385.741022 -162.240785) (xy 385.751655 -162.132911) (xy 385.760468 -162.079432) (xy 385.762754 -162.06597)
			(xy 385.753356 -162.040316) (xy 385.664202 -161.966656) (xy 385.637786 -161.962084) (xy 385.624832 -161.96691)
			(xy 385.573782 -161.985364) (xy 385.469113 -162.014163) (xy 385.362291 -162.033508) (xy 385.254169 -162.043246)
			(xy 385.19989 -162.043872) (xy 385.152228 -162.04341) (xy 385.057197 -162.035923) (xy 384.963047 -162.021004)
			(xy 384.870358 -161.998744) (xy 384.7797 -161.969282) (xy 384.691634 -161.932798) (xy 384.6067 -161.889518)
			(xy 384.525424 -161.839709) (xy 384.448307 -161.783676) (xy 384.375822 -161.721766) (xy 384.308418 -161.654361)
			(xy 384.277108 -161.618422) (xy 384.269543 -161.610392) (xy 384.24952 -161.601181) (xy 384.2385 -161.600642)
			(xy 384.161284 -161.600642) (xy 384.150262 -161.601158) (xy 384.130245 -161.610391) (xy 384.122676 -161.618422)
			(xy 384.091379 -161.654371) (xy 384.023964 -161.721763) (xy 383.951472 -161.78366) (xy 383.874349 -161.839683)
			(xy 383.793071 -161.889485) (xy 383.708137 -161.93276) (xy 383.620071 -161.969242) (xy 383.529416 -161.998705)
			(xy 383.43673 -162.020969) (xy 383.342583 -162.035895) (xy 383.247555 -162.043394) (xy 383.199894 -162.043872)
			(xy 383.14971 -162.043353) (xy 383.049684 -162.035065) (xy 382.950684 -162.018544) (xy 382.853387 -161.993905)
			(xy 382.758456 -161.961315) (xy 382.666541 -161.920997) (xy 382.57827 -161.873226) (xy 382.494245 -161.81833)
			(xy 382.41504 -161.756682) (xy 382.341196 -161.688704) (xy 382.273218 -161.61486) (xy 382.21157 -161.535655)
			(xy 382.156674 -161.45163) (xy 382.108903 -161.363359) (xy 382.068585 -161.271444) (xy 382.035995 -161.176513)
			(xy 382.011356 -161.079216) (xy 381.994835 -160.980216) (xy 381.986547 -160.88019) (xy 381.986028 -160.830006)
			(xy 378.21362 -160.830006) (xy 378.213154 -160.880185) (xy 378.204867 -160.9802) (xy 378.188349 -161.07919)
			(xy 378.163715 -161.176478) (xy 378.131132 -161.271399) (xy 378.090823 -161.363306) (xy 378.043062 -161.451571)
			(xy 377.988176 -161.535591) (xy 377.92654 -161.614791) (xy 377.858576 -161.688633) (xy 377.784746 -161.75661)
			(xy 377.705555 -161.818259) (xy 377.621544 -161.873158) (xy 377.533288 -161.920934) (xy 377.441387 -161.961259)
			(xy 377.346471 -161.993858) (xy 377.249188 -162.018508) (xy 377.150201 -162.035042) (xy 377.050187 -162.043345)
			(xy 377.000008 -162.043872) (xy 376.952346 -162.043397) (xy 376.857316 -162.035911) (xy 376.763166 -162.020993)
			(xy 376.670477 -161.998736) (xy 376.57982 -161.969275) (xy 376.491753 -161.932792) (xy 376.40682 -161.889513)
			(xy 376.325543 -161.839705) (xy 376.248425 -161.783673) (xy 376.175941 -161.721765) (xy 376.108536 -161.65436)
			(xy 376.077226 -161.618422) (xy 376.069653 -161.6104) (xy 376.049636 -161.601184) (xy 376.038618 -161.600642)
			(xy 375.961402 -161.600642) (xy 375.950381 -161.601168) (xy 375.930364 -161.610394) (xy 375.922794 -161.618422)
			(xy 375.891487 -161.654362) (xy 375.824073 -161.721754) (xy 375.751582 -161.783652) (xy 375.67446 -161.839675)
			(xy 375.593183 -161.889478) (xy 375.50825 -161.932754) (xy 375.420186 -161.969236) (xy 375.329532 -161.998701)
			(xy 375.236846 -162.020965) (xy 375.1427 -162.035893) (xy 375.047673 -162.043393) (xy 375.000012 -162.043872)
			(xy 374.950031 -162.043367) (xy 374.850408 -162.035131) (xy 374.7518 -162.01873) (xy 374.654875 -161.994275)
			(xy 374.56029 -161.961933) (xy 374.468684 -161.921921) (xy 374.380679 -161.874511) (xy 374.296872 -161.820025)
			(xy 374.217828 -161.758831) (xy 374.144086 -161.691345) (xy 374.076142 -161.618022) (xy 374.014459 -161.53936)
			(xy 373.959454 -161.455892) (xy 373.911499 -161.368183) (xy 373.87092 -161.276828) (xy 373.83799 -161.182445)
			(xy 373.812935 -161.085673) (xy 373.803926 -161.036508) (xy 373.801331 -161.024879) (xy 373.787304 -161.005662)
			(xy 373.777002 -160.999678) (xy 373.693436 -160.957514) (xy 373.669814 -160.95726) (xy 373.658892 -160.962594)
			(xy 373.611617 -160.985464) (xy 373.514417 -161.025256) (xy 373.414651 -161.058087) (xy 373.312816 -161.083794)
			(xy 373.20942 -161.102248) (xy 373.10498 -161.113358) (xy 373.000016 -161.117067) (xy 372.895052 -161.113358)
			(xy 372.790612 -161.102248) (xy 372.687216 -161.083794) (xy 372.585381 -161.058087) (xy 372.485615 -161.025256)
			(xy 372.388415 -160.985464) (xy 372.34114 -160.962594) (xy 372.330237 -160.95791) (xy 372.306532 -160.958058)
			(xy 372.295674 -160.962848) (xy 372.22303 -160.999678) (xy 372.212755 -161.0057) (xy 372.198706 -161.024888)
			(xy 372.196106 -161.036508) (xy 372.187109 -161.085678) (xy 372.16207 -161.182458) (xy 372.129154 -161.276851)
			(xy 372.088584 -161.368216) (xy 372.040637 -161.455934) (xy 371.985635 -161.539411) (xy 371.923954 -161.61808)
			(xy 371.856009 -161.691408) (xy 371.782263 -161.758898) (xy 371.703215 -161.820093) (xy 371.619401 -161.874578)
			(xy 371.531389 -161.921984) (xy 371.439775 -161.961989) (xy 371.345181 -161.994321) (xy 371.248248 -162.018763)
			(xy 371.149633 -162.035148) (xy 371.050004 -162.043365) (xy 371.00002 -162.043872) (xy 370.952358 -162.043388)
			(xy 370.857328 -162.035903) (xy 370.763179 -162.020987) (xy 370.67049 -161.99873) (xy 370.579832 -161.96927)
			(xy 370.491766 -161.932788) (xy 370.406832 -161.88951) (xy 370.325556 -161.839702) (xy 370.248438 -161.783672)
			(xy 370.175953 -161.721764) (xy 370.108548 -161.65436) (xy 370.077238 -161.618422) (xy 370.06966 -161.610406)
			(xy 370.049647 -161.601186) (xy 370.03863 -161.600642) (xy 369.961414 -161.600642) (xy 369.950394 -161.601175)
			(xy 369.930377 -161.610396) (xy 369.922806 -161.618422) (xy 369.891493 -161.654356) (xy 369.824079 -161.721748)
			(xy 369.751589 -161.783647) (xy 369.674468 -161.83967) (xy 369.593191 -161.889473) (xy 369.508259 -161.93275)
			(xy 369.420196 -161.969233) (xy 369.329542 -161.998698) (xy 369.236857 -162.020963) (xy 369.142711 -162.035892)
			(xy 369.047685 -162.043392) (xy 369.000024 -162.043872) (xy 368.949856 -162.043371) (xy 368.849863 -162.035088)
			(xy 368.750895 -162.018577) (xy 368.653628 -161.99395) (xy 368.558727 -161.961376) (xy 368.466839 -161.921078)
			(xy 368.378593 -161.873329) (xy 368.294591 -161.818457) (xy 368.215407 -161.756836) (xy 368.141581 -161.688887)
			(xy 368.073618 -161.615075) (xy 368.011981 -161.535903) (xy 367.957093 -161.451911) (xy 367.909327 -161.363675)
			(xy 367.86901 -161.271795) (xy 367.836418 -161.1769) (xy 367.811772 -161.079638) (xy 367.795241 -160.980674)
			(xy 367.786939 -160.880682) (xy 367.786412 -160.830514) (xy 367.786412 -160.830006) (xy 367.786905 -160.78235)
			(xy 367.794373 -160.687331) (xy 367.80927 -160.59319) (xy 367.831506 -160.500508) (xy 367.860943 -160.409856)
			(xy 367.897399 -160.321791) (xy 367.94065 -160.236858) (xy 367.99043 -160.155578) (xy 368.046432 -160.078454)
			(xy 368.108311 -160.00596) (xy 368.175685 -159.938542) (xy 368.211608 -159.907224) (xy 368.219619 -159.899642)
			(xy 368.228844 -159.879632) (xy 368.229388 -159.868616) (xy 368.229388 -159.7914) (xy 368.228854 -159.780381)
			(xy 368.219632 -159.760364) (xy 368.211608 -159.752792) (xy 368.173995 -159.719957) (xy 368.103675 -159.649064)
			(xy 368.039416 -159.572635) (xy 367.981654 -159.491184) (xy 367.930779 -159.405264) (xy 367.887134 -159.315454)
			(xy 367.851015 -159.222363) (xy 367.822666 -159.126619) (xy 367.802279 -159.028869) (xy 367.789991 -158.929775)
			(xy 367.785885 -158.830006) (xy 366.214202 -158.830006) (xy 366.210096 -158.929777) (xy 366.197807 -159.028873)
			(xy 366.177418 -159.126625) (xy 366.149068 -159.22237) (xy 366.112947 -159.315464) (xy 366.0693 -159.405274)
			(xy 366.018422 -159.491196) (xy 365.960657 -159.572647) (xy 365.896396 -159.649077) (xy 365.826073 -159.719969)
			(xy 365.788448 -159.752792) (xy 365.780422 -159.760361) (xy 365.771208 -159.780381) (xy 365.770668 -159.7914)
			(xy 365.770668 -159.868616) (xy 365.771207 -159.879634) (xy 365.780427 -159.89965) (xy 365.788448 -159.907224)
			(xy 365.824398 -159.938513) (xy 365.891767 -160.005937) (xy 365.953641 -160.078437) (xy 366.00964 -160.155566)
			(xy 366.059417 -160.236849) (xy 366.102668 -160.321785) (xy 366.139124 -160.409851) (xy 366.168563 -160.500505)
			(xy 366.190801 -160.593187) (xy 366.205703 -160.687329) (xy 366.213177 -160.782349) (xy 366.213644 -160.830006)
			(xy 366.213154 -160.880184) (xy 366.204867 -160.980199) (xy 366.18835 -161.079187) (xy 366.163717 -161.176473)
			(xy 366.131134 -161.271394) (xy 366.090826 -161.3633) (xy 366.043066 -161.451564) (xy 365.988182 -161.535583)
			(xy 365.926547 -161.614783) (xy 365.858584 -161.688624) (xy 365.784756 -161.756601) (xy 365.705567 -161.81825)
			(xy 365.621558 -161.87315) (xy 365.533303 -161.920926) (xy 365.441404 -161.961252) (xy 365.34649 -161.993852)
			(xy 365.249208 -162.018504) (xy 365.150223 -162.035039) (xy 365.05021 -162.043344) (xy 365.000032 -162.043872)
			(xy 364.95237 -162.043379) (xy 364.857341 -162.035896) (xy 364.763192 -162.02098) (xy 364.670502 -161.998724)
			(xy 364.579845 -161.969265) (xy 364.491778 -161.932784) (xy 364.406845 -161.889507) (xy 364.325569 -161.8397)
			(xy 364.24845 -161.78367) (xy 364.175965 -161.721763) (xy 364.10856 -161.65436) (xy 364.07725 -161.618422)
			(xy 364.069668 -161.610411) (xy 364.049658 -161.601189) (xy 364.038642 -161.600642) (xy 363.961426 -161.600642)
			(xy 363.950407 -161.601181) (xy 363.93039 -161.610398) (xy 363.922818 -161.618422) (xy 363.891498 -161.65435)
			(xy 363.824086 -161.721743) (xy 363.751596 -161.783641) (xy 363.674476 -161.839665) (xy 363.5932 -161.889469)
			(xy 363.508268 -161.932746) (xy 363.420205 -161.969229) (xy 363.329552 -161.998695) (xy 363.236868 -162.020961)
			(xy 363.142723 -162.035891) (xy 363.047697 -162.043392) (xy 363.000036 -162.043872) (xy 362.949868 -162.04336)
			(xy 362.849875 -162.035078) (xy 362.750907 -162.018567) (xy 362.653641 -161.993942) (xy 362.55874 -161.961369)
			(xy 362.466852 -161.92107) (xy 362.378606 -161.873323) (xy 362.294604 -161.818451) (xy 362.21542 -161.756831)
			(xy 362.141594 -161.688883) (xy 362.07363 -161.615071) (xy 362.011994 -161.535899) (xy 361.957105 -161.451909)
			(xy 361.909339 -161.363672) (xy 361.869022 -161.271793) (xy 361.83643 -161.176899) (xy 361.811784 -161.079638)
			(xy 361.795253 -160.980673) (xy 361.786951 -160.880682) (xy 361.786424 -160.830514) (xy 361.786424 -160.830006)
			(xy 361.786913 -160.78235) (xy 361.794381 -160.687331) (xy 361.809279 -160.59319) (xy 361.831514 -160.500508)
			(xy 361.860951 -160.409855) (xy 361.897408 -160.321791) (xy 361.94066 -160.236857) (xy 361.99044 -160.155578)
			(xy 362.046442 -160.078453) (xy 362.108322 -160.005959) (xy 362.175696 -159.938542) (xy 362.21162 -159.907224)
			(xy 362.219633 -159.899643) (xy 362.228856 -159.879633) (xy 362.2294 -159.868616) (xy 362.2294 -159.7914)
			(xy 362.228862 -159.780381) (xy 362.219642 -159.760365) (xy 362.21162 -159.752792) (xy 362.174006 -159.719957)
			(xy 362.103686 -159.649065) (xy 362.039427 -159.572635) (xy 361.981664 -159.491185) (xy 361.930788 -159.405265)
			(xy 361.887143 -159.315455) (xy 361.851024 -159.222363) (xy 361.822675 -159.126619) (xy 361.802287 -159.028869)
			(xy 361.789999 -158.929775) (xy 361.785893 -158.830006) (xy 359.492747 -158.830006) (xy 359.596877 -158.939217)
			(xy 359.706261 -159.065454) (xy 359.809514 -159.196753) (xy 359.906403 -159.332816) (xy 359.996708 -159.473335)
			(xy 360.080225 -159.617992) (xy 360.156764 -159.766459) (xy 360.226152 -159.9184) (xy 360.288231 -160.07347)
			(xy 360.342862 -160.231318) (xy 360.389921 -160.391587) (xy 360.4293 -160.553913) (xy 360.460911 -160.71793)
			(xy 360.484682 -160.883264) (xy 360.50056 -161.049543) (xy 360.508507 -161.216389) (xy 360.509058 -161.299906)
			(xy 360.509058 -166.649908) (xy 360.509557 -166.745241) (xy 360.51765 -166.935736) (xy 360.53382 -167.125715)
			(xy 360.558038 -167.314837) (xy 360.590261 -167.502761) (xy 360.629411 -167.684417) (xy 365.513608 -167.684417)
			(xy 365.513608 -167.575771) (xy 365.521539 -167.467414) (xy 365.537358 -167.359925) (xy 365.560981 -167.253878)
			(xy 365.592282 -167.149838) (xy 365.631094 -167.04836) (xy 365.677209 -166.949986) (xy 365.730383 -166.855241)
			(xy 365.790331 -166.76463) (xy 365.856733 -166.678636) (xy 365.929235 -166.597719) (xy 366.00745 -166.522311)
			(xy 366.090961 -166.452812) (xy 366.179322 -166.389595) (xy 366.272062 -166.332997) (xy 366.368686 -166.283319)
			(xy 366.468678 -166.240827) (xy 366.571506 -166.205747) (xy 366.67662 -166.178267) (xy 366.783459 -166.158532)
			(xy 366.891454 -166.146649) (xy 367.000028 -166.142682) (xy 367.108602 -166.146649) (xy 367.216597 -166.158532)
			(xy 367.323436 -166.178267) (xy 367.42855 -166.205747) (xy 367.531378 -166.240827) (xy 367.63137 -166.283319)
			(xy 367.727994 -166.332997) (xy 367.820734 -166.389595) (xy 367.909095 -166.452812) (xy 367.992606 -166.522311)
			(xy 368.070821 -166.597719) (xy 368.143323 -166.678636) (xy 368.209725 -166.76463) (xy 368.252971 -166.829996)
			(xy 397.160973 -166.829996) (xy 397.165078 -166.730227) (xy 397.177366 -166.631132) (xy 397.197754 -166.533381)
			(xy 397.226103 -166.437636) (xy 397.262222 -166.344543) (xy 397.305867 -166.254733) (xy 397.356743 -166.168811)
			(xy 397.414505 -166.08736) (xy 397.478764 -166.010929) (xy 397.549084 -165.940036) (xy 397.586708 -165.907212)
			(xy 397.594725 -165.899634) (xy 397.603946 -165.879622) (xy 397.604488 -165.868604) (xy 397.604488 -165.791388)
			(xy 397.60396 -165.780368) (xy 397.594734 -165.760351) (xy 397.586708 -165.75278) (xy 397.549083 -165.719958)
			(xy 397.478763 -165.649065) (xy 397.414504 -165.572634) (xy 397.356742 -165.491183) (xy 397.305867 -165.405261)
			(xy 397.262223 -165.315451) (xy 397.226104 -165.222358) (xy 397.197756 -165.126613) (xy 397.177369 -165.028863)
			(xy 397.165081 -164.929768) (xy 397.160976 -164.829999) (xy 397.165081 -164.730229) (xy 397.177369 -164.631135)
			(xy 397.197756 -164.533384) (xy 397.226105 -164.437639) (xy 397.262224 -164.344547) (xy 397.305869 -164.254736)
			(xy 397.356744 -164.168815) (xy 397.414506 -164.087364) (xy 397.478764 -164.010933) (xy 397.549085 -163.94004)
			(xy 397.586708 -163.907216) (xy 397.594723 -163.899637) (xy 397.603946 -163.879625) (xy 397.604488 -163.868608)
			(xy 397.604488 -163.791392) (xy 397.603958 -163.780372) (xy 397.594733 -163.760355) (xy 397.586708 -163.752784)
			(xy 397.549087 -163.719958) (xy 397.478767 -163.649065) (xy 397.414508 -163.572634) (xy 397.356746 -163.491183)
			(xy 397.305871 -163.405262) (xy 397.262227 -163.315452) (xy 397.226108 -163.22236) (xy 397.197759 -163.126615)
			(xy 397.177372 -163.028865) (xy 397.165084 -162.92977) (xy 397.160979 -162.830001) (xy 397.165084 -162.730232)
			(xy 397.177372 -162.631138) (xy 397.197759 -162.533388) (xy 397.226107 -162.437643) (xy 397.262226 -162.34455)
			(xy 397.30587 -162.25474) (xy 397.356745 -162.168819) (xy 397.414507 -162.087368) (xy 397.478765 -162.010937)
			(xy 397.549085 -161.940044) (xy 397.586708 -161.90722) (xy 397.594721 -161.899639) (xy 397.603945 -161.879629)
			(xy 397.604488 -161.868612) (xy 397.604488 -161.791396) (xy 397.603956 -161.780376) (xy 397.594733 -161.76036)
			(xy 397.586708 -161.752788) (xy 397.549091 -161.719957) (xy 397.478771 -161.649065) (xy 397.414512 -161.572634)
			(xy 397.35675 -161.491184) (xy 397.305875 -161.405263) (xy 397.262231 -161.315453) (xy 397.226112 -161.222361)
			(xy 397.197763 -161.126617) (xy 397.177375 -161.028867) (xy 397.165088 -160.929773) (xy 397.160982 -160.830004)
			(xy 397.165087 -160.730235) (xy 397.177374 -160.631141) (xy 397.197761 -160.533391) (xy 397.226109 -160.437646)
			(xy 397.262227 -160.344554) (xy 397.305871 -160.254744) (xy 397.356746 -160.168823) (xy 397.414508 -160.087372)
			(xy 397.478765 -160.010941) (xy 397.549085 -159.940048) (xy 397.586708 -159.907224) (xy 397.594719 -159.899642)
			(xy 397.603944 -159.879632) (xy 397.604488 -159.868616) (xy 397.604488 -159.7914) (xy 397.603954 -159.780381)
			(xy 397.594732 -159.760364) (xy 397.586708 -159.752792) (xy 397.549095 -159.719957) (xy 397.478775 -159.649064)
			(xy 397.414516 -159.572635) (xy 397.356754 -159.491184) (xy 397.305879 -159.405264) (xy 397.262234 -159.315454)
			(xy 397.226115 -159.222363) (xy 397.197766 -159.126619) (xy 397.177379 -159.028869) (xy 397.165091 -158.929775)
			(xy 397.160985 -158.830006) (xy 397.16509 -158.730238) (xy 397.177377 -158.631144) (xy 397.197763 -158.533394)
			(xy 397.226111 -158.43765) (xy 397.262229 -158.344558) (xy 397.305873 -158.254748) (xy 397.356747 -158.168827)
			(xy 397.414508 -158.087376) (xy 397.478766 -158.010945) (xy 397.549085 -157.940052) (xy 397.586708 -157.907228)
			(xy 397.594718 -157.899644) (xy 397.603943 -157.879636) (xy 397.604488 -157.86862) (xy 397.604488 -157.791404)
			(xy 397.603952 -157.780385) (xy 397.594731 -157.760368) (xy 397.586708 -157.752796) (xy 397.549099 -157.719956)
			(xy 397.478779 -157.649064) (xy 397.41452 -157.572635) (xy 397.356758 -157.491185) (xy 397.305883 -157.405265)
			(xy 397.262238 -157.315455) (xy 397.226119 -157.222364) (xy 397.19777 -157.12662) (xy 397.177382 -157.028871)
			(xy 397.165094 -156.929777) (xy 397.160988 -156.830009) (xy 397.165093 -156.730241) (xy 397.177379 -156.631147)
			(xy 397.197766 -156.533397) (xy 397.226113 -156.437653) (xy 397.262231 -156.344561) (xy 397.305874 -156.254751)
			(xy 397.356748 -156.16883) (xy 397.414509 -156.08738) (xy 397.478766 -156.010949) (xy 397.549085 -155.940056)
			(xy 397.586708 -155.907232) (xy 397.594716 -155.899646) (xy 397.603942 -155.87964) (xy 397.604488 -155.868624)
			(xy 397.604488 -155.791408) (xy 397.603949 -155.780389) (xy 397.594731 -155.760372) (xy 397.586708 -155.7528)
			(xy 397.549103 -155.719956) (xy 397.478783 -155.649064) (xy 397.414524 -155.572635) (xy 397.356762 -155.491185)
			(xy 397.305887 -155.405266) (xy 397.262242 -155.315457) (xy 397.226123 -155.222366) (xy 397.197774 -155.126622)
			(xy 397.177386 -155.028873) (xy 397.165097 -154.92978) (xy 397.160991 -154.830012) (xy 397.165095 -154.730244)
			(xy 397.177382 -154.63115) (xy 397.197768 -154.533401) (xy 397.226115 -154.437656) (xy 397.262233 -154.344565)
			(xy 397.305876 -154.254755) (xy 397.35675 -154.168834) (xy 397.41451 -154.087383) (xy 397.478767 -154.010953)
			(xy 397.549085 -153.94006) (xy 397.586708 -153.907236) (xy 397.594714 -153.899649) (xy 397.603942 -153.879643)
			(xy 397.604488 -153.868628) (xy 397.604488 -153.791412) (xy 397.603947 -153.780393) (xy 397.59473 -153.760377)
			(xy 397.586708 -153.752804) (xy 397.550784 -153.721486) (xy 397.483413 -153.654066) (xy 397.421536 -153.58157)
			(xy 397.365535 -153.504444) (xy 397.315755 -153.423165) (xy 397.272502 -153.338232) (xy 397.236043 -153.250169)
			(xy 397.206602 -153.159517) (xy 397.184361 -153.066836) (xy 397.169456 -152.972697) (xy 397.16198 -152.877678)
			(xy 397.161512 -152.830022) (xy 397.162073 -152.779845) (xy 397.170357 -152.679834) (xy 397.186871 -152.580848)
			(xy 397.211501 -152.483564) (xy 397.24408 -152.388646) (xy 397.284385 -152.296742) (xy 397.332141 -152.208479)
			(xy 397.387021 -152.124461) (xy 397.448651 -152.045262) (xy 397.51661 -151.971421) (xy 397.590434 -151.903444)
			(xy 397.669619 -151.841794) (xy 397.753623 -151.786893) (xy 397.841874 -151.739116) (xy 397.933768 -151.698789)
			(xy 398.028678 -151.666187) (xy 398.125957 -151.641532) (xy 398.224938 -151.624994) (xy 398.324947 -151.616685)
			(xy 398.375124 -151.616156) (xy 398.422787 -151.616598) (xy 398.517818 -151.624087) (xy 398.611969 -151.639007)
			(xy 398.704659 -151.661268) (xy 398.795316 -151.690732) (xy 398.883383 -151.727218) (xy 398.968317 -151.7705)
			(xy 399.049592 -151.820312) (xy 399.12671 -151.876346) (xy 399.199193 -151.938258) (xy 399.266597 -152.005666)
			(xy 399.297906 -152.041606) (xy 399.305477 -152.049631) (xy 399.325495 -152.058848) (xy 399.336514 -152.059386)
			(xy 399.41373 -152.059386) (xy 399.424752 -152.058869) (xy 399.444768 -152.049635) (xy 399.452338 -152.041606)
			(xy 399.483634 -152.005656) (xy 399.551049 -151.938264) (xy 399.623541 -151.876366) (xy 399.700663 -151.820343)
			(xy 399.781942 -151.77054) (xy 399.866876 -151.727265) (xy 399.954941 -151.690783) (xy 400.045597 -151.66132)
			(xy 400.138284 -151.639057) (xy 400.232431 -151.624131) (xy 400.327459 -151.616634) (xy 400.37512 -151.616156)
			(xy 400.425287 -151.616687) (xy 400.525277 -151.624972) (xy 400.624243 -151.641486) (xy 400.721506 -151.666114)
			(xy 400.816405 -151.698689) (xy 400.908289 -151.738988) (xy 400.996533 -151.786735) (xy 401.080533 -151.841606)
			(xy 401.159716 -151.903225) (xy 401.23354 -151.971171) (xy 401.301503 -152.044981) (xy 401.363139 -152.12415)
			(xy 401.418028 -152.208138) (xy 401.465796 -152.296372) (xy 401.506115 -152.388247) (xy 401.53871 -152.483139)
			(xy 401.56336 -152.580397) (xy 401.579895 -152.679359) (xy 401.588202 -152.779347) (xy 401.588732 -152.829514)
			(xy 401.588732 -152.830022) (xy 401.588278 -152.877679) (xy 401.580808 -152.9727) (xy 401.565908 -153.066842)
			(xy 401.543669 -153.159525) (xy 401.514229 -153.250178) (xy 401.477769 -153.338243) (xy 401.434513 -153.423176)
			(xy 401.384729 -153.504455) (xy 401.328723 -153.581579) (xy 401.26684 -153.654072) (xy 401.199462 -153.721487)
			(xy 401.163536 -153.752804) (xy 401.155503 -153.760367) (xy 401.146292 -153.780391) (xy 401.145756 -153.791412)
			(xy 401.145756 -153.868628) (xy 401.146261 -153.879651) (xy 401.155502 -153.899669) (xy 401.163536 -153.907236)
			(xy 401.201179 -153.940039) (xy 401.271502 -154.010932) (xy 401.335763 -154.087363) (xy 401.393527 -154.168815)
			(xy 401.444405 -154.254738) (xy 401.488051 -154.34455) (xy 401.524171 -154.437644) (xy 401.55252 -154.533391)
			(xy 401.572908 -154.631143) (xy 401.585195 -154.73024) (xy 401.5893 -154.830012) (xy 401.585193 -154.929783)
			(xy 401.572904 -155.02888) (xy 401.552515 -155.126632) (xy 401.524163 -155.222378) (xy 401.488042 -155.315472)
			(xy 401.444394 -155.405283) (xy 401.393515 -155.491204) (xy 401.335749 -155.572655) (xy 401.271486 -155.649085)
			(xy 401.201162 -155.719977) (xy 401.163536 -155.7528) (xy 401.155505 -155.760364) (xy 401.146293 -155.780388)
			(xy 401.145756 -155.791408) (xy 401.145756 -155.868624) (xy 401.146263 -155.879647) (xy 401.155502 -155.899664)
			(xy 401.163536 -155.907232) (xy 401.201175 -155.94004) (xy 401.271498 -156.010932) (xy 401.335759 -156.087363)
			(xy 401.393523 -156.168815) (xy 401.444401 -156.254737) (xy 401.488047 -156.344549) (xy 401.524167 -156.437643)
			(xy 401.552517 -156.533389) (xy 401.572904 -156.631141) (xy 401.585192 -156.730238) (xy 401.589297 -156.830009)
			(xy 401.585191 -156.92978) (xy 401.572901 -157.028877) (xy 401.552512 -157.126628) (xy 401.524161 -157.222375)
			(xy 401.48804 -157.315468) (xy 401.444392 -157.405279) (xy 401.393514 -157.4912) (xy 401.335748 -157.572651)
			(xy 401.271486 -157.649081) (xy 401.201161 -157.719973) (xy 401.163536 -157.752796) (xy 401.155507 -157.760362)
			(xy 401.146294 -157.780384) (xy 401.145756 -157.791404) (xy 401.145756 -157.86862) (xy 401.146265 -157.879643)
			(xy 401.155503 -157.89966) (xy 401.163536 -157.907228) (xy 401.201171 -157.94004) (xy 401.271494 -158.010933)
			(xy 401.335755 -158.087363) (xy 401.393519 -158.168814) (xy 401.444397 -158.254736) (xy 401.488043 -158.344548)
			(xy 401.524163 -158.437641) (xy 401.552513 -158.533387) (xy 401.572901 -158.631139) (xy 401.585189 -158.730236)
			(xy 401.589294 -158.830006) (xy 401.585188 -158.929777) (xy 401.572899 -159.028874) (xy 401.55251 -159.126625)
			(xy 401.524159 -159.222371) (xy 401.488038 -159.315464) (xy 401.444391 -159.405275) (xy 401.393512 -159.491197)
			(xy 401.335747 -159.572647) (xy 401.271485 -159.649077) (xy 401.201161 -159.719969) (xy 401.163536 -159.752792)
			(xy 401.155508 -159.760359) (xy 401.146295 -159.78038) (xy 401.145756 -159.7914) (xy 401.145756 -159.868616)
			(xy 401.146267 -159.879639) (xy 401.155504 -159.899656) (xy 401.163536 -159.907224) (xy 401.201167 -159.940041)
			(xy 401.27149 -160.010933) (xy 401.335751 -160.087363) (xy 401.393516 -160.168814) (xy 401.444393 -160.254735)
			(xy 401.488039 -160.344546) (xy 401.52416 -160.43764) (xy 401.55251 -160.533386) (xy 401.572898 -160.631137)
			(xy 401.585186 -160.730233) (xy 401.589291 -160.830004) (xy 401.585185 -160.929774) (xy 401.572896 -161.028871)
			(xy 401.552508 -161.126622) (xy 401.524157 -161.222368) (xy 401.488036 -161.315461) (xy 401.444389 -161.405272)
			(xy 401.393511 -161.491193) (xy 401.335746 -161.572643) (xy 401.271485 -161.649073) (xy 401.201161 -161.719965)
			(xy 401.163536 -161.752788) (xy 401.15551 -161.760357) (xy 401.146296 -161.780377) (xy 401.145756 -161.791396)
			(xy 401.145756 -161.868612) (xy 401.146269 -161.879634) (xy 401.155504 -161.899652) (xy 401.163536 -161.90722)
			(xy 401.201163 -161.940041) (xy 401.271486 -162.010933) (xy 401.335747 -162.087363) (xy 401.393512 -162.168813)
			(xy 401.444389 -162.254734) (xy 401.488036 -162.344545) (xy 401.524156 -162.437638) (xy 401.552506 -162.533384)
			(xy 401.572894 -162.631135) (xy 401.585182 -162.730231) (xy 401.589288 -162.830001) (xy 401.585182 -162.929772)
			(xy 401.572894 -163.028867) (xy 401.552505 -163.126619) (xy 401.524155 -163.222364) (xy 401.488035 -163.315457)
			(xy 401.444388 -163.405268) (xy 401.39351 -163.491189) (xy 401.335745 -163.57264) (xy 401.271484 -163.649069)
			(xy 401.201161 -163.719961) (xy 401.163536 -163.752784) (xy 401.155512 -163.760355) (xy 401.146296 -163.780373)
			(xy 401.145756 -163.791392) (xy 401.145756 -163.868608) (xy 401.146272 -163.87963) (xy 401.155505 -163.899648)
			(xy 401.163536 -163.907216) (xy 401.201159 -163.940041) (xy 401.271482 -164.010933) (xy 401.335743 -164.087362)
			(xy 401.393508 -164.168813) (xy 401.444385 -164.254734) (xy 401.488032 -164.344544) (xy 401.524152 -164.437637)
			(xy 401.552503 -164.533382) (xy 401.572891 -164.631133) (xy 401.585179 -164.730229) (xy 401.589285 -164.829999)
			(xy 401.585179 -164.929769) (xy 401.572891 -165.028864) (xy 401.552503 -165.126615) (xy 401.524153 -165.222361)
			(xy 401.488033 -165.315454) (xy 401.444386 -165.405264) (xy 401.393509 -165.491185) (xy 401.335745 -165.572636)
			(xy 401.271484 -165.649065) (xy 401.201161 -165.719957) (xy 401.163536 -165.75278) (xy 401.155514 -165.760352)
			(xy 401.146297 -165.78037) (xy 401.145756 -165.791388) (xy 401.145756 -165.868604) (xy 401.146274 -165.879626)
			(xy 401.155505 -165.899643) (xy 401.163536 -165.907212) (xy 401.201155 -165.940042) (xy 401.271478 -166.010933)
			(xy 401.335739 -166.087362) (xy 401.393504 -166.168812) (xy 401.444381 -166.254733) (xy 401.488028 -166.344543)
			(xy 401.524149 -166.437635) (xy 401.552499 -166.53338) (xy 401.572887 -166.631131) (xy 401.585176 -166.730226)
			(xy 401.589282 -166.829996) (xy 401.585177 -166.929766) (xy 401.572889 -167.028861) (xy 401.552501 -167.126612)
			(xy 401.524151 -167.222357) (xy 401.488031 -167.31545) (xy 401.444385 -167.40526) (xy 401.393508 -167.491181)
			(xy 401.335744 -167.572632) (xy 401.271483 -167.649061) (xy 401.201161 -167.719953) (xy 401.163536 -167.752776)
			(xy 401.155516 -167.76035) (xy 401.146298 -167.780366) (xy 401.145756 -167.791384) (xy 401.145756 -167.8686)
			(xy 401.146276 -167.879622) (xy 401.155506 -167.899639) (xy 401.163536 -167.907208) (xy 401.199475 -167.938508)
			(xy 401.266845 -168.005932) (xy 401.32872 -168.07843) (xy 401.384719 -168.155558) (xy 401.434498 -168.236839)
			(xy 401.477749 -168.321774) (xy 401.514207 -168.409839) (xy 401.543646 -168.500491) (xy 401.565886 -168.593173)
			(xy 401.58079 -168.687314) (xy 401.588265 -168.782333) (xy 401.588732 -168.82999) (xy 401.588238 -168.880168)
			(xy 401.579953 -168.980183) (xy 401.563437 -169.079172) (xy 401.538804 -169.176459) (xy 401.506223 -169.271379)
			(xy 401.465915 -169.363286) (xy 401.418156 -169.45155) (xy 401.363272 -169.53557) (xy 401.301637 -169.61477)
			(xy 401.233674 -169.688611) (xy 401.159846 -169.756589) (xy 401.080657 -169.818238) (xy 400.996648 -169.873138)
			(xy 400.908392 -169.920914) (xy 400.816494 -169.961239) (xy 400.721579 -169.993839) (xy 400.624297 -170.01849)
			(xy 400.525311 -170.035024) (xy 400.425298 -170.043329) (xy 400.37512 -170.043856) (xy 400.327458 -170.043378)
			(xy 400.232428 -170.035893) (xy 400.138278 -170.020976) (xy 400.045589 -169.998719) (xy 399.954931 -169.969258)
			(xy 399.866864 -169.932776) (xy 399.781931 -169.889498) (xy 399.700655 -169.839689) (xy 399.623537 -169.783658)
			(xy 399.551052 -169.721749) (xy 399.483648 -169.654345) (xy 399.452338 -169.618406) (xy 399.444748 -169.610403)
			(xy 399.424745 -169.601173) (xy 399.41373 -169.600626) (xy 399.336514 -169.600626) (xy 399.325495 -169.601163)
			(xy 399.305478 -169.610382) (xy 399.297906 -169.618406) (xy 399.266589 -169.654337) (xy 399.199176 -169.721729)
			(xy 399.126687 -169.783628) (xy 399.049566 -169.839652) (xy 398.96829 -169.889456) (xy 398.883358 -169.932733)
			(xy 398.795295 -169.969216) (xy 398.704641 -169.998681) (xy 398.611956 -170.020947) (xy 398.517811 -170.035876)
			(xy 398.422785 -170.043376) (xy 398.375124 -170.043856) (xy 398.324958 -170.043271) (xy 398.224969 -170.034989)
			(xy 398.126005 -170.018479) (xy 398.028743 -169.993855) (xy 397.933845 -169.961284) (xy 397.841961 -169.920988)
			(xy 397.753718 -169.873244) (xy 397.669718 -169.818376) (xy 397.590535 -169.756761) (xy 397.516711 -169.688817)
			(xy 397.448748 -169.61501) (xy 397.387111 -169.535844) (xy 397.332221 -169.451859) (xy 397.284453 -169.363628)
			(xy 397.244133 -169.271755) (xy 397.211537 -169.176866) (xy 397.186887 -169.07961) (xy 397.170351 -168.98065)
			(xy 397.162042 -168.880664) (xy 397.161512 -168.830498) (xy 397.161512 -168.82999) (xy 397.161994 -168.782334)
			(xy 397.169463 -168.687314) (xy 397.184361 -168.593173) (xy 397.206598 -168.500491) (xy 397.236036 -168.409839)
			(xy 397.272493 -168.321774) (xy 397.315746 -168.236841) (xy 397.365527 -168.155562) (xy 397.42153 -168.078437)
			(xy 397.483409 -168.005943) (xy 397.550784 -167.938526) (xy 397.586708 -167.907208) (xy 397.594727 -167.899632)
			(xy 397.603947 -167.879618) (xy 397.604488 -167.8686) (xy 397.604488 -167.791384) (xy 397.603963 -167.780363)
			(xy 397.594735 -167.760347) (xy 397.586708 -167.752776) (xy 397.549079 -167.719959) (xy 397.478759 -167.649065)
			(xy 397.4145 -167.572634) (xy 397.356739 -167.491182) (xy 397.305863 -167.40526) (xy 397.262219 -167.31545)
			(xy 397.226101 -167.222357) (xy 397.197752 -167.126611) (xy 397.177365 -167.028861) (xy 397.165078 -166.929766)
			(xy 397.160973 -166.829996) (xy 368.252971 -166.829996) (xy 368.269673 -166.855241) (xy 368.322847 -166.949986)
			(xy 368.368962 -167.04836) (xy 368.407774 -167.149838) (xy 368.439075 -167.253878) (xy 368.462698 -167.359925)
			(xy 368.478517 -167.467414) (xy 368.486448 -167.575771) (xy 368.486944 -167.630094) (xy 368.486448 -167.684417)
			(xy 368.478517 -167.792774) (xy 368.462698 -167.900263) (xy 368.439075 -168.00631) (xy 368.407774 -168.11035)
			(xy 368.368962 -168.211828) (xy 368.322847 -168.310202) (xy 368.269673 -168.404947) (xy 368.209725 -168.495558)
			(xy 368.143323 -168.581552) (xy 368.070821 -168.662469) (xy 367.992606 -168.737877) (xy 367.909095 -168.807376)
			(xy 367.820734 -168.870593) (xy 367.727994 -168.927191) (xy 367.63137 -168.976869) (xy 367.531378 -169.019361)
			(xy 367.42855 -169.054441) (xy 367.323436 -169.081921) (xy 367.216597 -169.101656) (xy 367.108602 -169.113539)
			(xy 367.000028 -169.117507) (xy 366.891454 -169.113539) (xy 366.783459 -169.101656) (xy 366.67662 -169.081921)
			(xy 366.571506 -169.054441) (xy 366.468678 -169.019361) (xy 366.368686 -168.976869) (xy 366.272062 -168.927191)
			(xy 366.179322 -168.870593) (xy 366.090961 -168.807376) (xy 366.00745 -168.737877) (xy 365.929235 -168.662469)
			(xy 365.856733 -168.581552) (xy 365.790331 -168.495558) (xy 365.730383 -168.404947) (xy 365.677209 -168.310202)
			(xy 365.631094 -168.211828) (xy 365.592282 -168.11035) (xy 365.560981 -168.00631) (xy 365.537358 -167.900263)
			(xy 365.521539 -167.792774) (xy 365.513608 -167.684417) (xy 360.629411 -167.684417) (xy 360.630431 -167.689148)
			(xy 360.678475 -167.873662) (xy 360.734307 -168.05597) (xy 360.797826 -168.235745) (xy 360.868918 -168.412662)
			(xy 360.947454 -168.586403) (xy 361.033294 -168.756653) (xy 361.126281 -168.923107) (xy 361.22625 -169.085465)
			(xy 361.333019 -169.243433) (xy 361.446396 -169.396728) (xy 361.566177 -169.545073) (xy 361.692146 -169.6882)
			(xy 361.824076 -169.825852) (xy 361.961729 -169.957781) (xy 362.104858 -170.083749) (xy 362.253204 -170.203529)
			(xy 362.406499 -170.316905) (xy 362.564469 -170.423672) (xy 362.726827 -170.523639) (xy 362.893282 -170.616625)
			(xy 363.063534 -170.702463) (xy 363.237275 -170.780998) (xy 363.414192 -170.852088) (xy 363.593968 -170.915605)
			(xy 363.776277 -170.971436) (xy 363.960791 -171.019478) (xy 364.147178 -171.059646) (xy 364.335102 -171.091868)
			(xy 364.524225 -171.116085) (xy 364.714204 -171.132253) (xy 364.904699 -171.140344) (xy 365.000032 -171.140882)
			(xy 403.999954 -171.140882) (xy 404.095288 -171.140384) (xy 404.285785 -171.132294) (xy 404.475767 -171.116126)
			(xy 404.664891 -171.091909) (xy 404.852817 -171.059688) (xy 405.039206 -171.01952) (xy 405.223723 -170.971477)
			(xy 405.406034 -170.915647) (xy 405.585812 -170.852129) (xy 405.762731 -170.781038) (xy 405.936475 -170.702503)
			(xy 406.106728 -170.616665) (xy 406.273185 -170.523678) (xy 406.435545 -170.423711) (xy 406.593517 -170.316942)
			(xy 406.746814 -170.203565) (xy 406.895162 -170.083785) (xy 407.038292 -169.957816) (xy 407.175947 -169.825886)
			(xy 407.307879 -169.688232) (xy 407.43385 -169.545103) (xy 407.553632 -169.396757) (xy 407.667011 -169.243461)
			(xy 407.773781 -169.085491) (xy 407.873751 -168.923132) (xy 407.96674 -168.756676) (xy 408.05258 -168.586423)
			(xy 408.131117 -168.412681) (xy 408.20221 -168.235762) (xy 408.26573 -168.055986) (xy 408.321562 -167.873675)
			(xy 408.369607 -167.689159) (xy 408.409778 -167.50277) (xy 408.442001 -167.314844) (xy 408.46622 -167.12572)
			(xy 408.48239 -166.935739) (xy 408.490483 -166.745242) (xy 408.490928 -166.649908) (xy 408.490928 -163.299902)
			(xy 408.491427 -163.194368) (xy 408.499512 -162.983455) (xy 408.515669 -162.773006) (xy 408.539875 -162.563331)
			(xy 408.572094 -162.354737) (xy 408.61228 -162.14753) (xy 408.660372 -161.942014) (xy 408.716302 -161.738491)
			(xy 408.779985 -161.53726) (xy 408.85133 -161.338616) (xy 408.930231 -161.14285) (xy 409.016573 -160.95025)
			(xy 409.110228 -160.761098) (xy 409.21106 -160.575672) (xy 409.31892 -160.394245) (xy 409.43365 -160.217082)
			(xy 409.555081 -160.044444) (xy 409.683036 -159.876583) (xy 409.817327 -159.713747) (xy 409.957756 -159.556174)
			(xy 410.104118 -159.404096) (xy 410.256198 -159.257735) (xy 410.413771 -159.117306) (xy 410.576608 -158.983016)
			(xy 410.74447 -158.855062) (xy 410.917109 -158.733632) (xy 411.094272 -158.618903) (xy 411.2757 -158.511044)
			(xy 411.461126 -158.410213) (xy 411.650279 -158.316559) (xy 411.842879 -158.230219) (xy 412.038645 -158.151319)
			(xy 412.23729 -158.079975) (xy 412.438522 -158.016293) (xy 412.642045 -157.960365) (xy 412.847561 -157.912273)
			(xy 413.054769 -157.872089) (xy 413.263363 -157.839871) (xy 413.473038 -157.815666) (xy 413.683487 -157.79951)
			(xy 413.8944 -157.791427) (xy 413.999934 -157.790896) (xy 434.999892 -157.790896) (xy 435.095226 -157.79039)
			(xy 435.285721 -157.782299) (xy 435.475702 -157.766129) (xy 435.664825 -157.741911) (xy 435.85275 -157.709689)
			(xy 436.039137 -157.66952) (xy 436.223653 -157.621476) (xy 436.405963 -157.565645) (xy 436.585739 -157.502126)
			(xy 436.762657 -157.431035) (xy 436.936399 -157.3525) (xy 437.106651 -157.266661) (xy 437.273106 -157.173674)
			(xy 437.435465 -157.073706) (xy 437.593435 -156.966938) (xy 437.746732 -156.853561) (xy 437.895078 -156.73378)
			(xy 438.038207 -156.607812) (xy 438.175861 -156.475882) (xy 438.307792 -156.338229) (xy 438.433761 -156.195101)
			(xy 438.553543 -156.046755) (xy 438.66692 -155.89346) (xy 438.77369 -155.73549) (xy 438.873659 -155.573132)
			(xy 438.966647 -155.406677) (xy 439.052487 -155.236426) (xy 439.131023 -155.062685) (xy 439.202116 -154.885767)
			(xy 439.265635 -154.705991) (xy 439.321468 -154.523682) (xy 439.369513 -154.339167) (xy 439.409683 -154.152779)
			(xy 439.441907 -153.964854) (xy 439.466126 -153.775732) (xy 439.482297 -153.585751) (xy 439.49039 -153.395256)
			(xy 439.490866 -153.299922) (xy 439.490866 -136.77011) (xy 439.491377 -136.664578) (xy 439.499472 -136.453669)
			(xy 439.515639 -136.243225) (xy 439.539854 -136.033554) (xy 439.572082 -135.824965) (xy 439.612275 -135.617763)
			(xy 439.660375 -135.412253) (xy 439.71631 -135.208736) (xy 439.78 -135.00751) (xy 439.851349 -134.808871)
			(xy 439.930254 -134.613111) (xy 440.016599 -134.420517) (xy 440.110257 -134.231371) (xy 440.211091 -134.045951)
			(xy 440.318953 -133.864528) (xy 440.433684 -133.687371) (xy 440.555116 -133.514737) (xy 440.68307 -133.346881)
			(xy 440.81736 -133.184049) (xy 440.957788 -133.026479) (xy 441.104148 -132.874404) (xy 441.256225 -132.728046)
			(xy 441.413796 -132.58762) (xy 441.576629 -132.453332) (xy 441.744487 -132.325379) (xy 441.917122 -132.203949)
			(xy 442.094281 -132.08922) (xy 442.275704 -131.981361) (xy 442.461126 -131.880529) (xy 442.650273 -131.786873)
			(xy 442.842868 -131.70053) (xy 443.038629 -131.621627) (xy 443.237269 -131.55028) (xy 443.438495 -131.486593)
			(xy 443.642013 -131.430659) (xy 443.847524 -131.382562) (xy 444.054726 -131.342371) (xy 444.263316 -131.310146)
			(xy 444.472987 -131.285933) (xy 444.683431 -131.269768) (xy 444.89434 -131.261676) (xy 444.999872 -131.261104)
			(xy 471.000074 -131.261104) (xy 471.095408 -131.260599) (xy 471.285904 -131.252508) (xy 471.475885 -131.236339)
			(xy 471.665009 -131.212122) (xy 471.852935 -131.1799) (xy 472.039323 -131.139731) (xy 472.223839 -131.091688)
			(xy 472.40615 -131.035857) (xy 472.585927 -130.972339) (xy 472.762846 -130.901249) (xy 472.936588 -130.822713)
			(xy 473.106841 -130.736875) (xy 473.273298 -130.643888) (xy 473.435658 -130.543921) (xy 473.593628 -130.437152)
			(xy 473.746926 -130.323776) (xy 473.895273 -130.203995) (xy 474.038403 -130.078027) (xy 474.176057 -129.946097)
			(xy 474.307989 -129.808444) (xy 474.433959 -129.665316) (xy 474.553742 -129.51697) (xy 474.66712 -129.363674)
			(xy 474.77389 -129.205705) (xy 474.87386 -129.043346) (xy 474.966849 -128.876891) (xy 475.052689 -128.706639)
			(xy 475.131227 -128.532897) (xy 475.20232 -128.355979) (xy 475.26584 -128.176203) (xy 475.321673 -127.993893)
			(xy 475.369718 -127.809378) (xy 475.409889 -127.62299) (xy 475.442114 -127.435064) (xy 475.466333 -127.245941)
			(xy 475.482504 -127.05596) (xy 475.490597 -126.865464) (xy 475.491048 -126.77013) (xy 475.491048 -21.770086)
			(xy 475.490549 -21.674753) (xy 475.482456 -21.484258) (xy 475.466286 -21.294279) (xy 475.442067 -21.105157)
			(xy 475.409844 -20.917234) (xy 475.369674 -20.730847) (xy 475.321629 -20.546333) (xy 475.265797 -20.364024)
			(xy 475.202278 -20.18425) (xy 475.131186 -20.007333) (xy 475.05265 -19.833593) (xy 474.966811 -19.663342)
			(xy 474.873823 -19.496888) (xy 474.773855 -19.334531) (xy 474.667086 -19.176562) (xy 474.553708 -19.023267)
			(xy 474.433927 -18.874923) (xy 474.307958 -18.731795) (xy 474.176028 -18.594143) (xy 474.038375 -18.462215)
			(xy 473.895247 -18.336247) (xy 473.746901 -18.216467) (xy 473.593605 -18.103091) (xy 473.435636 -17.996324)
			(xy 473.273277 -17.896357) (xy 473.106823 -17.803371) (xy 472.936571 -17.717533) (xy 472.76283 -17.638998)
			(xy 472.585913 -17.567908) (xy 472.406138 -17.50439) (xy 472.223829 -17.44856) (xy 472.039314 -17.400517)
			(xy 471.852927 -17.360349) (xy 471.665003 -17.328127) (xy 471.475881 -17.30391) (xy 471.285902 -17.287741)
			(xy 471.095407 -17.27965) (xy 471.000074 -17.279112) (xy 444.999872 -17.279112) (xy 444.894339 -17.278602)
			(xy 444.683429 -17.27051) (xy 444.472984 -17.254345) (xy 444.263312 -17.230132) (xy 444.054721 -17.197906)
			(xy 443.847518 -17.157714) (xy 443.642006 -17.109616) (xy 443.438487 -17.053682) (xy 443.237259 -16.989994)
			(xy 443.038619 -16.918645) (xy 442.842857 -16.839741) (xy 442.650261 -16.753397) (xy 442.461113 -16.65974)
			(xy 442.275691 -16.558907) (xy 442.094267 -16.451046) (xy 441.917108 -16.336315) (xy 441.744473 -16.214883)
			(xy 441.576615 -16.086929) (xy 441.413781 -15.952639) (xy 441.25621 -15.812211) (xy 441.104134 -15.665851)
			(xy 440.957774 -15.513774) (xy 440.817347 -15.356202) (xy 440.683058 -15.193368) (xy 440.555104 -15.02551)
			(xy 440.433673 -14.852874) (xy 440.318943 -14.675714) (xy 440.211083 -14.49429) (xy 440.11025 -14.308867)
			(xy 440.016594 -14.119719) (xy 439.93025 -13.927123) (xy 439.851347 -13.73136) (xy 439.779999 -13.53272)
			(xy 439.716312 -13.331492) (xy 439.660379 -13.127973) (xy 439.612281 -12.922461) (xy 439.572091 -12.715257)
			(xy 439.539865 -12.506666) (xy 439.515653 -12.296994) (xy 439.499489 -12.086549) (xy 439.491397 -11.875639)
			(xy 439.490866 -11.770106) (xy 439.490866 -4.99999) (xy 439.49036 -4.904657) (xy 439.482267 -4.714162)
			(xy 439.466097 -4.524183) (xy 439.441879 -4.335061) (xy 439.409656 -4.147137) (xy 439.369486 -3.96075)
			(xy 439.321442 -3.776236) (xy 439.26561 -3.593927) (xy 439.202091 -3.414153) (xy 439.130999 -3.237235)
			(xy 439.052463 -3.063495) (xy 438.966624 -2.893244) (xy 438.873637 -2.72679) (xy 438.773669 -2.564432)
			(xy 438.6669 -2.406464) (xy 438.553523 -2.253169) (xy 438.433742 -2.104824) (xy 438.307774 -1.961696)
			(xy 438.175844 -1.824043) (xy 438.038191 -1.692114) (xy 437.895063 -1.566146) (xy 437.746717 -1.446366)
			(xy 437.593422 -1.33299) (xy 437.435453 -1.226222) (xy 437.273094 -1.126254) (xy 437.10664 -1.033267)
			(xy 436.936389 -0.947429) (xy 436.762648 -0.868894) (xy 436.585731 -0.797803) (xy 436.405955 -0.734284)
			(xy 436.223646 -0.678453) (xy 436.039132 -0.63041) (xy 435.852745 -0.590241) (xy 435.664821 -0.558018)
			(xy 435.475699 -0.533801) (xy 435.28572 -0.517631) (xy 435.095225 -0.50954) (xy 434.999892 -0.509016)
			(xy 4.99999 -0.509016) (xy 4.904657 -0.509522) (xy 4.714162 -0.517614) (xy 4.524182 -0.533784) (xy 4.335059 -0.558002)
			(xy 4.147135 -0.590225) (xy 3.960748 -0.630394) (xy 3.776233 -0.678438) (xy 3.593924 -0.73427) (xy 3.414149 -0.797788)
			(xy 3.237231 -0.86888) (xy 3.06349 -0.947415) (xy 2.893239 -1.033254) (xy 2.726784 -1.126242) (xy 2.564426 -1.22621)
			(xy 2.406456 -1.332978) (xy 2.253161 -1.446355) (xy 2.104815 -1.566136) (xy 1.961687 -1.692104) (xy 1.824034 -1.824034)
			(xy 1.692104 -1.961687) (xy 1.566136 -2.104815) (xy 1.446355 -2.253161) (xy 1.332978 -2.406456) (xy 1.22621 -2.564426)
			(xy 1.126242 -2.726784) (xy 1.033254 -2.893239) (xy 0.947415 -3.06349) (xy 0.86888 -3.237231) (xy 0.797788 -3.414149)
			(xy 0.73427 -3.593924) (xy 0.678438 -3.776233) (xy 0.646137 -3.900286) (xy 59.465106 -3.900286) (xy 59.471831 -3.783378)
			(xy 59.486516 -3.667201) (xy 59.509092 -3.552297) (xy 59.539454 -3.4392) (xy 59.577461 -3.328438)
			(xy 59.622935 -3.220527) (xy 59.675664 -3.115969) (xy 59.735404 -3.015253) (xy 59.801875 -2.918846)
			(xy 59.874768 -2.827198) (xy 59.953743 -2.740736) (xy 60.038433 -2.659864) (xy 60.128442 -2.584957)
			(xy 60.223352 -2.516365) (xy 60.32272 -2.454408) (xy 60.426083 -2.399373) (xy 60.532959 -2.351518)
			(xy 60.642851 -2.311065) (xy 60.755247 -2.278204) (xy 60.869623 -2.253086) (xy 60.985446 -2.23583)
			(xy 61.102176 -2.226514) (xy 61.219269 -2.225184) (xy 61.336181 -2.231845) (xy 61.452366 -2.246466)
			(xy 61.567283 -2.268978) (xy 61.680396 -2.299278) (xy 61.791179 -2.337224) (xy 61.899115 -2.382638)
			(xy 62.003702 -2.43531) (xy 62.104452 -2.494994) (xy 62.200895 -2.561413) (xy 62.292583 -2.634255)
			(xy 62.336172 -2.67335) (xy 62.343731 -2.679658) (xy 62.362196 -2.686443) (xy 62.381859 -2.68581)
			(xy 62.391036 -2.68224) (xy 62.476126 -2.644394) (xy 62.484905 -2.639997) (xy 62.498544 -2.625901)
			(xy 62.505902 -2.607719) (xy 62.506352 -2.597912) (xy 62.506352 -2.590038) (xy 62.506852 -2.540721)
			(xy 62.514857 -2.442413) (xy 62.530814 -2.345078) (xy 62.554617 -2.24936) (xy 62.58611 -2.155889)
			(xy 62.625084 -2.065282) (xy 62.671283 -1.978137) (xy 62.724402 -1.895029) (xy 62.784091 -1.816506)
			(xy 62.849955 -1.743086) (xy 62.92156 -1.675253) (xy 62.998434 -1.613455) (xy 63.08007 -1.5581) (xy 63.165929 -1.509552)
			(xy 63.255444 -1.468132) (xy 63.348026 -1.434114) (xy 63.443063 -1.407721) (xy 63.539928 -1.389129)
			(xy 63.637983 -1.378458) (xy 63.73658 -1.375781) (xy 63.83507 -1.381114) (xy 63.932801 -1.394422)
			(xy 64.029131 -1.415618) (xy 64.123422 -1.444561) (xy 64.215054 -1.481062) (xy 64.303421 -1.524878)
			(xy 64.38794 -1.575721) (xy 64.468055 -1.633256) (xy 64.543236 -1.697102) (xy 64.612988 -1.76684)
			(xy 64.67685 -1.842008) (xy 64.734401 -1.922111) (xy 64.785262 -2.00662) (xy 64.829096 -2.094978)
			(xy 64.865616 -2.186602) (xy 64.894579 -2.280887) (xy 64.915794 -2.377212) (xy 64.929123 -2.474941)
			(xy 64.934476 -2.57343) (xy 64.934028 -2.590038) (xy 65.045593 -2.590038) (xy 65.049633 -2.491055)
			(xy 65.061728 -2.392732) (xy 65.081798 -2.295721) (xy 65.109708 -2.200669) (xy 65.145272 -2.108208)
			(xy 65.188255 -2.018953) (xy 65.23837 -1.933499) (xy 65.295283 -1.852414) (xy 65.358616 -1.776238)
			(xy 65.427947 -1.705478) (xy 65.502816 -1.640604) (xy 65.582723 -1.582049) (xy 65.667137 -1.530201)
			(xy 65.755496 -1.485407) (xy 65.847212 -1.447964) (xy 65.941675 -1.418121) (xy 66.038256 -1.396077)
			(xy 66.136313 -1.381978) (xy 66.235193 -1.375919) (xy 66.334237 -1.37794) (xy 66.432787 -1.388027)
			(xy 66.530187 -1.406113) (xy 66.625789 -1.432078) (xy 66.718956 -1.46575) (xy 66.809069 -1.506903)
			(xy 66.895527 -1.555264) (xy 66.977756 -1.610511) (xy 67.055208 -1.672277) (xy 67.127368 -1.740151)
			(xy 67.193756 -1.81368) (xy 67.253929 -1.892376) (xy 67.307487 -1.975715) (xy 67.354075 -2.063142)
			(xy 67.393381 -2.154075) (xy 67.425145 -2.24791) (xy 67.449154 -2.344021) (xy 67.46525 -2.44177)
			(xy 67.473325 -2.540506) (xy 67.47383 -2.590038) (xy 67.473325 -2.63957) (xy 67.472584 -2.648633)
			(xy 74.704694 -2.648633) (xy 74.704694 -2.531443) (xy 74.712691 -2.414525) (xy 74.728649 -2.298426)
			(xy 74.752492 -2.183686) (xy 74.78411 -2.070841) (xy 74.823355 -1.960417) (xy 74.870043 -1.852928)
			(xy 74.923959 -1.748876) (xy 74.984849 -1.648746) (xy 75.052431 -1.553005) (xy 75.126389 -1.462099)
			(xy 75.206377 -1.376451) (xy 75.292025 -1.296463) (xy 75.382931 -1.222505) (xy 75.478672 -1.154923)
			(xy 75.578802 -1.094033) (xy 75.682854 -1.040117) (xy 75.790343 -0.993429) (xy 75.900767 -0.954184)
			(xy 76.013612 -0.922566) (xy 76.128352 -0.898723) (xy 76.244451 -0.882765) (xy 76.361369 -0.874768)
			(xy 76.478559 -0.874768) (xy 76.595477 -0.882765) (xy 76.711576 -0.898723) (xy 76.826316 -0.922566)
			(xy 76.939161 -0.954184) (xy 77.049585 -0.993429) (xy 77.157074 -1.040117) (xy 77.261126 -1.094033)
			(xy 77.361256 -1.154923) (xy 77.456997 -1.222505) (xy 77.547903 -1.296463) (xy 77.633551 -1.376451)
			(xy 77.713539 -1.462099) (xy 77.787497 -1.553005) (xy 77.855079 -1.648746) (xy 77.915969 -1.748876)
			(xy 77.969885 -1.852928) (xy 78.016573 -1.960417) (xy 78.055818 -2.070841) (xy 78.087436 -2.183686)
			(xy 78.111279 -2.298426) (xy 78.127237 -2.414525) (xy 78.135234 -2.531443) (xy 78.135734 -2.590038)
			(xy 78.135234 -2.648633) (xy 78.127237 -2.765551) (xy 78.111279 -2.88165) (xy 78.087436 -2.99639)
			(xy 78.055818 -3.109235) (xy 78.016573 -3.219659) (xy 77.969885 -3.327148) (xy 77.915969 -3.4312)
			(xy 77.855079 -3.53133) (xy 77.787497 -3.627071) (xy 77.713539 -3.717977) (xy 77.633551 -3.803625)
			(xy 77.547903 -3.883613) (xy 77.456997 -3.957571) (xy 77.361256 -4.025153) (xy 77.261126 -4.086043)
			(xy 77.157074 -4.139959) (xy 77.049585 -4.186647) (xy 76.939161 -4.225892) (xy 76.826316 -4.25751)
			(xy 76.711576 -4.281353) (xy 76.595477 -4.297311) (xy 76.478559 -4.305308) (xy 76.361369 -4.305308)
			(xy 76.244451 -4.297311) (xy 76.128352 -4.281353) (xy 76.013612 -4.25751) (xy 75.900767 -4.225892)
			(xy 75.790343 -4.186647) (xy 75.682854 -4.139959) (xy 75.578802 -4.086043) (xy 75.478672 -4.025153)
			(xy 75.382931 -3.957571) (xy 75.292025 -3.883613) (xy 75.206377 -3.803625) (xy 75.126389 -3.717977)
			(xy 75.052431 -3.627071) (xy 74.984849 -3.53133) (xy 74.923959 -3.4312) (xy 74.870043 -3.327148)
			(xy 74.823355 -3.219659) (xy 74.78411 -3.109235) (xy 74.752492 -2.99639) (xy 74.728649 -2.88165)
			(xy 74.712691 -2.765551) (xy 74.704694 -2.648633) (xy 67.472584 -2.648633) (xy 67.46525 -2.738306)
			(xy 67.449154 -2.836055) (xy 67.425145 -2.932166) (xy 67.393381 -3.026001) (xy 67.354075 -3.116934)
			(xy 67.307487 -3.204361) (xy 67.253929 -3.2877) (xy 67.193756 -3.366396) (xy 67.127368 -3.439925)
			(xy 67.055208 -3.507799) (xy 66.977756 -3.569565) (xy 66.895527 -3.624812) (xy 66.809069 -3.673173)
			(xy 66.718956 -3.714326) (xy 66.625789 -3.747998) (xy 66.530187 -3.773963) (xy 66.432787 -3.792049)
			(xy 66.334237 -3.802136) (xy 66.235193 -3.804157) (xy 66.136313 -3.798098) (xy 66.038256 -3.783999)
			(xy 65.941675 -3.761955) (xy 65.847212 -3.732112) (xy 65.755496 -3.694669) (xy 65.667137 -3.649875)
			(xy 65.582723 -3.598027) (xy 65.502816 -3.539472) (xy 65.427947 -3.474598) (xy 65.358616 -3.403838)
			(xy 65.295283 -3.327662) (xy 65.23837 -3.246577) (xy 65.188255 -3.161123) (xy 65.145272 -3.071868)
			(xy 65.109708 -2.979407) (xy 65.081798 -2.884355) (xy 65.061728 -2.787344) (xy 65.049633 -2.689021)
			(xy 65.045593 -2.590038) (xy 64.934028 -2.590038) (xy 64.931819 -2.672028) (xy 64.921169 -2.770085)
			(xy 64.902596 -2.866954) (xy 64.876223 -2.961996) (xy 64.842223 -3.054585) (xy 64.800822 -3.144109)
			(xy 64.752292 -3.229978) (xy 64.696954 -3.311625) (xy 64.635172 -3.388512) (xy 64.567354 -3.460131)
			(xy 64.493947 -3.52601) (xy 64.415436 -3.585715) (xy 64.332339 -3.638851) (xy 64.245203 -3.685068)
			(xy 64.154604 -3.724061) (xy 64.06114 -3.755573) (xy 63.965427 -3.779396) (xy 63.868095 -3.795372)
			(xy 63.769789 -3.803397) (xy 63.720472 -3.803904) (xy 63.719964 -3.803904) (xy 63.667939 -3.803349)
			(xy 63.564271 -3.794428) (xy 63.461748 -3.776665) (xy 63.361123 -3.750189) (xy 63.263133 -3.715195)
			(xy 63.1685 -3.67194) (xy 63.077917 -3.620741) (xy 63.034672 -3.591814) (xy 63.022226 -3.583178)
			(xy 62.992 -3.58267) (xy 62.887352 -3.647948) (xy 62.874652 -3.67538) (xy 62.876938 -3.690366) (xy 62.88499 -3.748362)
			(xy 62.894112 -3.865108) (xy 62.895249 -3.982203) (xy 62.888395 -4.099104) (xy 62.873582 -4.215265)
			(xy 62.85088 -4.330144) (xy 62.820393 -4.443207) (xy 62.782264 -4.553927) (xy 62.736672 -4.661788)
			(xy 62.683827 -4.766287) (xy 62.623976 -4.866938) (xy 62.557399 -4.963272) (xy 62.484405 -5.054839)
			(xy 62.405335 -5.141214) (xy 62.320556 -5.221993) (xy 62.230464 -5.296801) (xy 62.178873 -5.334)
			(xy 81.787492 -5.334) (xy 81.787492 -5.333492) (xy 81.788098 -5.28716) (xy 81.797769 -5.195002) (xy 81.816965 -5.104348)
			(xy 81.845477 -5.016179) (xy 81.863692 -4.973574) (xy 81.867498 -4.963632) (xy 81.867498 -4.942368)
			(xy 81.863692 -4.932426) (xy 81.845447 -4.889764) (xy 81.816903 -4.801471) (xy 81.79771 -4.710686)
			(xy 81.788077 -4.618396) (xy 81.787492 -4.572) (xy 81.788075 -4.525604) (xy 81.79772 -4.433316) (xy 81.816916 -4.342532)
			(xy 81.845454 -4.254239) (xy 81.863692 -4.211574) (xy 81.867498 -4.201632) (xy 81.867498 -4.180368)
			(xy 81.863692 -4.170426) (xy 81.84547 -4.127823) (xy 81.816952 -4.039656) (xy 81.79776 -3.949) (xy 81.7881 -3.85684)
			(xy 81.787492 -3.810508) (xy 81.787492 -3.81) (xy 81.787967 -3.768898) (xy 81.795552 -3.687043) (xy 81.810657 -3.606238)
			(xy 81.833153 -3.527171) (xy 81.862849 -3.450517) (xy 81.899491 -3.37693) (xy 81.942766 -3.307038)
			(xy 81.992306 -3.241437) (xy 82.047687 -3.180687) (xy 82.108437 -3.125306) (xy 82.174038 -3.075766)
			(xy 82.24393 -3.032491) (xy 82.317517 -2.995849) (xy 82.394171 -2.966153) (xy 82.473238 -2.943657)
			(xy 82.554043 -2.928552) (xy 82.635898 -2.920967) (xy 82.677 -2.920492) (xy 82.677508 -2.920492)
			(xy 82.72384 -2.921098) (xy 82.815998 -2.930769) (xy 82.906652 -2.949965) (xy 82.994821 -2.978477)
			(xy 83.037426 -2.996692) (xy 83.047368 -3.000498) (xy 83.068632 -3.000498) (xy 83.078574 -2.996692)
			(xy 83.121236 -2.978447) (xy 83.209529 -2.949903) (xy 83.300314 -2.93071) (xy 83.392604 -2.921077)
			(xy 83.439 -2.920492) (xy 83.485396 -2.921075) (xy 83.577684 -2.93072) (xy 83.668468 -2.949916) (xy 83.756761 -2.978454)
			(xy 83.799426 -2.996692) (xy 83.809368 -3.000498) (xy 83.830632 -3.000498) (xy 83.840574 -2.996692)
			(xy 83.883236 -2.978447) (xy 83.971529 -2.949903) (xy 84.062314 -2.93071) (xy 84.154604 -2.921077)
			(xy 84.201 -2.920492) (xy 84.247396 -2.921075) (xy 84.339684 -2.93072) (xy 84.430468 -2.949916) (xy 84.518761 -2.978454)
			(xy 84.561426 -2.996692) (xy 84.571368 -3.000498) (xy 84.592632 -3.000498) (xy 84.602574 -2.996692)
			(xy 84.645236 -2.978447) (xy 84.733529 -2.949903) (xy 84.824314 -2.93071) (xy 84.916604 -2.921077)
			(xy 84.963 -2.920492) (xy 85.009396 -2.921075) (xy 85.101684 -2.93072) (xy 85.192468 -2.949916) (xy 85.280761 -2.978454)
			(xy 85.323426 -2.996692) (xy 85.333368 -3.000498) (xy 85.354632 -3.000498) (xy 85.364574 -2.996692)
			(xy 85.407236 -2.978447) (xy 85.495529 -2.949903) (xy 85.586314 -2.93071) (xy 85.678604 -2.921077)
			(xy 85.725 -2.920492) (xy 85.771396 -2.921075) (xy 85.863684 -2.93072) (xy 85.954468 -2.949916) (xy 86.042761 -2.978454)
			(xy 86.085426 -2.996692) (xy 86.095368 -3.000498) (xy 86.116632 -3.000498) (xy 86.126574 -2.996692)
			(xy 86.169177 -2.97847) (xy 86.257344 -2.949952) (xy 86.348 -2.93076) (xy 86.44016 -2.9211) (xy 86.486492 -2.920492)
			(xy 86.487 -2.920492) (xy 86.528102 -2.920967) (xy 86.609957 -2.928552) (xy 86.690762 -2.943657)
			(xy 86.769829 -2.966153) (xy 86.846483 -2.995849) (xy 86.92007 -3.032491) (xy 86.989962 -3.075766)
			(xy 87.055563 -3.125306) (xy 87.116313 -3.180687) (xy 87.171694 -3.241437) (xy 87.221234 -3.307038)
			(xy 87.264509 -3.37693) (xy 87.301151 -3.450517) (xy 87.330847 -3.527171) (xy 87.353343 -3.606238)
			(xy 87.368448 -3.687043) (xy 87.376033 -3.768898) (xy 87.376508 -3.81) (xy 87.376508 -3.810508) (xy 87.375902 -3.85684)
			(xy 87.366231 -3.948998) (xy 87.347035 -4.039652) (xy 87.318523 -4.127821) (xy 87.300308 -4.170426)
			(xy 87.296502 -4.180368) (xy 87.296502 -4.201632) (xy 87.300308 -4.211574) (xy 87.318553 -4.254236)
			(xy 87.347097 -4.342529) (xy 87.36629 -4.433314) (xy 87.375923 -4.525604) (xy 87.376508 -4.572) (xy 87.375925 -4.618396)
			(xy 87.36628 -4.710684) (xy 87.347084 -4.801468) (xy 87.318546 -4.889761) (xy 87.300308 -4.932426)
			(xy 87.296502 -4.942368) (xy 87.296502 -4.963632) (xy 87.300308 -4.973574) (xy 87.31853 -5.016177)
			(xy 87.347048 -5.104344) (xy 87.36624 -5.195) (xy 87.3759 -5.28716) (xy 87.376508 -5.333492) (xy 87.376508 -5.334)
			(xy 87.376285 -5.353304) (xy 354.006912 -5.353304) (xy 354.006912 -5.352796) (xy 354.007518 -5.306464)
			(xy 354.017189 -5.214306) (xy 354.036385 -5.123652) (xy 354.064897 -5.035483) (xy 354.083112 -4.992878)
			(xy 354.086914 -4.982935) (xy 354.086915 -4.961672) (xy 354.083112 -4.95173) (xy 354.06487 -4.909067)
			(xy 354.036325 -4.820775) (xy 354.017131 -4.72999) (xy 354.007497 -4.6377) (xy 354.006912 -4.591304)
			(xy 354.007495 -4.544908) (xy 354.017139 -4.45262) (xy 354.036335 -4.361836) (xy 354.064874 -4.273543)
			(xy 354.083112 -4.230878) (xy 354.086914 -4.220935) (xy 354.086915 -4.199672) (xy 354.083112 -4.18973)
			(xy 354.064892 -4.147126) (xy 354.036374 -4.058959) (xy 354.01718 -3.968304) (xy 354.00752 -3.876144)
			(xy 354.006912 -3.829812) (xy 354.006912 -3.829304) (xy 354.007356 -3.7882) (xy 354.014941 -3.706344)
			(xy 354.030046 -3.625536) (xy 354.052543 -3.546467) (xy 354.08224 -3.469811) (xy 354.118884 -3.396222)
			(xy 354.162161 -3.326328) (xy 354.211702 -3.260725) (xy 354.267085 -3.199974) (xy 354.327838 -3.144592)
			(xy 354.393441 -3.095051) (xy 354.463336 -3.051776) (xy 354.536925 -3.015134) (xy 354.613582 -2.985438)
			(xy 354.692652 -2.962943) (xy 354.773459 -2.947839) (xy 354.855316 -2.940255) (xy 354.89642 -2.939796)
			(xy 354.896928 -2.939796) (xy 354.94326 -2.940395) (xy 355.035418 -2.950068) (xy 355.126072 -2.969266)
			(xy 355.214241 -2.99778) (xy 355.256846 -3.015996) (xy 355.266788 -3.019802) (xy 355.288052 -3.019802)
			(xy 355.297994 -3.015996) (xy 355.340654 -2.997745) (xy 355.428947 -2.969202) (xy 355.519733 -2.950011)
			(xy 355.612024 -2.94038) (xy 355.65842 -2.939796) (xy 355.704815 -2.940407) (xy 355.797102 -2.950044)
			(xy 355.887886 -2.969231) (xy 355.97618 -2.997762) (xy 356.018846 -3.015996) (xy 356.028788 -3.019802)
			(xy 356.050052 -3.019802) (xy 356.059994 -3.015996) (xy 356.102654 -2.997745) (xy 356.190947 -2.969202)
			(xy 356.281733 -2.950011) (xy 356.374024 -2.94038) (xy 356.42042 -2.939796) (xy 356.466815 -2.940407)
			(xy 356.559102 -2.950044) (xy 356.649886 -2.969231) (xy 356.73818 -2.997762) (xy 356.780846 -3.015996)
			(xy 356.790788 -3.019802) (xy 356.812052 -3.019802) (xy 356.821994 -3.015996) (xy 356.864654 -2.997745)
			(xy 356.952947 -2.969202) (xy 357.043733 -2.950011) (xy 357.136024 -2.94038) (xy 357.18242 -2.939796)
			(xy 357.228815 -2.940407) (xy 357.321102 -2.950044) (xy 357.411886 -2.969231) (xy 357.50018 -2.997762)
			(xy 357.542846 -3.015996) (xy 357.552788 -3.019802) (xy 357.574052 -3.019802) (xy 357.583994 -3.015996)
			(xy 357.626654 -2.997745) (xy 357.714947 -2.969202) (xy 357.805733 -2.950011) (xy 357.898024 -2.94038)
			(xy 357.94442 -2.939796) (xy 357.990815 -2.940407) (xy 358.083102 -2.950044) (xy 358.173886 -2.969231)
			(xy 358.26218 -2.997762) (xy 358.304846 -3.015996) (xy 358.314788 -3.019802) (xy 358.336052 -3.019802)
			(xy 358.345994 -3.015996) (xy 358.388594 -2.997768) (xy 358.476763 -2.969252) (xy 358.567419 -2.950061)
			(xy 358.65958 -2.940403) (xy 358.705912 -2.939796) (xy 358.70642 -2.939796) (xy 358.747523 -2.940248)
			(xy 358.829378 -2.947834) (xy 358.910184 -2.962941) (xy 358.989251 -2.985439) (xy 359.065905 -3.015137)
			(xy 359.139492 -3.051781) (xy 359.209385 -3.095058) (xy 359.274986 -3.144599) (xy 359.335736 -3.199981)
			(xy 359.391117 -3.260733) (xy 359.440656 -3.326335) (xy 359.483931 -3.396229) (xy 359.520573 -3.469817)
			(xy 359.550268 -3.546472) (xy 359.572764 -3.62554) (xy 359.587869 -3.706346) (xy 359.595454 -3.788201)
			(xy 359.595928 -3.829304) (xy 359.595928 -3.829812) (xy 359.595322 -3.876144) (xy 359.592786 -3.900309)
			(xy 361.865136 -3.900309) (xy 361.87186 -3.783404) (xy 361.886543 -3.667229) (xy 361.909117 -3.552327)
			(xy 361.939477 -3.439232) (xy 361.977481 -3.328472) (xy 362.022952 -3.220563) (xy 362.075679 -3.116006)
			(xy 362.135416 -3.015291) (xy 362.201884 -2.918885) (xy 362.274775 -2.827238) (xy 362.353747 -2.740777)
			(xy 362.438434 -2.659905) (xy 362.52844 -2.584998) (xy 362.623346 -2.516406) (xy 362.722711 -2.454448)
			(xy 362.826071 -2.399413) (xy 362.932945 -2.351557) (xy 363.042834 -2.311104) (xy 363.155227 -2.278241)
			(xy 363.269599 -2.253122) (xy 363.38542 -2.235864) (xy 363.502147 -2.226547) (xy 363.619238 -2.225214)
			(xy 363.736148 -2.231873) (xy 363.85233 -2.246491) (xy 363.967245 -2.269002) (xy 364.080357 -2.299299)
			(xy 364.191138 -2.337241) (xy 364.299073 -2.382653) (xy 364.403658 -2.435322) (xy 364.504407 -2.495003)
			(xy 364.60085 -2.561418) (xy 364.692537 -2.634257) (xy 364.736126 -2.67335) (xy 364.74371 -2.679623)
			(xy 364.762161 -2.686419) (xy 364.781815 -2.685801) (xy 364.79099 -2.68224) (xy 364.87608 -2.644394)
			(xy 364.88487 -2.640018) (xy 364.898503 -2.62591) (xy 364.905858 -2.607721) (xy 364.906306 -2.597912)
			(xy 364.906306 -2.597658) (xy 364.906052 -2.5908) (xy 364.906052 -2.589276) (xy 364.90662 -2.539112)
			(xy 364.914961 -2.439131) (xy 364.931528 -2.340179) (xy 364.956206 -2.242933) (xy 364.988828 -2.148056)
			(xy 365.02917 -2.056196) (xy 365.076958 -1.967979) (xy 365.131864 -1.884009) (xy 365.193515 -1.804857)
			(xy 365.261489 -1.731065) (xy 365.335323 -1.663135) (xy 365.414513 -1.601533) (xy 365.498517 -1.546678)
			(xy 365.586763 -1.498944) (xy 365.678648 -1.458658) (xy 365.773545 -1.426094) (xy 365.870806 -1.401475)
			(xy 365.969767 -1.384969) (xy 366.069754 -1.376689) (xy 366.119918 -1.376172) (xy 366.168816 -1.376589)
			(xy 366.266296 -1.38446) (xy 366.362826 -1.400149) (xy 366.457781 -1.423554) (xy 366.550544 -1.454524)
			(xy 366.640514 -1.492858) (xy 366.727109 -1.538308) (xy 366.809765 -1.590578) (xy 366.887947 -1.649329)
			(xy 366.961149 -1.714181) (xy 367.028894 -1.784712) (xy 367.090745 -1.860467) (xy 367.146299 -1.940952)
			(xy 367.195197 -2.025647) (xy 367.237122 -2.114001) (xy 367.271801 -2.205443) (xy 367.299009 -2.299379)
			(xy 367.318571 -2.395199) (xy 367.330359 -2.492283) (xy 367.334297 -2.59) (xy 367.334295 -2.590038)
			(xy 367.445547 -2.590038) (xy 367.449587 -2.491055) (xy 367.461682 -2.392732) (xy 367.481752 -2.295721)
			(xy 367.509662 -2.200669) (xy 367.545226 -2.108208) (xy 367.588209 -2.018953) (xy 367.638324 -1.933499)
			(xy 367.695237 -1.852414) (xy 367.75857 -1.776238) (xy 367.827901 -1.705478) (xy 367.90277 -1.640604)
			(xy 367.982677 -1.582049) (xy 368.067091 -1.530201) (xy 368.15545 -1.485407) (xy 368.247166 -1.447964)
			(xy 368.341629 -1.418121) (xy 368.43821 -1.396077) (xy 368.536267 -1.381978) (xy 368.635147 -1.375919)
			(xy 368.734191 -1.37794) (xy 368.832741 -1.388027) (xy 368.930141 -1.406113) (xy 369.025743 -1.432078)
			(xy 369.11891 -1.46575) (xy 369.209023 -1.506903) (xy 369.295481 -1.555264) (xy 369.37771 -1.610511)
			(xy 369.455162 -1.672277) (xy 369.527322 -1.740151) (xy 369.59371 -1.81368) (xy 369.653883 -1.892376)
			(xy 369.707441 -1.975715) (xy 369.754029 -2.063142) (xy 369.793335 -2.154075) (xy 369.825099 -2.24791)
			(xy 369.849108 -2.344021) (xy 369.865204 -2.44177) (xy 369.873279 -2.540506) (xy 369.873784 -2.590038)
			(xy 369.873279 -2.63957) (xy 369.872538 -2.648633) (xy 377.104648 -2.648633) (xy 377.104648 -2.531443)
			(xy 377.112645 -2.414525) (xy 377.128603 -2.298426) (xy 377.152446 -2.183686) (xy 377.184064 -2.070841)
			(xy 377.223309 -1.960417) (xy 377.269997 -1.852928) (xy 377.323913 -1.748876) (xy 377.384803 -1.648746)
			(xy 377.452385 -1.553005) (xy 377.526343 -1.462099) (xy 377.606331 -1.376451) (xy 377.691979 -1.296463)
			(xy 377.782885 -1.222505) (xy 377.878626 -1.154923) (xy 377.978756 -1.094033) (xy 378.082808 -1.040117)
			(xy 378.190297 -0.993429) (xy 378.300721 -0.954184) (xy 378.413566 -0.922566) (xy 378.528306 -0.898723)
			(xy 378.644405 -0.882765) (xy 378.761323 -0.874768) (xy 378.878513 -0.874768) (xy 378.995431 -0.882765)
			(xy 379.11153 -0.898723) (xy 379.22627 -0.922566) (xy 379.339115 -0.954184) (xy 379.449539 -0.993429)
			(xy 379.557028 -1.040117) (xy 379.66108 -1.094033) (xy 379.76121 -1.154923) (xy 379.856951 -1.222505)
			(xy 379.947857 -1.296463) (xy 380.033505 -1.376451) (xy 380.113493 -1.462099) (xy 380.187451 -1.553005)
			(xy 380.255033 -1.648746) (xy 380.315923 -1.748876) (xy 380.369839 -1.852928) (xy 380.416527 -1.960417)
			(xy 380.455772 -2.070841) (xy 380.48739 -2.183686) (xy 380.511233 -2.298426) (xy 380.527191 -2.414525)
			(xy 380.535188 -2.531443) (xy 380.535688 -2.590038) (xy 380.535188 -2.648633) (xy 380.527191 -2.765551)
			(xy 380.511233 -2.88165) (xy 380.48739 -2.99639) (xy 380.455772 -3.109235) (xy 380.416527 -3.219659)
			(xy 380.369839 -3.327148) (xy 380.315923 -3.4312) (xy 380.255033 -3.53133) (xy 380.187451 -3.627071)
			(xy 380.113493 -3.717977) (xy 380.033505 -3.803625) (xy 379.947857 -3.883613) (xy 379.856951 -3.957571)
			(xy 379.76121 -4.025153) (xy 379.66108 -4.086043) (xy 379.557028 -4.139959) (xy 379.449539 -4.186647)
			(xy 379.339115 -4.225892) (xy 379.22627 -4.25751) (xy 379.11153 -4.281353) (xy 378.995431 -4.297311)
			(xy 378.878513 -4.305308) (xy 378.761323 -4.305308) (xy 378.644405 -4.297311) (xy 378.528306 -4.281353)
			(xy 378.413566 -4.25751) (xy 378.300721 -4.225892) (xy 378.190297 -4.186647) (xy 378.082808 -4.139959)
			(xy 377.978756 -4.086043) (xy 377.878626 -4.025153) (xy 377.782885 -3.957571) (xy 377.691979 -3.883613)
			(xy 377.606331 -3.803625) (xy 377.526343 -3.717977) (xy 377.452385 -3.627071) (xy 377.384803 -3.53133)
			(xy 377.323913 -3.4312) (xy 377.269997 -3.327148) (xy 377.223309 -3.219659) (xy 377.184064 -3.109235)
			(xy 377.152446 -2.99639) (xy 377.128603 -2.88165) (xy 377.112645 -2.765551) (xy 377.104648 -2.648633)
			(xy 369.872538 -2.648633) (xy 369.865204 -2.738306) (xy 369.849108 -2.836055) (xy 369.825099 -2.932166)
			(xy 369.793335 -3.026001) (xy 369.754029 -3.116934) (xy 369.707441 -3.204361) (xy 369.653883 -3.2877)
			(xy 369.59371 -3.366396) (xy 369.527322 -3.439925) (xy 369.455162 -3.507799) (xy 369.37771 -3.569565)
			(xy 369.295481 -3.624812) (xy 369.209023 -3.673173) (xy 369.11891 -3.714326) (xy 369.025743 -3.747998)
			(xy 368.930141 -3.773963) (xy 368.832741 -3.792049) (xy 368.734191 -3.802136) (xy 368.635147 -3.804157)
			(xy 368.536267 -3.798098) (xy 368.43821 -3.783999) (xy 368.341629 -3.761955) (xy 368.247166 -3.732112)
			(xy 368.15545 -3.694669) (xy 368.067091 -3.649875) (xy 367.982677 -3.598027) (xy 367.90277 -3.539472)
			(xy 367.827901 -3.474598) (xy 367.75857 -3.403838) (xy 367.695237 -3.327662) (xy 367.638324 -3.246577)
			(xy 367.588209 -3.161123) (xy 367.545226 -3.071868) (xy 367.509662 -2.979407) (xy 367.481752 -2.884355)
			(xy 367.461682 -2.787344) (xy 367.449587 -2.689021) (xy 367.445547 -2.590038) (xy 367.334295 -2.590038)
			(xy 367.330359 -2.687717) (xy 367.318571 -2.784801) (xy 367.299009 -2.880621) (xy 367.271801 -2.974557)
			(xy 367.237122 -3.065999) (xy 367.195197 -3.154353) (xy 367.146299 -3.239048) (xy 367.090745 -3.319533)
			(xy 367.028894 -3.395288) (xy 366.961149 -3.465819) (xy 366.887947 -3.530671) (xy 366.809765 -3.589422)
			(xy 366.727109 -3.641692) (xy 366.640514 -3.687142) (xy 366.550544 -3.725476) (xy 366.457781 -3.756446)
			(xy 366.362826 -3.779851) (xy 366.266296 -3.79554) (xy 366.168816 -3.803411) (xy 366.119918 -3.803904)
			(xy 366.067892 -3.803373) (xy 365.964224 -3.794448) (xy 365.861701 -3.776681) (xy 365.761075 -3.750202)
			(xy 365.663086 -3.715204) (xy 365.568453 -3.671945) (xy 365.477871 -3.620743) (xy 365.434626 -3.591814)
			(xy 365.42218 -3.583178) (xy 365.391954 -3.58267) (xy 365.287306 -3.647948) (xy 365.274606 -3.67538)
			(xy 365.276892 -3.690366) (xy 365.284958 -3.748359) (xy 365.294081 -3.865102) (xy 365.295218 -3.982195)
			(xy 365.288365 -4.099093) (xy 365.273553 -4.215251) (xy 365.250851 -4.330129) (xy 365.220366 -4.44319)
			(xy 365.182239 -4.553907) (xy 365.136647 -4.661766) (xy 365.083804 -4.766264) (xy 365.023956 -4.866913)
			(xy 364.95738 -4.963245) (xy 364.884389 -5.054811) (xy 364.80532 -5.141184) (xy 364.720544 -5.221962)
			(xy 364.630454 -5.296769) (xy 364.535472 -5.365256) (xy 364.436038 -5.427103) (xy 364.332617 -5.482023)
			(xy 364.225691 -5.52976) (xy 364.115757 -5.570092) (xy 364.003327 -5.60283) (xy 363.888927 -5.627822)
			(xy 363.773088 -5.644952) (xy 363.65635 -5.654139) (xy 363.539257 -5.655341) (xy 363.422355 -5.648553)
			(xy 363.306189 -5.633805) (xy 363.191299 -5.611168) (xy 363.078221 -5.580745) (xy 362.967482 -5.542679)
			(xy 362.859598 -5.497148) (xy 362.755071 -5.444363) (xy 362.654389 -5.38457) (xy 362.55802 -5.318048)
			(xy 362.466413 -5.245107) (xy 362.379996 -5.166087) (xy 362.299171 -5.081355) (xy 362.224314 -4.991308)
			(xy 362.155775 -4.896363) (xy 362.093872 -4.796964) (xy 362.038895 -4.693573) (xy 361.991098 -4.586673)
			(xy 361.950706 -4.476762) (xy 361.917905 -4.36435) (xy 361.89285 -4.249964) (xy 361.875656 -4.134134)
			(xy 361.866404 -4.017401) (xy 361.865136 -3.900309) (xy 359.592786 -3.900309) (xy 359.58565 -3.968302)
			(xy 359.566455 -4.058956) (xy 359.537943 -4.147125) (xy 359.519728 -4.18973) (xy 359.515919 -4.199671)
			(xy 359.515921 -4.220936) (xy 359.519728 -4.230878) (xy 359.537975 -4.273539) (xy 359.566518 -4.361832)
			(xy 359.585711 -4.452617) (xy 359.595343 -4.544908) (xy 359.595928 -4.591304) (xy 359.595345 -4.6377)
			(xy 359.5857 -4.729988) (xy 359.566504 -4.820772) (xy 359.537966 -4.909065) (xy 359.519728 -4.95173)
			(xy 359.515919 -4.961671) (xy 359.515921 -4.982936) (xy 359.519728 -4.992878) (xy 359.537953 -5.03548)
			(xy 359.566469 -5.123648) (xy 359.585661 -5.214303) (xy 359.59532 -5.306464) (xy 359.595928 -5.352796)
			(xy 359.595928 -5.353304) (xy 359.595437 -5.394406) (xy 359.587852 -5.476259) (xy 359.572747 -5.557063)
			(xy 359.550251 -5.636129) (xy 359.520556 -5.712782) (xy 359.483914 -5.786368) (xy 359.44064 -5.85626)
			(xy 359.391101 -5.92186) (xy 359.335722 -5.98261) (xy 359.274973 -6.037991) (xy 359.209373 -6.087531)
			(xy 359.139482 -6.130807) (xy 359.065897 -6.167449) (xy 358.989245 -6.197146) (xy 358.910179 -6.219643)
			(xy 358.829375 -6.23475) (xy 358.747522 -6.242336) (xy 358.70642 -6.242812) (xy 358.705912 -6.242812)
			(xy 358.65958 -6.242199) (xy 358.567423 -6.232529) (xy 358.476769 -6.213336) (xy 358.3886 -6.184826)
			(xy 358.345994 -6.166612) (xy 358.336052 -6.162806) (xy 358.314788 -6.162806) (xy 358.304846 -6.166612)
			(xy 358.262181 -6.18485) (xy 358.17389 -6.213396) (xy 358.083106 -6.232591) (xy 357.990816 -6.242226)
			(xy 357.94442 -6.242812) (xy 357.898025 -6.242222) (xy 357.805736 -6.232579) (xy 357.714953 -6.213385)
			(xy 357.626659 -6.184849) (xy 357.583994 -6.166612) (xy 357.574052 -6.162806) (xy 357.552788 -6.162806)
			(xy 357.542846 -6.166612) (xy 357.500181 -6.18485) (xy 357.41189 -6.213396) (xy 357.321106 -6.232591)
			(xy 357.228816 -6.242226) (xy 357.18242 -6.242812) (xy 357.136025 -6.242222) (xy 357.043736 -6.232579)
			(xy 356.952953 -6.213385) (xy 356.864659 -6.184849) (xy 356.821994 -6.166612) (xy 356.812052 -6.162806)
			(xy 356.790788 -6.162806) (xy 356.780846 -6.166612) (xy 356.738181 -6.18485) (xy 356.64989 -6.213396)
			(xy 356.559106 -6.232591) (xy 356.466816 -6.242226) (xy 356.42042 -6.242812) (xy 356.374025 -6.242222)
			(xy 356.281736 -6.232579) (xy 356.190953 -6.213385) (xy 356.102659 -6.184849) (xy 356.059994 -6.166612)
			(xy 356.050052 -6.162806) (xy 356.028788 -6.162806) (xy 356.018846 -6.166612) (xy 355.976181 -6.18485)
			(xy 355.88789 -6.213396) (xy 355.797106 -6.232591) (xy 355.704816 -6.242226) (xy 355.65842 -6.242812)
			(xy 355.612025 -6.242222) (xy 355.519736 -6.232579) (xy 355.428953 -6.213385) (xy 355.340659 -6.184849)
			(xy 355.297994 -6.166612) (xy 355.288052 -6.162806) (xy 355.266788 -6.162806) (xy 355.256846 -6.166612)
			(xy 355.214241 -6.184828) (xy 355.126074 -6.213347) (xy 355.035419 -6.232541) (xy 354.94326 -6.242203)
			(xy 354.896928 -6.242812) (xy 354.89642 -6.242812) (xy 354.855317 -6.242329) (xy 354.773462 -6.234746)
			(xy 354.692656 -6.219642) (xy 354.613589 -6.197147) (xy 354.536934 -6.167452) (xy 354.463346 -6.130811)
			(xy 354.393453 -6.087537) (xy 354.327851 -6.037998) (xy 354.267099 -5.982618) (xy 354.211717 -5.921868)
			(xy 354.162177 -5.856267) (xy 354.1189 -5.786375) (xy 354.082257 -5.712788) (xy 354.052561 -5.636134)
			(xy 354.030063 -5.557067) (xy 354.014958 -5.476261) (xy 354.007372 -5.394407) (xy 354.006912 -5.353304)
			(xy 87.376285 -5.353304) (xy 87.376033 -5.375102) (xy 87.368448 -5.456957) (xy 87.353343 -5.537762)
			(xy 87.330847 -5.616829) (xy 87.301151 -5.693483) (xy 87.264509 -5.76707) (xy 87.221234 -5.836962)
			(xy 87.171694 -5.902563) (xy 87.116313 -5.963313) (xy 87.055563 -6.018694) (xy 86.989962 -6.068234)
			(xy 86.92007 -6.111509) (xy 86.846483 -6.148151) (xy 86.769829 -6.177847) (xy 86.690762 -6.200343)
			(xy 86.609957 -6.215448) (xy 86.528102 -6.223033) (xy 86.487 -6.223508) (xy 86.486492 -6.223508)
			(xy 86.44016 -6.222902) (xy 86.348002 -6.213231) (xy 86.257348 -6.194035) (xy 86.169179 -6.165523)
			(xy 86.126574 -6.147308) (xy 86.116632 -6.143502) (xy 86.095368 -6.143502) (xy 86.085426 -6.147308)
			(xy 86.042764 -6.165553) (xy 85.954471 -6.194097) (xy 85.863686 -6.21329) (xy 85.771396 -6.222923)
			(xy 85.725 -6.223508) (xy 85.678604 -6.222925) (xy 85.586316 -6.21328) (xy 85.495532 -6.194084) (xy 85.407239 -6.165546)
			(xy 85.364574 -6.147308) (xy 85.354632 -6.143502) (xy 85.333368 -6.143502) (xy 85.323426 -6.147308)
			(xy 85.280764 -6.165553) (xy 85.192471 -6.194097) (xy 85.101686 -6.21329) (xy 85.009396 -6.222923)
			(xy 84.963 -6.223508) (xy 84.916604 -6.222925) (xy 84.824316 -6.21328) (xy 84.733532 -6.194084) (xy 84.645239 -6.165546)
			(xy 84.602574 -6.147308) (xy 84.592632 -6.143502) (xy 84.571368 -6.143502) (xy 84.561426 -6.147308)
			(xy 84.518764 -6.165553) (xy 84.430471 -6.194097) (xy 84.339686 -6.21329) (xy 84.247396 -6.222923)
			(xy 84.201 -6.223508) (xy 84.154604 -6.222925) (xy 84.062316 -6.21328) (xy 83.971532 -6.194084) (xy 83.883239 -6.165546)
			(xy 83.840574 -6.147308) (xy 83.830632 -6.143502) (xy 83.809368 -6.143502) (xy 83.799426 -6.147308)
			(xy 83.756764 -6.165553) (xy 83.668471 -6.194097) (xy 83.577686 -6.21329) (xy 83.485396 -6.222923)
			(xy 83.439 -6.223508) (xy 83.392604 -6.222925) (xy 83.300316 -6.21328) (xy 83.209532 -6.194084) (xy 83.121239 -6.165546)
			(xy 83.078574 -6.147308) (xy 83.068632 -6.143502) (xy 83.047368 -6.143502) (xy 83.037426 -6.147308)
			(xy 82.994823 -6.16553) (xy 82.906656 -6.194048) (xy 82.816 -6.21324) (xy 82.72384 -6.2229) (xy 82.677508 -6.223508)
			(xy 82.677 -6.223508) (xy 82.635898 -6.223033) (xy 82.554043 -6.215448) (xy 82.473238 -6.200343)
			(xy 82.394171 -6.177847) (xy 82.317517 -6.148151) (xy 82.24393 -6.111509) (xy 82.174038 -6.068234)
			(xy 82.108437 -6.018694) (xy 82.047687 -5.963313) (xy 81.992306 -5.902563) (xy 81.942766 -5.836962)
			(xy 81.899491 -5.76707) (xy 81.862849 -5.693483) (xy 81.833153 -5.616829) (xy 81.810657 -5.537762)
			(xy 81.795552 -5.456957) (xy 81.787967 -5.375102) (xy 81.787492 -5.334) (xy 62.178873 -5.334) (xy 62.135479 -5.365288)
			(xy 62.036043 -5.427136) (xy 61.932619 -5.482057) (xy 61.82569 -5.529794) (xy 61.715754 -5.570126)
			(xy 61.603322 -5.602863) (xy 61.488918 -5.627855) (xy 61.373077 -5.644984) (xy 61.256336 -5.654171)
			(xy 61.139241 -5.655372) (xy 61.022337 -5.648582) (xy 60.906168 -5.633833) (xy 60.791276 -5.611194)
			(xy 60.678196 -5.58077) (xy 60.567455 -5.542702) (xy 60.459569 -5.497169) (xy 60.355041 -5.444382)
			(xy 60.254357 -5.384586) (xy 60.157987 -5.318062) (xy 60.066379 -5.245119) (xy 59.979961 -5.166096)
			(xy 59.899135 -5.081362) (xy 59.824278 -4.991311) (xy 59.755738 -4.896364) (xy 59.693835 -4.796962)
			(xy 59.638858 -4.693568) (xy 59.591062 -4.586666) (xy 59.55067 -4.476751) (xy 59.51787 -4.364337)
			(xy 59.492815 -4.249948) (xy 59.475623 -4.134116) (xy 59.466372 -4.01738) (xy 59.465106 -3.900286)
			(xy 0.646137 -3.900286) (xy 0.630394 -3.960748) (xy 0.590225 -4.147135) (xy 0.558002 -4.335059) (xy 0.533784 -4.524182)
			(xy 0.517614 -4.714162) (xy 0.509522 -4.904657) (xy 0.509016 -4.99999) (xy 0.509016 -17.272) (xy 111.565944 -17.272)
			(xy 111.565944 -17.271492) (xy 111.566546 -17.22516) (xy 111.576218 -17.133002) (xy 111.595414 -17.042348)
			(xy 111.623928 -16.954179) (xy 111.642144 -16.911574) (xy 111.645952 -16.901632) (xy 111.645952 -16.880368)
			(xy 111.642144 -16.870426) (xy 111.623902 -16.827762) (xy 111.595357 -16.739471) (xy 111.576163 -16.648686)
			(xy 111.566529 -16.556396) (xy 111.565944 -16.51) (xy 111.566522 -16.463604) (xy 111.576168 -16.371316)
			(xy 111.595365 -16.280532) (xy 111.623905 -16.192239) (xy 111.642144 -16.149574) (xy 111.645952 -16.139632)
			(xy 111.645952 -16.118368) (xy 111.642144 -16.108426) (xy 111.623902 -16.065762) (xy 111.595357 -15.977471)
			(xy 111.576163 -15.886686) (xy 111.566529 -15.794396) (xy 111.565944 -15.748) (xy 111.566522 -15.701604)
			(xy 111.576168 -15.609316) (xy 111.595365 -15.518532) (xy 111.623905 -15.430239) (xy 111.642144 -15.387574)
			(xy 111.645952 -15.377632) (xy 111.645952 -15.356368) (xy 111.642144 -15.346426) (xy 111.623902 -15.303762)
			(xy 111.595357 -15.215471) (xy 111.576163 -15.124686) (xy 111.566529 -15.032396) (xy 111.565944 -14.986)
			(xy 111.566522 -14.939604) (xy 111.576168 -14.847316) (xy 111.595365 -14.756532) (xy 111.623905 -14.668239)
			(xy 111.642144 -14.625574) (xy 111.645952 -14.615632) (xy 111.645952 -14.594368) (xy 111.642144 -14.584426)
			(xy 111.623919 -14.541824) (xy 111.595403 -14.453656) (xy 111.576211 -14.363) (xy 111.566552 -14.27084)
			(xy 111.565944 -14.224508) (xy 111.565944 -14.224) (xy 111.566467 -14.182899) (xy 111.574051 -14.101047)
			(xy 111.589155 -14.020245) (xy 111.61165 -13.94118) (xy 111.641344 -13.864529) (xy 111.677983 -13.790944)
			(xy 111.721256 -13.721053) (xy 111.770792 -13.655454) (xy 111.82617 -13.594704) (xy 111.886917 -13.539323)
			(xy 111.952514 -13.489783) (xy 112.022402 -13.446507) (xy 112.095985 -13.409863) (xy 112.172635 -13.380165)
			(xy 112.251698 -13.357666) (xy 112.3325 -13.342558) (xy 112.414351 -13.334969) (xy 112.455452 -13.334492)
			(xy 112.45596 -13.334492) (xy 112.502291 -13.335115) (xy 112.594449 -13.344781) (xy 112.685103 -13.363972)
			(xy 112.773272 -13.392479) (xy 112.815878 -13.410692) (xy 112.82582 -13.414498) (xy 112.847084 -13.414498)
			(xy 112.857026 -13.410692) (xy 112.899695 -13.392463) (xy 112.987985 -13.363915) (xy 113.078768 -13.344717)
			(xy 113.171056 -13.335079) (xy 113.217452 -13.334492) (xy 113.263847 -13.335092) (xy 113.356135 -13.344732)
			(xy 113.446919 -13.363923) (xy 113.535213 -13.392456) (xy 113.577878 -13.410692) (xy 113.58782 -13.414498)
			(xy 113.609084 -13.414498) (xy 113.619026 -13.410692) (xy 113.661695 -13.392463) (xy 113.749985 -13.363915)
			(xy 113.840768 -13.344717) (xy 113.933056 -13.335079) (xy 113.979452 -13.334492) (xy 114.025847 -13.335092)
			(xy 114.118135 -13.344732) (xy 114.208919 -13.363923) (xy 114.297213 -13.392456) (xy 114.339878 -13.410692)
			(xy 114.34982 -13.414498) (xy 114.371084 -13.414498) (xy 114.381026 -13.410692) (xy 114.423695 -13.392463)
			(xy 114.511985 -13.363915) (xy 114.602768 -13.344717) (xy 114.695056 -13.335079) (xy 114.741452 -13.334492)
			(xy 114.787847 -13.335092) (xy 114.880135 -13.344732) (xy 114.970919 -13.363923) (xy 115.059213 -13.392456)
			(xy 115.101878 -13.410692) (xy 115.11182 -13.414498) (xy 115.133084 -13.414498) (xy 115.143026 -13.410692)
			(xy 115.185635 -13.392486) (xy 115.2738 -13.363964) (xy 115.364454 -13.344767) (xy 115.456612 -13.335103)
			(xy 115.502944 -13.334492) (xy 115.503452 -13.334492) (xy 115.544554 -13.334998) (xy 115.626409 -13.342579)
			(xy 115.707215 -13.35768) (xy 115.786282 -13.380173) (xy 115.862937 -13.409865) (xy 115.936525 -13.446504)
			(xy 116.006418 -13.489777) (xy 116.072021 -13.539314) (xy 116.132772 -13.594694) (xy 116.188155 -13.655442)
			(xy 116.237696 -13.721042) (xy 116.280972 -13.790933) (xy 116.317615 -13.864519) (xy 116.347312 -13.941172)
			(xy 116.369809 -14.020239) (xy 116.384915 -14.101044) (xy 116.3925 -14.182898) (xy 116.39296 -14.224)
			(xy 116.39296 -14.224508) (xy 116.392358 -14.27084) (xy 116.382686 -14.362998) (xy 116.363489 -14.453652)
			(xy 116.334976 -14.541821) (xy 116.31676 -14.584426) (xy 116.312952 -14.594368) (xy 116.312952 -14.615632)
			(xy 116.31676 -14.625574) (xy 116.335002 -14.668237) (xy 116.363547 -14.756529) (xy 116.382741 -14.847314)
			(xy 116.392375 -14.939604) (xy 116.39296 -14.986) (xy 116.392381 -15.032396) (xy 116.382736 -15.124684)
			(xy 116.363539 -15.215468) (xy 116.334999 -15.303761) (xy 116.31676 -15.346426) (xy 116.312952 -15.356368)
			(xy 116.312952 -15.377632) (xy 116.31676 -15.387574) (xy 116.335002 -15.430237) (xy 116.363547 -15.518529)
			(xy 116.382741 -15.609314) (xy 116.392375 -15.701604) (xy 116.39296 -15.748) (xy 116.392381 -15.794396)
			(xy 116.382736 -15.886684) (xy 116.363539 -15.977468) (xy 116.334999 -16.065761) (xy 116.31676 -16.108426)
			(xy 116.312952 -16.118368) (xy 116.312952 -16.139632) (xy 116.31676 -16.149574) (xy 116.335002 -16.192237)
			(xy 116.363547 -16.280529) (xy 116.382741 -16.371314) (xy 116.392375 -16.463604) (xy 116.39296 -16.51)
			(xy 116.392381 -16.556396) (xy 116.382736 -16.648684) (xy 116.363539 -16.739468) (xy 116.334999 -16.827761)
			(xy 116.31676 -16.870426) (xy 116.312952 -16.880368) (xy 116.312952 -16.901632) (xy 116.31676 -16.911574)
			(xy 116.334985 -16.954176) (xy 116.363501 -17.042344) (xy 116.382693 -17.132999) (xy 116.392352 -17.22516)
			(xy 116.39296 -17.271492) (xy 116.39296 -17.272) (xy 116.392548 -17.313105) (xy 116.384962 -17.394963)
			(xy 116.369856 -17.475772) (xy 116.347357 -17.554843) (xy 116.317659 -17.6315) (xy 116.281014 -17.70509)
			(xy 116.237735 -17.774985) (xy 116.188192 -17.840588) (xy 116.132806 -17.90134) (xy 116.072051 -17.956722)
			(xy 116.006446 -18.006262) (xy 115.936548 -18.049538) (xy 115.862956 -18.086179) (xy 115.786297 -18.115873)
			(xy 115.707226 -18.138367) (xy 115.626415 -18.153469) (xy 115.544557 -18.16105) (xy 115.503452 -18.161508)
			(xy 115.502944 -18.161508) (xy 115.456613 -18.160884) (xy 115.364455 -18.151218) (xy 115.273801 -18.132027)
			(xy 115.185632 -18.103521) (xy 115.143026 -18.085308) (xy 115.133084 -18.081502) (xy 115.11182 -18.081502)
			(xy 115.101878 -18.085308) (xy 115.059209 -18.103536) (xy 114.970919 -18.132084) (xy 114.880136 -18.151282)
			(xy 114.787847 -18.16092) (xy 114.741452 -18.161508) (xy 114.695057 -18.160907) (xy 114.602769 -18.151267)
			(xy 114.511985 -18.132076) (xy 114.423691 -18.103543) (xy 114.381026 -18.085308) (xy 114.371084 -18.081502)
			(xy 114.34982 -18.081502) (xy 114.339878 -18.085308) (xy 114.297209 -18.103536) (xy 114.208919 -18.132084)
			(xy 114.118136 -18.151282) (xy 114.025847 -18.16092) (xy 113.979452 -18.161508) (xy 113.933057 -18.160907)
			(xy 113.840769 -18.151267) (xy 113.749985 -18.132076) (xy 113.661691 -18.103543) (xy 113.619026 -18.085308)
			(xy 113.609084 -18.081502) (xy 113.58782 -18.081502) (xy 113.577878 -18.085308) (xy 113.535209 -18.103536)
			(xy 113.446919 -18.132084) (xy 113.356136 -18.151282) (xy 113.263847 -18.16092) (xy 113.217452 -18.161508)
			(xy 113.171057 -18.160907) (xy 113.078769 -18.151267) (xy 112.987985 -18.132076) (xy 112.899691 -18.103543)
			(xy 112.857026 -18.085308) (xy 112.847084 -18.081502) (xy 112.82582 -18.081502) (xy 112.815878 -18.085308)
			(xy 112.773268 -18.103513) (xy 112.685103 -18.132035) (xy 112.59445 -18.151233) (xy 112.502292 -18.160897)
			(xy 112.45596 -18.161508) (xy 112.455452 -18.161508) (xy 112.414349 -18.161079) (xy 112.332493 -18.15349)
			(xy 112.251687 -18.138381) (xy 112.17262 -18.11588) (xy 112.095965 -18.086181) (xy 112.022379 -18.049535)
			(xy 111.952487 -18.006257) (xy 111.886886 -17.956714) (xy 111.826136 -17.90133) (xy 111.770755 -17.840577)
			(xy 111.721216 -17.774974) (xy 111.677941 -17.705079) (xy 111.6413 -17.631491) (xy 111.611604 -17.554835)
			(xy 111.589108 -17.475766) (xy 111.574003 -17.394959) (xy 111.566419 -17.313103) (xy 111.565944 -17.272)
			(xy 0.509016 -17.272) (xy 0.509016 -20.63857) (xy 56.730635 -20.63857) (xy 56.730635 -20.50943) (xy 56.738585 -20.380535)
			(xy 56.754455 -20.252375) (xy 56.778184 -20.125434) (xy 56.809683 -20.000195) (xy 56.848832 -19.877132)
			(xy 56.895483 -19.756713) (xy 56.949458 -19.639394) (xy 57.010553 -19.52562) (xy 57.078536 -19.415823)
			(xy 57.15315 -19.31042) (xy 57.234111 -19.20981) (xy 57.321111 -19.114375) (xy 57.413822 -19.024476)
			(xy 57.511892 -18.940455) (xy 57.614947 -18.862631) (xy 57.722598 -18.791299) (xy 57.834437 -18.726729)
			(xy 57.950038 -18.669167) (xy 58.068963 -18.61883) (xy 58.190762 -18.57591) (xy 58.314972 -18.540569)
			(xy 58.441121 -18.512942) (xy 58.568733 -18.493133) (xy 58.697322 -18.481217) (xy 58.8264 -18.477241)
			(xy 58.955478 -18.481217) (xy 59.084067 -18.493133) (xy 59.211679 -18.512942) (xy 59.337828 -18.540569)
			(xy 59.462038 -18.57591) (xy 59.583837 -18.61883) (xy 59.702762 -18.669167) (xy 59.818363 -18.726729)
			(xy 59.930202 -18.791299) (xy 60.037853 -18.862631) (xy 60.140908 -18.940455) (xy 60.238978 -19.024476)
			(xy 60.331689 -19.114375) (xy 60.418689 -19.20981) (xy 60.49965 -19.31042) (xy 60.574264 -19.415823)
			(xy 60.642247 -19.52562) (xy 60.703342 -19.639394) (xy 60.757317 -19.756713) (xy 60.803968 -19.877132)
			(xy 60.843117 -20.000195) (xy 60.874616 -20.125434) (xy 60.898345 -20.252375) (xy 60.914215 -20.380535)
			(xy 60.922165 -20.50943) (xy 60.922662 -20.574) (xy 60.922165 -20.63857) (xy 60.914215 -20.767465)
			(xy 60.898345 -20.895625) (xy 60.874616 -21.022566) (xy 60.843117 -21.147805) (xy 60.803968 -21.270868)
			(xy 60.757317 -21.391287) (xy 60.703342 -21.508606) (xy 60.642247 -21.62238) (xy 60.574264 -21.732177)
			(xy 60.49965 -21.83758) (xy 60.418689 -21.93819) (xy 60.331689 -22.033625) (xy 60.238978 -22.123524)
			(xy 60.140908 -22.207545) (xy 60.037853 -22.285369) (xy 59.988365 -22.318161) (xy 111.362994 -22.318161)
			(xy 111.362994 -22.233439) (xy 111.371047 -22.149102) (xy 111.387081 -22.065912) (xy 111.410949 -21.984622)
			(xy 111.442437 -21.90597) (xy 111.481259 -21.830667) (xy 111.527062 -21.759395) (xy 111.579433 -21.692799)
			(xy 111.637898 -21.631484) (xy 111.701926 -21.576003) (xy 111.770938 -21.52686) (xy 111.844308 -21.4845)
			(xy 111.921373 -21.449305) (xy 112.001435 -21.421596) (xy 112.083768 -21.401622) (xy 112.167627 -21.389565)
			(xy 112.252252 -21.385534) (xy 112.336877 -21.389565) (xy 112.420736 -21.401622) (xy 112.503069 -21.421596)
			(xy 112.583131 -21.449305) (xy 112.660196 -21.4845) (xy 112.733566 -21.52686) (xy 112.802578 -21.576003)
			(xy 112.866606 -21.631484) (xy 112.925071 -21.692799) (xy 112.977442 -21.759395) (xy 113.023245 -21.830667)
			(xy 113.062067 -21.90597) (xy 113.093555 -21.984622) (xy 113.117423 -22.065912) (xy 113.133457 -22.149102)
			(xy 113.14151 -22.233439) (xy 113.142014 -22.2758) (xy 113.14151 -22.318161) (xy 113.133457 -22.402498)
			(xy 113.117423 -22.485688) (xy 113.093555 -22.566978) (xy 113.062067 -22.64563) (xy 113.023245 -22.720933)
			(xy 112.977442 -22.792205) (xy 112.925071 -22.858801) (xy 112.866606 -22.920116) (xy 112.802578 -22.975597)
			(xy 112.733566 -23.02474) (xy 112.660196 -23.0671) (xy 112.583131 -23.102295) (xy 112.503069 -23.130004)
			(xy 112.420736 -23.149978) (xy 112.336877 -23.162035) (xy 112.252252 -23.166067) (xy 112.167627 -23.162035)
			(xy 112.083768 -23.149978) (xy 112.001435 -23.130004) (xy 111.921373 -23.102295) (xy 111.844308 -23.0671)
			(xy 111.770938 -23.02474) (xy 111.701926 -22.975597) (xy 111.637898 -22.920116) (xy 111.579433 -22.858801)
			(xy 111.527062 -22.792205) (xy 111.481259 -22.720933) (xy 111.442437 -22.64563) (xy 111.410949 -22.566978)
			(xy 111.387081 -22.485688) (xy 111.371047 -22.402498) (xy 111.362994 -22.318161) (xy 59.988365 -22.318161)
			(xy 59.930202 -22.356701) (xy 59.818363 -22.421271) (xy 59.702762 -22.478833) (xy 59.583837 -22.52917)
			(xy 59.462038 -22.57209) (xy 59.337828 -22.607431) (xy 59.211679 -22.635058) (xy 59.084067 -22.654867)
			(xy 58.955478 -22.666783) (xy 58.8264 -22.67076) (xy 58.697322 -22.666783) (xy 58.568733 -22.654867)
			(xy 58.441121 -22.635058) (xy 58.314972 -22.607431) (xy 58.190762 -22.57209) (xy 58.068963 -22.52917)
			(xy 57.950038 -22.478833) (xy 57.834437 -22.421271) (xy 57.722598 -22.356701) (xy 57.614947 -22.285369)
			(xy 57.511892 -22.207545) (xy 57.413822 -22.123524) (xy 57.321111 -22.033625) (xy 57.234111 -21.93819)
			(xy 57.15315 -21.83758) (xy 57.078536 -21.732177) (xy 57.010553 -21.62238) (xy 56.949458 -21.508606)
			(xy 56.895483 -21.391287) (xy 56.848832 -21.270868) (xy 56.809683 -21.147805) (xy 56.778184 -21.022566)
			(xy 56.754455 -20.895625) (xy 56.738585 -20.767465) (xy 56.730635 -20.63857) (xy 0.509016 -20.63857)
			(xy 0.509016 -28.5496) (xy 111.565944 -28.5496) (xy 111.565944 -28.549092) (xy 111.566546 -28.50276)
			(xy 111.576218 -28.410602) (xy 111.595414 -28.319948) (xy 111.623928 -28.231779) (xy 111.642144 -28.189174)
			(xy 111.645952 -28.179232) (xy 111.645952 -28.157968) (xy 111.642144 -28.148026) (xy 111.623902 -28.105362)
			(xy 111.595357 -28.017071) (xy 111.576163 -27.926286) (xy 111.566529 -27.833996) (xy 111.565944 -27.7876)
			(xy 111.566522 -27.741204) (xy 111.576168 -27.648916) (xy 111.595365 -27.558132) (xy 111.623905 -27.469839)
			(xy 111.642144 -27.427174) (xy 111.645952 -27.417232) (xy 111.645952 -27.395968) (xy 111.642144 -27.386026)
			(xy 111.623902 -27.343362) (xy 111.595357 -27.255071) (xy 111.576163 -27.164286) (xy 111.566529 -27.071996)
			(xy 111.565944 -27.0256) (xy 111.566522 -26.979204) (xy 111.576168 -26.886916) (xy 111.595365 -26.796132)
			(xy 111.623905 -26.707839) (xy 111.642144 -26.665174) (xy 111.645952 -26.655232) (xy 111.645952 -26.633968)
			(xy 111.642144 -26.624026) (xy 111.623902 -26.581362) (xy 111.595357 -26.493071) (xy 111.576163 -26.402286)
			(xy 111.566529 -26.309996) (xy 111.565944 -26.2636) (xy 111.566522 -26.217204) (xy 111.576168 -26.124916)
			(xy 111.595365 -26.034132) (xy 111.623905 -25.945839) (xy 111.642144 -25.903174) (xy 111.645952 -25.893232)
			(xy 111.645952 -25.871968) (xy 111.642144 -25.862026) (xy 111.623919 -25.819424) (xy 111.595403 -25.731256)
			(xy 111.576211 -25.6406) (xy 111.566552 -25.54844) (xy 111.565944 -25.502108) (xy 111.565944 -25.5016)
			(xy 111.566467 -25.460499) (xy 111.574051 -25.378647) (xy 111.589155 -25.297845) (xy 111.61165 -25.21878)
			(xy 111.641344 -25.142129) (xy 111.677983 -25.068544) (xy 111.721256 -24.998653) (xy 111.770792 -24.933054)
			(xy 111.82617 -24.872304) (xy 111.886917 -24.816923) (xy 111.952514 -24.767383) (xy 112.022402 -24.724107)
			(xy 112.095985 -24.687463) (xy 112.172635 -24.657765) (xy 112.251698 -24.635266) (xy 112.3325 -24.620158)
			(xy 112.414351 -24.612569) (xy 112.455452 -24.612092) (xy 112.45596 -24.612092) (xy 112.502291 -24.612715)
			(xy 112.594449 -24.622381) (xy 112.685103 -24.641572) (xy 112.773272 -24.670079) (xy 112.815878 -24.688292)
			(xy 112.82582 -24.692098) (xy 112.847084 -24.692098) (xy 112.857026 -24.688292) (xy 112.899695 -24.670063)
			(xy 112.987985 -24.641515) (xy 113.078768 -24.622317) (xy 113.171056 -24.612679) (xy 113.217452 -24.612092)
			(xy 113.263847 -24.612692) (xy 113.356135 -24.622332) (xy 113.446919 -24.641523) (xy 113.535213 -24.670056)
			(xy 113.577878 -24.688292) (xy 113.58782 -24.692098) (xy 113.609084 -24.692098) (xy 113.619026 -24.688292)
			(xy 113.661695 -24.670063) (xy 113.749985 -24.641515) (xy 113.840768 -24.622317) (xy 113.933056 -24.612679)
			(xy 113.979452 -24.612092) (xy 114.025847 -24.612692) (xy 114.118135 -24.622332) (xy 114.208919 -24.641523)
			(xy 114.297213 -24.670056) (xy 114.339878 -24.688292) (xy 114.34982 -24.692098) (xy 114.371084 -24.692098)
			(xy 114.381026 -24.688292) (xy 114.423695 -24.670063) (xy 114.511985 -24.641515) (xy 114.602768 -24.622317)
			(xy 114.695056 -24.612679) (xy 114.741452 -24.612092) (xy 114.787847 -24.612692) (xy 114.880135 -24.622332)
			(xy 114.970919 -24.641523) (xy 115.059213 -24.670056) (xy 115.101878 -24.688292) (xy 115.11182 -24.692098)
			(xy 115.133084 -24.692098) (xy 115.143026 -24.688292) (xy 115.185635 -24.670086) (xy 115.2738 -24.641564)
			(xy 115.364454 -24.622367) (xy 115.456612 -24.612703) (xy 115.502944 -24.612092) (xy 115.503452 -24.612092)
			(xy 115.544554 -24.612598) (xy 115.626409 -24.620179) (xy 115.707215 -24.63528) (xy 115.786282 -24.657773)
			(xy 115.862937 -24.687465) (xy 115.936525 -24.724104) (xy 116.006418 -24.767377) (xy 116.072021 -24.816914)
			(xy 116.132772 -24.872294) (xy 116.188155 -24.933042) (xy 116.237696 -24.998642) (xy 116.280972 -25.068533)
			(xy 116.317615 -25.142119) (xy 116.347312 -25.218772) (xy 116.369809 -25.297839) (xy 116.384915 -25.378644)
			(xy 116.3925 -25.460498) (xy 116.39296 -25.5016) (xy 116.39296 -25.502108) (xy 116.392358 -25.54844)
			(xy 116.382686 -25.640598) (xy 116.363489 -25.731252) (xy 116.334976 -25.819421) (xy 116.31676 -25.862026)
			(xy 116.312952 -25.871968) (xy 116.312952 -25.893232) (xy 116.31676 -25.903174) (xy 116.335002 -25.945837)
			(xy 116.363547 -26.034129) (xy 116.382741 -26.124914) (xy 116.392375 -26.217204) (xy 116.39296 -26.2636)
			(xy 116.392381 -26.309996) (xy 116.382736 -26.402284) (xy 116.363539 -26.493068) (xy 116.334999 -26.581361)
			(xy 116.31676 -26.624026) (xy 116.312952 -26.633968) (xy 116.312952 -26.655232) (xy 116.31676 -26.665174)
			(xy 116.335002 -26.707837) (xy 116.363547 -26.796129) (xy 116.382741 -26.886914) (xy 116.392375 -26.979204)
			(xy 116.39296 -27.0256) (xy 116.392381 -27.071996) (xy 116.382736 -27.164284) (xy 116.363539 -27.255068)
			(xy 116.334999 -27.343361) (xy 116.31676 -27.386026) (xy 116.312952 -27.395968) (xy 116.312952 -27.417232)
			(xy 116.31676 -27.427174) (xy 116.335002 -27.469837) (xy 116.363547 -27.558129) (xy 116.382741 -27.648914)
			(xy 116.392375 -27.741204) (xy 116.39296 -27.7876) (xy 116.392381 -27.833996) (xy 116.382736 -27.926284)
			(xy 116.363539 -28.017068) (xy 116.334999 -28.105361) (xy 116.31676 -28.148026) (xy 116.312952 -28.157968)
			(xy 116.312952 -28.179232) (xy 116.31676 -28.189174) (xy 116.334985 -28.231776) (xy 116.363501 -28.319944)
			(xy 116.382693 -28.410599) (xy 116.392352 -28.50276) (xy 116.39296 -28.549092) (xy 116.39296 -28.5496)
			(xy 116.392548 -28.590705) (xy 116.384962 -28.672563) (xy 116.369856 -28.753372) (xy 116.347357 -28.832443)
			(xy 116.317659 -28.9091) (xy 116.281014 -28.98269) (xy 116.237735 -29.052585) (xy 116.188192 -29.118188)
			(xy 116.132806 -29.17894) (xy 116.072051 -29.234322) (xy 116.006446 -29.283862) (xy 115.936548 -29.327138)
			(xy 115.862956 -29.363779) (xy 115.786297 -29.393473) (xy 115.707226 -29.415967) (xy 115.626415 -29.431069)
			(xy 115.544557 -29.43865) (xy 115.503452 -29.439108) (xy 115.502944 -29.439108) (xy 115.456613 -29.438484)
			(xy 115.364455 -29.428818) (xy 115.273801 -29.409627) (xy 115.185632 -29.381121) (xy 115.143026 -29.362908)
			(xy 115.133084 -29.359102) (xy 115.11182 -29.359102) (xy 115.101878 -29.362908) (xy 115.059209 -29.381136)
			(xy 114.970919 -29.409684) (xy 114.880136 -29.428882) (xy 114.787847 -29.43852) (xy 114.741452 -29.439108)
			(xy 114.695057 -29.438507) (xy 114.602769 -29.428867) (xy 114.511985 -29.409676) (xy 114.423691 -29.381143)
			(xy 114.381026 -29.362908) (xy 114.371084 -29.359102) (xy 114.34982 -29.359102) (xy 114.339878 -29.362908)
			(xy 114.297209 -29.381136) (xy 114.208919 -29.409684) (xy 114.118136 -29.428882) (xy 114.025847 -29.43852)
			(xy 113.979452 -29.439108) (xy 113.933057 -29.438507) (xy 113.840769 -29.428867) (xy 113.749985 -29.409676)
			(xy 113.661691 -29.381143) (xy 113.619026 -29.362908) (xy 113.609084 -29.359102) (xy 113.58782 -29.359102)
			(xy 113.577878 -29.362908) (xy 113.535209 -29.381136) (xy 113.446919 -29.409684) (xy 113.356136 -29.428882)
			(xy 113.263847 -29.43852) (xy 113.217452 -29.439108) (xy 113.171057 -29.438507) (xy 113.078769 -29.428867)
			(xy 112.987985 -29.409676) (xy 112.899691 -29.381143) (xy 112.857026 -29.362908) (xy 112.847084 -29.359102)
			(xy 112.82582 -29.359102) (xy 112.815878 -29.362908) (xy 112.773268 -29.381113) (xy 112.685103 -29.409635)
			(xy 112.59445 -29.428833) (xy 112.502292 -29.438497) (xy 112.45596 -29.439108) (xy 112.455452 -29.439108)
			(xy 112.414349 -29.438679) (xy 112.332493 -29.43109) (xy 112.251687 -29.415981) (xy 112.17262 -29.39348)
			(xy 112.095965 -29.363781) (xy 112.022379 -29.327135) (xy 111.952487 -29.283857) (xy 111.886886 -29.234314)
			(xy 111.826136 -29.17893) (xy 111.770755 -29.118177) (xy 111.721216 -29.052574) (xy 111.677941 -28.982679)
			(xy 111.6413 -28.909091) (xy 111.611604 -28.832435) (xy 111.589108 -28.753366) (xy 111.574003 -28.672559)
			(xy 111.566419 -28.590703) (xy 111.565944 -28.5496) (xy 0.509016 -28.5496) (xy 0.509016 -33.595761)
			(xy 111.362994 -33.595761) (xy 111.362994 -33.511039) (xy 111.371047 -33.426702) (xy 111.387081 -33.343512)
			(xy 111.410949 -33.262222) (xy 111.442437 -33.18357) (xy 111.481259 -33.108267) (xy 111.527062 -33.036995)
			(xy 111.579433 -32.970399) (xy 111.637898 -32.909084) (xy 111.701926 -32.853603) (xy 111.770938 -32.80446)
			(xy 111.844308 -32.7621) (xy 111.921373 -32.726905) (xy 112.001435 -32.699196) (xy 112.083768 -32.679222)
			(xy 112.167627 -32.667165) (xy 112.252252 -32.663134) (xy 112.336877 -32.667165) (xy 112.420736 -32.679222)
			(xy 112.503069 -32.699196) (xy 112.583131 -32.726905) (xy 112.660196 -32.7621) (xy 112.733566 -32.80446)
			(xy 112.802578 -32.853603) (xy 112.866606 -32.909084) (xy 112.925071 -32.970399) (xy 112.977442 -33.036995)
			(xy 113.023245 -33.108267) (xy 113.062067 -33.18357) (xy 113.093555 -33.262222) (xy 113.117423 -33.343512)
			(xy 113.133457 -33.426702) (xy 113.14151 -33.511039) (xy 113.142014 -33.5534) (xy 113.14151 -33.595761)
			(xy 113.133457 -33.680098) (xy 113.117423 -33.763288) (xy 113.093555 -33.844578) (xy 113.062067 -33.92323)
			(xy 113.023245 -33.998533) (xy 112.977442 -34.069805) (xy 112.925071 -34.136401) (xy 112.866606 -34.197716)
			(xy 112.802578 -34.253197) (xy 112.733566 -34.30234) (xy 112.660196 -34.3447) (xy 112.583131 -34.379895)
			(xy 112.503069 -34.407604) (xy 112.420736 -34.427578) (xy 112.336877 -34.439635) (xy 112.252252 -34.443667)
			(xy 112.167627 -34.439635) (xy 112.083768 -34.427578) (xy 112.001435 -34.407604) (xy 111.921373 -34.379895)
			(xy 111.844308 -34.3447) (xy 111.770938 -34.30234) (xy 111.701926 -34.253197) (xy 111.637898 -34.197716)
			(xy 111.579433 -34.136401) (xy 111.527062 -34.069805) (xy 111.481259 -33.998533) (xy 111.442437 -33.92323)
			(xy 111.410949 -33.844578) (xy 111.387081 -33.763288) (xy 111.371047 -33.680098) (xy 111.362994 -33.595761)
			(xy 0.509016 -33.595761) (xy 0.509016 -39.8272) (xy 111.565944 -39.8272) (xy 111.565944 -39.826692)
			(xy 111.566546 -39.78036) (xy 111.576218 -39.688202) (xy 111.595414 -39.597548) (xy 111.623928 -39.509379)
			(xy 111.642144 -39.466774) (xy 111.645952 -39.456832) (xy 111.645952 -39.435568) (xy 111.642144 -39.425626)
			(xy 111.623902 -39.382962) (xy 111.595357 -39.294671) (xy 111.576163 -39.203886) (xy 111.566529 -39.111596)
			(xy 111.565944 -39.0652) (xy 111.566522 -39.018804) (xy 111.576168 -38.926516) (xy 111.595365 -38.835732)
			(xy 111.623905 -38.747439) (xy 111.642144 -38.704774) (xy 111.645952 -38.694832) (xy 111.645952 -38.673568)
			(xy 111.642144 -38.663626) (xy 111.623902 -38.620962) (xy 111.595357 -38.532671) (xy 111.576163 -38.441886)
			(xy 111.566529 -38.349596) (xy 111.565944 -38.3032) (xy 111.566522 -38.256804) (xy 111.576168 -38.164516)
			(xy 111.595365 -38.073732) (xy 111.623905 -37.985439) (xy 111.642144 -37.942774) (xy 111.645952 -37.932832)
			(xy 111.645952 -37.911568) (xy 111.642144 -37.901626) (xy 111.623902 -37.858962) (xy 111.595357 -37.770671)
			(xy 111.576163 -37.679886) (xy 111.566529 -37.587596) (xy 111.565944 -37.5412) (xy 111.566522 -37.494804)
			(xy 111.576168 -37.402516) (xy 111.595365 -37.311732) (xy 111.623905 -37.223439) (xy 111.642144 -37.180774)
			(xy 111.645952 -37.170832) (xy 111.645952 -37.149568) (xy 111.642144 -37.139626) (xy 111.623919 -37.097024)
			(xy 111.595403 -37.008856) (xy 111.576211 -36.9182) (xy 111.566552 -36.82604) (xy 111.565944 -36.779708)
			(xy 111.565944 -36.7792) (xy 111.566467 -36.738099) (xy 111.574051 -36.656247) (xy 111.589155 -36.575445)
			(xy 111.61165 -36.49638) (xy 111.641344 -36.419729) (xy 111.677983 -36.346144) (xy 111.721256 -36.276253)
			(xy 111.770792 -36.210654) (xy 111.82617 -36.149904) (xy 111.886917 -36.094523) (xy 111.952514 -36.044983)
			(xy 112.022402 -36.001707) (xy 112.095985 -35.965063) (xy 112.172635 -35.935365) (xy 112.251698 -35.912866)
			(xy 112.3325 -35.897758) (xy 112.414351 -35.890169) (xy 112.455452 -35.889692) (xy 112.45596 -35.889692)
			(xy 112.502291 -35.890315) (xy 112.594449 -35.899981) (xy 112.685103 -35.919172) (xy 112.773272 -35.947679)
			(xy 112.815878 -35.965892) (xy 112.82582 -35.969698) (xy 112.847084 -35.969698) (xy 112.857026 -35.965892)
			(xy 112.899695 -35.947663) (xy 112.987985 -35.919115) (xy 113.078768 -35.899917) (xy 113.171056 -35.890279)
			(xy 113.217452 -35.889692) (xy 113.263847 -35.890292) (xy 113.356135 -35.899932) (xy 113.446919 -35.919123)
			(xy 113.535213 -35.947656) (xy 113.577878 -35.965892) (xy 113.58782 -35.969698) (xy 113.609084 -35.969698)
			(xy 113.619026 -35.965892) (xy 113.661695 -35.947663) (xy 113.749985 -35.919115) (xy 113.840768 -35.899917)
			(xy 113.933056 -35.890279) (xy 113.979452 -35.889692) (xy 114.025847 -35.890292) (xy 114.118135 -35.899932)
			(xy 114.208919 -35.919123) (xy 114.297213 -35.947656) (xy 114.339878 -35.965892) (xy 114.34982 -35.969698)
			(xy 114.371084 -35.969698) (xy 114.381026 -35.965892) (xy 114.423695 -35.947663) (xy 114.511985 -35.919115)
			(xy 114.602768 -35.899917) (xy 114.695056 -35.890279) (xy 114.741452 -35.889692) (xy 114.787847 -35.890292)
			(xy 114.880135 -35.899932) (xy 114.970919 -35.919123) (xy 115.059213 -35.947656) (xy 115.101878 -35.965892)
			(xy 115.11182 -35.969698) (xy 115.133084 -35.969698) (xy 115.143026 -35.965892) (xy 115.185635 -35.947686)
			(xy 115.2738 -35.919164) (xy 115.364454 -35.899967) (xy 115.456612 -35.890303) (xy 115.502944 -35.889692)
			(xy 115.503452 -35.889692) (xy 115.544554 -35.890198) (xy 115.626409 -35.897779) (xy 115.707215 -35.91288)
			(xy 115.786282 -35.935373) (xy 115.862937 -35.965065) (xy 115.936525 -36.001704) (xy 116.006418 -36.044977)
			(xy 116.072021 -36.094514) (xy 116.132772 -36.149894) (xy 116.188155 -36.210642) (xy 116.237696 -36.276242)
			(xy 116.280972 -36.346133) (xy 116.317615 -36.419719) (xy 116.347312 -36.496372) (xy 116.369809 -36.575439)
			(xy 116.384915 -36.656244) (xy 116.3925 -36.738098) (xy 116.39296 -36.7792) (xy 116.39296 -36.779708)
			(xy 116.392358 -36.82604) (xy 116.382686 -36.918198) (xy 116.363489 -37.008852) (xy 116.334976 -37.097021)
			(xy 116.31676 -37.139626) (xy 116.312952 -37.149568) (xy 116.312952 -37.170832) (xy 116.31676 -37.180774)
			(xy 116.335002 -37.223437) (xy 116.363547 -37.311729) (xy 116.382741 -37.402514) (xy 116.392375 -37.494804)
			(xy 116.39296 -37.5412) (xy 116.392381 -37.587596) (xy 116.382736 -37.679884) (xy 116.363539 -37.770668)
			(xy 116.334999 -37.858961) (xy 116.31676 -37.901626) (xy 116.312952 -37.911568) (xy 116.312952 -37.932832)
			(xy 116.31676 -37.942774) (xy 116.335002 -37.985437) (xy 116.363547 -38.073729) (xy 116.382741 -38.164514)
			(xy 116.392375 -38.256804) (xy 116.39296 -38.3032) (xy 116.392381 -38.349596) (xy 116.382736 -38.441884)
			(xy 116.363539 -38.532668) (xy 116.334999 -38.620961) (xy 116.31676 -38.663626) (xy 116.312952 -38.673568)
			(xy 116.312952 -38.694832) (xy 116.31676 -38.704774) (xy 116.335002 -38.747437) (xy 116.363547 -38.835729)
			(xy 116.382741 -38.926514) (xy 116.392375 -39.018804) (xy 116.39296 -39.0652) (xy 116.392381 -39.111596)
			(xy 116.382736 -39.203884) (xy 116.363539 -39.294668) (xy 116.334999 -39.382961) (xy 116.31676 -39.425626)
			(xy 116.312952 -39.435568) (xy 116.312952 -39.456832) (xy 116.31676 -39.466774) (xy 116.334985 -39.509376)
			(xy 116.363501 -39.597544) (xy 116.382693 -39.688199) (xy 116.392352 -39.78036) (xy 116.39296 -39.826692)
			(xy 116.39296 -39.8272) (xy 116.392548 -39.868305) (xy 116.384962 -39.950163) (xy 116.369856 -40.030972)
			(xy 116.347357 -40.110043) (xy 116.317659 -40.1867) (xy 116.281014 -40.26029) (xy 116.237735 -40.330185)
			(xy 116.188192 -40.395788) (xy 116.132806 -40.45654) (xy 116.072051 -40.511922) (xy 116.006446 -40.561462)
			(xy 115.936548 -40.604738) (xy 115.862956 -40.641379) (xy 115.786297 -40.671073) (xy 115.707226 -40.693567)
			(xy 115.626415 -40.708669) (xy 115.544557 -40.71625) (xy 115.503452 -40.716708) (xy 115.502944 -40.716708)
			(xy 115.456613 -40.716084) (xy 115.364455 -40.706418) (xy 115.273801 -40.687227) (xy 115.185632 -40.658721)
			(xy 115.143026 -40.640508) (xy 115.133084 -40.636702) (xy 115.11182 -40.636702) (xy 115.101878 -40.640508)
			(xy 115.059209 -40.658736) (xy 114.970919 -40.687284) (xy 114.880136 -40.706482) (xy 114.787847 -40.71612)
			(xy 114.741452 -40.716708) (xy 114.695057 -40.716107) (xy 114.602769 -40.706467) (xy 114.511985 -40.687276)
			(xy 114.423691 -40.658743) (xy 114.381026 -40.640508) (xy 114.371084 -40.636702) (xy 114.34982 -40.636702)
			(xy 114.339878 -40.640508) (xy 114.297209 -40.658736) (xy 114.208919 -40.687284) (xy 114.118136 -40.706482)
			(xy 114.025847 -40.71612) (xy 113.979452 -40.716708) (xy 113.933057 -40.716107) (xy 113.840769 -40.706467)
			(xy 113.749985 -40.687276) (xy 113.661691 -40.658743) (xy 113.619026 -40.640508) (xy 113.609084 -40.636702)
			(xy 113.58782 -40.636702) (xy 113.577878 -40.640508) (xy 113.535209 -40.658736) (xy 113.446919 -40.687284)
			(xy 113.356136 -40.706482) (xy 113.263847 -40.71612) (xy 113.217452 -40.716708) (xy 113.171057 -40.716107)
			(xy 113.078769 -40.706467) (xy 112.987985 -40.687276) (xy 112.899691 -40.658743) (xy 112.857026 -40.640508)
			(xy 112.847084 -40.636702) (xy 112.82582 -40.636702) (xy 112.815878 -40.640508) (xy 112.773268 -40.658713)
			(xy 112.685103 -40.687235) (xy 112.59445 -40.706433) (xy 112.502292 -40.716097) (xy 112.45596 -40.716708)
			(xy 112.455452 -40.716708) (xy 112.414349 -40.716279) (xy 112.332493 -40.70869) (xy 112.251687 -40.693581)
			(xy 112.17262 -40.67108) (xy 112.095965 -40.641381) (xy 112.022379 -40.604735) (xy 111.952487 -40.561457)
			(xy 111.886886 -40.511914) (xy 111.826136 -40.45653) (xy 111.770755 -40.395777) (xy 111.721216 -40.330174)
			(xy 111.677941 -40.260279) (xy 111.6413 -40.186691) (xy 111.611604 -40.110035) (xy 111.589108 -40.030966)
			(xy 111.574003 -39.950159) (xy 111.566419 -39.868303) (xy 111.565944 -39.8272) (xy 0.509016 -39.8272)
			(xy 0.509016 -42.474585) (xy 107.8931 -42.474585) (xy 107.8931 -42.389863) (xy 107.901153 -42.305526)
			(xy 107.917187 -42.222336) (xy 107.941055 -42.141046) (xy 107.972543 -42.062394) (xy 108.011365 -41.987091)
			(xy 108.057168 -41.915819) (xy 108.109539 -41.849223) (xy 108.168004 -41.787908) (xy 108.232032 -41.732427)
			(xy 108.301044 -41.683284) (xy 108.374414 -41.640924) (xy 108.451479 -41.605729) (xy 108.531541 -41.57802)
			(xy 108.613874 -41.558046) (xy 108.697733 -41.545989) (xy 108.782358 -41.541958) (xy 108.866983 -41.545989)
			(xy 108.950842 -41.558046) (xy 109.033175 -41.57802) (xy 109.113237 -41.605729) (xy 109.190302 -41.640924)
			(xy 109.263672 -41.683284) (xy 109.332684 -41.732427) (xy 109.396712 -41.787908) (xy 109.455177 -41.849223)
			(xy 109.507548 -41.915819) (xy 109.553351 -41.987091) (xy 109.592173 -42.062394) (xy 109.623661 -42.141046)
			(xy 109.647529 -42.222336) (xy 109.663563 -42.305526) (xy 109.671616 -42.389863) (xy 109.67212 -42.432224)
			(xy 109.671616 -42.474585) (xy 109.663563 -42.558922) (xy 109.647529 -42.642112) (xy 109.623661 -42.723402)
			(xy 109.592173 -42.802054) (xy 109.553351 -42.877357) (xy 109.507548 -42.948629) (xy 109.455177 -43.015225)
			(xy 109.396712 -43.07654) (xy 109.332684 -43.132021) (xy 109.263672 -43.181164) (xy 109.192316 -43.222361)
			(xy 110.388142 -43.222361) (xy 110.388142 -43.137639) (xy 110.396195 -43.053302) (xy 110.412229 -42.970112)
			(xy 110.436097 -42.888822) (xy 110.467585 -42.81017) (xy 110.506407 -42.734867) (xy 110.55221 -42.663595)
			(xy 110.604581 -42.596999) (xy 110.663046 -42.535684) (xy 110.727074 -42.480203) (xy 110.796086 -42.43106)
			(xy 110.869456 -42.3887) (xy 110.946521 -42.353505) (xy 111.026583 -42.325796) (xy 111.108916 -42.305822)
			(xy 111.192775 -42.293765) (xy 111.2774 -42.289734) (xy 111.362025 -42.293765) (xy 111.445884 -42.305822)
			(xy 111.528217 -42.325796) (xy 111.608279 -42.353505) (xy 111.685344 -42.3887) (xy 111.758714 -42.43106)
			(xy 111.827726 -42.480203) (xy 111.891754 -42.535684) (xy 111.950219 -42.596999) (xy 112.00259 -42.663595)
			(xy 112.048393 -42.734867) (xy 112.087215 -42.81017) (xy 112.118703 -42.888822) (xy 112.142571 -42.970112)
			(xy 112.158605 -43.053302) (xy 112.166658 -43.137639) (xy 112.167162 -43.18) (xy 112.166658 -43.222361)
			(xy 112.158605 -43.306698) (xy 112.142571 -43.389888) (xy 112.118703 -43.471178) (xy 112.087215 -43.54983)
			(xy 112.048393 -43.625133) (xy 112.00259 -43.696405) (xy 111.950219 -43.763001) (xy 111.891754 -43.824316)
			(xy 111.827726 -43.879797) (xy 111.758714 -43.92894) (xy 111.685344 -43.9713) (xy 111.608279 -44.006495)
			(xy 111.528217 -44.034204) (xy 111.445884 -44.054178) (xy 111.362025 -44.066235) (xy 111.2774 -44.070267)
			(xy 111.192775 -44.066235) (xy 111.108916 -44.054178) (xy 111.026583 -44.034204) (xy 110.946521 -44.006495)
			(xy 110.869456 -43.9713) (xy 110.796086 -43.92894) (xy 110.727074 -43.879797) (xy 110.663046 -43.824316)
			(xy 110.604581 -43.763001) (xy 110.55221 -43.696405) (xy 110.506407 -43.625133) (xy 110.467585 -43.54983)
			(xy 110.436097 -43.471178) (xy 110.412229 -43.389888) (xy 110.396195 -43.306698) (xy 110.388142 -43.222361)
			(xy 109.192316 -43.222361) (xy 109.190302 -43.223524) (xy 109.113237 -43.258719) (xy 109.033175 -43.286428)
			(xy 108.950842 -43.306402) (xy 108.866983 -43.318459) (xy 108.782358 -43.322491) (xy 108.697733 -43.318459)
			(xy 108.613874 -43.306402) (xy 108.531541 -43.286428) (xy 108.451479 -43.258719) (xy 108.374414 -43.223524)
			(xy 108.301044 -43.181164) (xy 108.232032 -43.132021) (xy 108.168004 -43.07654) (xy 108.109539 -43.015225)
			(xy 108.057168 -42.948629) (xy 108.011365 -42.877357) (xy 107.972543 -42.802054) (xy 107.941055 -42.723402)
			(xy 107.917187 -42.642112) (xy 107.901153 -42.558922) (xy 107.8931 -42.474585) (xy 0.509016 -42.474585)
			(xy 0.509016 -44.873361) (xy 111.362994 -44.873361) (xy 111.362994 -44.788639) (xy 111.371047 -44.704302)
			(xy 111.387081 -44.621112) (xy 111.410949 -44.539822) (xy 111.442437 -44.46117) (xy 111.481259 -44.385867)
			(xy 111.527062 -44.314595) (xy 111.579433 -44.247999) (xy 111.637898 -44.186684) (xy 111.701926 -44.131203)
			(xy 111.770938 -44.08206) (xy 111.844308 -44.0397) (xy 111.921373 -44.004505) (xy 112.001435 -43.976796)
			(xy 112.083768 -43.956822) (xy 112.167627 -43.944765) (xy 112.252252 -43.940734) (xy 112.336877 -43.944765)
			(xy 112.420736 -43.956822) (xy 112.503069 -43.976796) (xy 112.583131 -44.004505) (xy 112.660196 -44.0397)
			(xy 112.733566 -44.08206) (xy 112.802578 -44.131203) (xy 112.866606 -44.186684) (xy 112.925071 -44.247999)
			(xy 112.977442 -44.314595) (xy 113.023245 -44.385867) (xy 113.062067 -44.46117) (xy 113.093555 -44.539822)
			(xy 113.117423 -44.621112) (xy 113.133457 -44.704302) (xy 113.14151 -44.788639) (xy 113.142014 -44.831)
			(xy 113.14151 -44.873361) (xy 113.133457 -44.957698) (xy 113.117423 -45.040888) (xy 113.093555 -45.122178)
			(xy 113.062067 -45.20083) (xy 113.023245 -45.276133) (xy 112.977442 -45.347405) (xy 112.925071 -45.414001)
			(xy 112.866606 -45.475316) (xy 112.802578 -45.530797) (xy 112.733566 -45.57994) (xy 112.660196 -45.6223)
			(xy 112.583131 -45.657495) (xy 112.503069 -45.685204) (xy 112.420736 -45.705178) (xy 112.336877 -45.717235)
			(xy 112.252252 -45.721267) (xy 112.167627 -45.717235) (xy 112.083768 -45.705178) (xy 112.001435 -45.685204)
			(xy 111.921373 -45.657495) (xy 111.844308 -45.6223) (xy 111.770938 -45.57994) (xy 111.701926 -45.530797)
			(xy 111.637898 -45.475316) (xy 111.579433 -45.414001) (xy 111.527062 -45.347405) (xy 111.481259 -45.276133)
			(xy 111.442437 -45.20083) (xy 111.410949 -45.122178) (xy 111.387081 -45.040888) (xy 111.371047 -44.957698)
			(xy 111.362994 -44.873361) (xy 0.509016 -44.873361) (xy 0.509016 -50.919888) (xy 41.345622 -50.919888)
			(xy 41.349604 -50.829938) (xy 41.361521 -50.740691) (xy 41.381279 -50.652847) (xy 41.408723 -50.567093)
			(xy 41.443639 -50.4841) (xy 41.485753 -50.404518) (xy 41.534736 -50.328969) (xy 41.590204 -50.258045)
			(xy 41.651724 -50.1923) (xy 41.718813 -50.13225) (xy 41.790947 -50.078365) (xy 41.867561 -50.031065)
			(xy 41.948055 -49.990722) (xy 42.0318 -49.95765) (xy 42.118141 -49.93211) (xy 42.2064 -49.9143) (xy 42.295889 -49.90436)
			(xy 42.385905 -49.902369) (xy 42.475746 -49.90834) (xy 42.564707 -49.922229) (xy 42.652092 -49.943925)
			(xy 42.737218 -49.97326) (xy 42.819418 -50.010003) (xy 42.898049 -50.053867) (xy 42.972496 -50.104509)
			(xy 43.042176 -50.161533) (xy 43.106543 -50.224492) (xy 43.165094 -50.292893) (xy 43.217371 -50.366201)
			(xy 43.262964 -50.443843) (xy 43.301517 -50.52521) (xy 43.332728 -50.609666) (xy 43.356352 -50.69655)
			(xy 43.372205 -50.785182) (xy 43.380162 -50.874869) (xy 43.38066 -50.919888) (xy 60.903622 -50.919888)
			(xy 60.907604 -50.829938) (xy 60.919521 -50.740691) (xy 60.939279 -50.652847) (xy 60.966723 -50.567093)
			(xy 61.001639 -50.4841) (xy 61.043753 -50.404518) (xy 61.092736 -50.328969) (xy 61.148204 -50.258045)
			(xy 61.209724 -50.1923) (xy 61.276813 -50.13225) (xy 61.348947 -50.078365) (xy 61.425561 -50.031065)
			(xy 61.506055 -49.990722) (xy 61.5898 -49.95765) (xy 61.676141 -49.93211) (xy 61.7644 -49.9143) (xy 61.853889 -49.90436)
			(xy 61.943905 -49.902369) (xy 62.033746 -49.90834) (xy 62.122707 -49.922229) (xy 62.210092 -49.943925)
			(xy 62.295218 -49.97326) (xy 62.377418 -50.010003) (xy 62.456049 -50.053867) (xy 62.530496 -50.104509)
			(xy 62.600176 -50.161533) (xy 62.664543 -50.224492) (xy 62.723094 -50.292893) (xy 62.775371 -50.366201)
			(xy 62.820964 -50.443843) (xy 62.859517 -50.52521) (xy 62.890728 -50.609666) (xy 62.914352 -50.69655)
			(xy 62.930205 -50.785182) (xy 62.938162 -50.874869) (xy 62.93866 -50.919888) (xy 62.938162 -50.964907)
			(xy 62.930205 -51.054594) (xy 62.921225 -51.1048) (xy 111.565944 -51.1048) (xy 111.565944 -51.104292)
			(xy 111.566546 -51.05796) (xy 111.576218 -50.965802) (xy 111.595414 -50.875148) (xy 111.623928 -50.786979)
			(xy 111.642144 -50.744374) (xy 111.645952 -50.734432) (xy 111.645952 -50.713168) (xy 111.642144 -50.703226)
			(xy 111.623902 -50.660562) (xy 111.595357 -50.572271) (xy 111.576163 -50.481486) (xy 111.566529 -50.389196)
			(xy 111.565944 -50.3428) (xy 111.566522 -50.296404) (xy 111.576168 -50.204116) (xy 111.595365 -50.113332)
			(xy 111.623905 -50.025039) (xy 111.642144 -49.982374) (xy 111.645952 -49.972432) (xy 111.645952 -49.951168)
			(xy 111.642144 -49.941226) (xy 111.623902 -49.898562) (xy 111.595357 -49.810271) (xy 111.576163 -49.719486)
			(xy 111.566529 -49.627196) (xy 111.565944 -49.5808) (xy 111.566522 -49.534404) (xy 111.576168 -49.442116)
			(xy 111.595365 -49.351332) (xy 111.623905 -49.263039) (xy 111.642144 -49.220374) (xy 111.645952 -49.210432)
			(xy 111.645952 -49.189168) (xy 111.642144 -49.179226) (xy 111.623902 -49.136562) (xy 111.595357 -49.048271)
			(xy 111.576163 -48.957486) (xy 111.566529 -48.865196) (xy 111.565944 -48.8188) (xy 111.566522 -48.772404)
			(xy 111.576168 -48.680116) (xy 111.595365 -48.589332) (xy 111.623905 -48.501039) (xy 111.642144 -48.458374)
			(xy 111.645952 -48.448432) (xy 111.645952 -48.427168) (xy 111.642144 -48.417226) (xy 111.623919 -48.374624)
			(xy 111.595403 -48.286456) (xy 111.576211 -48.1958) (xy 111.566552 -48.10364) (xy 111.565944 -48.057308)
			(xy 111.565944 -48.0568) (xy 111.566467 -48.015699) (xy 111.574051 -47.933847) (xy 111.589155 -47.853045)
			(xy 111.61165 -47.77398) (xy 111.641344 -47.697329) (xy 111.677983 -47.623744) (xy 111.721256 -47.553853)
			(xy 111.770792 -47.488254) (xy 111.82617 -47.427504) (xy 111.886917 -47.372123) (xy 111.952514 -47.322583)
			(xy 112.022402 -47.279307) (xy 112.095985 -47.242663) (xy 112.172635 -47.212965) (xy 112.251698 -47.190466)
			(xy 112.3325 -47.175358) (xy 112.414351 -47.167769) (xy 112.455452 -47.167292) (xy 112.45596 -47.167292)
			(xy 112.502291 -47.167915) (xy 112.594449 -47.177581) (xy 112.685103 -47.196772) (xy 112.773272 -47.225279)
			(xy 112.815878 -47.243492) (xy 112.82582 -47.247298) (xy 112.847084 -47.247298) (xy 112.857026 -47.243492)
			(xy 112.899695 -47.225263) (xy 112.987985 -47.196715) (xy 113.078768 -47.177517) (xy 113.171056 -47.167879)
			(xy 113.217452 -47.167292) (xy 113.263847 -47.167892) (xy 113.356135 -47.177532) (xy 113.446919 -47.196723)
			(xy 113.535213 -47.225256) (xy 113.577878 -47.243492) (xy 113.58782 -47.247298) (xy 113.609084 -47.247298)
			(xy 113.619026 -47.243492) (xy 113.661695 -47.225263) (xy 113.749985 -47.196715) (xy 113.840768 -47.177517)
			(xy 113.933056 -47.167879) (xy 113.979452 -47.167292) (xy 114.025847 -47.167892) (xy 114.118135 -47.177532)
			(xy 114.208919 -47.196723) (xy 114.297213 -47.225256) (xy 114.339878 -47.243492) (xy 114.34982 -47.247298)
			(xy 114.371084 -47.247298) (xy 114.381026 -47.243492) (xy 114.423695 -47.225263) (xy 114.511985 -47.196715)
			(xy 114.602768 -47.177517) (xy 114.695056 -47.167879) (xy 114.741452 -47.167292) (xy 114.787847 -47.167892)
			(xy 114.880135 -47.177532) (xy 114.970919 -47.196723) (xy 115.059213 -47.225256) (xy 115.101878 -47.243492)
			(xy 115.11182 -47.247298) (xy 115.133084 -47.247298) (xy 115.143026 -47.243492) (xy 115.185635 -47.225286)
			(xy 115.2738 -47.196764) (xy 115.364454 -47.177567) (xy 115.456612 -47.167903) (xy 115.502944 -47.167292)
			(xy 115.503452 -47.167292) (xy 115.544554 -47.167798) (xy 115.626409 -47.175379) (xy 115.707215 -47.19048)
			(xy 115.786282 -47.212973) (xy 115.862937 -47.242665) (xy 115.936525 -47.279304) (xy 116.006418 -47.322577)
			(xy 116.072021 -47.372114) (xy 116.132772 -47.427494) (xy 116.188155 -47.488242) (xy 116.237696 -47.553842)
			(xy 116.280972 -47.623733) (xy 116.317615 -47.697319) (xy 116.347312 -47.773972) (xy 116.369809 -47.853039)
			(xy 116.384915 -47.933844) (xy 116.3925 -48.015698) (xy 116.39296 -48.0568) (xy 116.39296 -48.057308)
			(xy 116.392358 -48.10364) (xy 116.382686 -48.195798) (xy 116.363489 -48.286452) (xy 116.334976 -48.374621)
			(xy 116.31676 -48.417226) (xy 116.312952 -48.427168) (xy 116.312952 -48.448432) (xy 116.31676 -48.458374)
			(xy 116.335002 -48.501037) (xy 116.363547 -48.589329) (xy 116.382741 -48.680114) (xy 116.392375 -48.772404)
			(xy 116.39296 -48.8188) (xy 116.392381 -48.865196) (xy 116.382736 -48.957484) (xy 116.363539 -49.048268)
			(xy 116.334999 -49.136561) (xy 116.31676 -49.179226) (xy 116.312952 -49.189168) (xy 116.312952 -49.210432)
			(xy 116.31676 -49.220374) (xy 116.335002 -49.263037) (xy 116.363547 -49.351329) (xy 116.382741 -49.442114)
			(xy 116.392375 -49.534404) (xy 116.39296 -49.5808) (xy 116.392381 -49.627196) (xy 116.382736 -49.719484)
			(xy 116.363539 -49.810268) (xy 116.334999 -49.898561) (xy 116.31676 -49.941226) (xy 116.312952 -49.951168)
			(xy 116.312952 -49.972432) (xy 116.31676 -49.982374) (xy 116.335002 -50.025037) (xy 116.363547 -50.113329)
			(xy 116.382741 -50.204114) (xy 116.392375 -50.296404) (xy 116.39296 -50.3428) (xy 116.392381 -50.389196)
			(xy 116.382736 -50.481484) (xy 116.363539 -50.572268) (xy 116.334999 -50.660561) (xy 116.31676 -50.703226)
			(xy 116.312952 -50.713168) (xy 116.312952 -50.734432) (xy 116.31676 -50.744374) (xy 116.334985 -50.786976)
			(xy 116.363501 -50.875144) (xy 116.382693 -50.965799) (xy 116.392352 -51.05796) (xy 116.39296 -51.104292)
			(xy 116.39296 -51.1048) (xy 116.392548 -51.145905) (xy 116.384962 -51.227763) (xy 116.369856 -51.308572)
			(xy 116.347357 -51.387643) (xy 116.317659 -51.4643) (xy 116.281014 -51.53789) (xy 116.237735 -51.607785)
			(xy 116.188192 -51.673388) (xy 116.132806 -51.73414) (xy 116.072051 -51.789522) (xy 116.006446 -51.839062)
			(xy 115.936548 -51.882338) (xy 115.862956 -51.918979) (xy 115.786297 -51.948673) (xy 115.707226 -51.971167)
			(xy 115.626415 -51.986269) (xy 115.544557 -51.99385) (xy 115.503452 -51.994308) (xy 115.502944 -51.994308)
			(xy 115.456613 -51.993684) (xy 115.364455 -51.984018) (xy 115.273801 -51.964827) (xy 115.185632 -51.936321)
			(xy 115.143026 -51.918108) (xy 115.133084 -51.914302) (xy 115.11182 -51.914302) (xy 115.101878 -51.918108)
			(xy 115.059209 -51.936336) (xy 114.970919 -51.964884) (xy 114.880136 -51.984082) (xy 114.787847 -51.99372)
			(xy 114.741452 -51.994308) (xy 114.695057 -51.993707) (xy 114.602769 -51.984067) (xy 114.511985 -51.964876)
			(xy 114.423691 -51.936343) (xy 114.381026 -51.918108) (xy 114.371084 -51.914302) (xy 114.34982 -51.914302)
			(xy 114.339878 -51.918108) (xy 114.297209 -51.936336) (xy 114.208919 -51.964884) (xy 114.118136 -51.984082)
			(xy 114.025847 -51.99372) (xy 113.979452 -51.994308) (xy 113.933057 -51.993707) (xy 113.840769 -51.984067)
			(xy 113.749985 -51.964876) (xy 113.661691 -51.936343) (xy 113.619026 -51.918108) (xy 113.609084 -51.914302)
			(xy 113.58782 -51.914302) (xy 113.577878 -51.918108) (xy 113.535209 -51.936336) (xy 113.446919 -51.964884)
			(xy 113.356136 -51.984082) (xy 113.263847 -51.99372) (xy 113.217452 -51.994308) (xy 113.171057 -51.993707)
			(xy 113.078769 -51.984067) (xy 112.987985 -51.964876) (xy 112.899691 -51.936343) (xy 112.857026 -51.918108)
			(xy 112.847084 -51.914302) (xy 112.82582 -51.914302) (xy 112.815878 -51.918108) (xy 112.773268 -51.936313)
			(xy 112.685103 -51.964835) (xy 112.59445 -51.984033) (xy 112.502292 -51.993697) (xy 112.45596 -51.994308)
			(xy 112.455452 -51.994308) (xy 112.414349 -51.993879) (xy 112.332493 -51.98629) (xy 112.251687 -51.971181)
			(xy 112.17262 -51.94868) (xy 112.095965 -51.918981) (xy 112.022379 -51.882335) (xy 111.952487 -51.839057)
			(xy 111.886886 -51.789514) (xy 111.826136 -51.73413) (xy 111.770755 -51.673377) (xy 111.721216 -51.607774)
			(xy 111.677941 -51.537879) (xy 111.6413 -51.464291) (xy 111.611604 -51.387635) (xy 111.589108 -51.308566)
			(xy 111.574003 -51.227759) (xy 111.566419 -51.145903) (xy 111.565944 -51.1048) (xy 62.921225 -51.1048)
			(xy 62.914352 -51.143226) (xy 62.890728 -51.23011) (xy 62.859517 -51.314566) (xy 62.820964 -51.395933)
			(xy 62.775371 -51.473575) (xy 62.723094 -51.546883) (xy 62.664543 -51.615284) (xy 62.600176 -51.678243)
			(xy 62.530496 -51.735267) (xy 62.456049 -51.785909) (xy 62.377418 -51.829773) (xy 62.295218 -51.866516)
			(xy 62.210092 -51.895851) (xy 62.122707 -51.917547) (xy 62.033746 -51.931436) (xy 61.943905 -51.937407)
			(xy 61.853889 -51.935416) (xy 61.7644 -51.925476) (xy 61.676141 -51.907666) (xy 61.5898 -51.882126)
			(xy 61.506055 -51.849054) (xy 61.425561 -51.808711) (xy 61.348947 -51.761411) (xy 61.276813 -51.707526)
			(xy 61.209724 -51.647476) (xy 61.148204 -51.581731) (xy 61.092736 -51.510807) (xy 61.043753 -51.435258)
			(xy 61.001639 -51.355676) (xy 60.966723 -51.272683) (xy 60.939279 -51.186929) (xy 60.919521 -51.099085)
			(xy 60.907604 -51.009838) (xy 60.903622 -50.919888) (xy 43.38066 -50.919888) (xy 43.380162 -50.964907)
			(xy 43.372205 -51.054594) (xy 43.356352 -51.143226) (xy 43.332728 -51.23011) (xy 43.301517 -51.314566)
			(xy 43.262964 -51.395933) (xy 43.217371 -51.473575) (xy 43.165094 -51.546883) (xy 43.106543 -51.615284)
			(xy 43.042176 -51.678243) (xy 42.972496 -51.735267) (xy 42.898049 -51.785909) (xy 42.819418 -51.829773)
			(xy 42.737218 -51.866516) (xy 42.652092 -51.895851) (xy 42.564707 -51.917547) (xy 42.475746 -51.931436)
			(xy 42.385905 -51.937407) (xy 42.295889 -51.935416) (xy 42.2064 -51.925476) (xy 42.118141 -51.907666)
			(xy 42.0318 -51.882126) (xy 41.948055 -51.849054) (xy 41.867561 -51.808711) (xy 41.790947 -51.761411)
			(xy 41.718813 -51.707526) (xy 41.651724 -51.647476) (xy 41.590204 -51.581731) (xy 41.534736 -51.510807)
			(xy 41.485753 -51.435258) (xy 41.443639 -51.355676) (xy 41.408723 -51.272683) (xy 41.381279 -51.186929)
			(xy 41.361521 -51.099085) (xy 41.349604 -51.009838) (xy 41.345622 -50.919888) (xy 0.509016 -50.919888)
			(xy 0.509016 -53.735167) (xy 108.485174 -53.735167) (xy 108.485174 -53.650445) (xy 108.493227 -53.566108)
			(xy 108.509261 -53.482918) (xy 108.533129 -53.401628) (xy 108.564617 -53.322976) (xy 108.603439 -53.247673)
			(xy 108.649242 -53.176401) (xy 108.701613 -53.109805) (xy 108.760078 -53.04849) (xy 108.824106 -52.993009)
			(xy 108.893118 -52.943866) (xy 108.966488 -52.901506) (xy 109.043553 -52.866311) (xy 109.123615 -52.838602)
			(xy 109.205948 -52.818628) (xy 109.289807 -52.806571) (xy 109.374432 -52.80254) (xy 109.459057 -52.806571)
			(xy 109.542916 -52.818628) (xy 109.625249 -52.838602) (xy 109.705311 -52.866311) (xy 109.782376 -52.901506)
			(xy 109.855746 -52.943866) (xy 109.924758 -52.993009) (xy 109.988786 -53.04849) (xy 110.047251 -53.109805)
			(xy 110.099622 -53.176401) (xy 110.145425 -53.247673) (xy 110.184247 -53.322976) (xy 110.215735 -53.401628)
			(xy 110.239603 -53.482918) (xy 110.255637 -53.566108) (xy 110.26369 -53.650445) (xy 110.264194 -53.692806)
			(xy 110.26369 -53.735167) (xy 110.255637 -53.819504) (xy 110.239603 -53.902694) (xy 110.215735 -53.983984)
			(xy 110.184247 -54.062636) (xy 110.145425 -54.137939) (xy 110.099622 -54.209211) (xy 110.047251 -54.275807)
			(xy 109.988786 -54.337122) (xy 109.924758 -54.392603) (xy 109.855746 -54.441746) (xy 109.782376 -54.484106)
			(xy 109.705311 -54.519301) (xy 109.687801 -54.525361) (xy 110.388142 -54.525361) (xy 110.388142 -54.440639)
			(xy 110.396195 -54.356302) (xy 110.412229 -54.273112) (xy 110.436097 -54.191822) (xy 110.467585 -54.11317)
			(xy 110.506407 -54.037867) (xy 110.55221 -53.966595) (xy 110.604581 -53.899999) (xy 110.663046 -53.838684)
			(xy 110.727074 -53.783203) (xy 110.796086 -53.73406) (xy 110.869456 -53.6917) (xy 110.946521 -53.656505)
			(xy 111.026583 -53.628796) (xy 111.108916 -53.608822) (xy 111.192775 -53.596765) (xy 111.2774 -53.592734)
			(xy 111.362025 -53.596765) (xy 111.445884 -53.608822) (xy 111.528217 -53.628796) (xy 111.608279 -53.656505)
			(xy 111.685344 -53.6917) (xy 111.758714 -53.73406) (xy 111.827726 -53.783203) (xy 111.891754 -53.838684)
			(xy 111.950219 -53.899999) (xy 112.00259 -53.966595) (xy 112.048393 -54.037867) (xy 112.087215 -54.11317)
			(xy 112.118703 -54.191822) (xy 112.142571 -54.273112) (xy 112.158605 -54.356302) (xy 112.166658 -54.440639)
			(xy 112.167162 -54.483) (xy 112.166658 -54.525361) (xy 112.158605 -54.609698) (xy 112.142571 -54.692888)
			(xy 112.118703 -54.774178) (xy 112.087215 -54.85283) (xy 112.048393 -54.928133) (xy 112.00259 -54.999405)
			(xy 111.950219 -55.066001) (xy 111.891754 -55.127316) (xy 111.827726 -55.182797) (xy 111.758714 -55.23194)
			(xy 111.685344 -55.2743) (xy 111.608279 -55.309495) (xy 111.528217 -55.337204) (xy 111.445884 -55.357178)
			(xy 111.362025 -55.369235) (xy 111.2774 -55.373267) (xy 111.192775 -55.369235) (xy 111.108916 -55.357178)
			(xy 111.026583 -55.337204) (xy 110.946521 -55.309495) (xy 110.869456 -55.2743) (xy 110.796086 -55.23194)
			(xy 110.727074 -55.182797) (xy 110.663046 -55.127316) (xy 110.604581 -55.066001) (xy 110.55221 -54.999405)
			(xy 110.506407 -54.928133) (xy 110.467585 -54.85283) (xy 110.436097 -54.774178) (xy 110.412229 -54.692888)
			(xy 110.396195 -54.609698) (xy 110.388142 -54.525361) (xy 109.687801 -54.525361) (xy 109.625249 -54.54701)
			(xy 109.542916 -54.566984) (xy 109.459057 -54.579041) (xy 109.374432 -54.583073) (xy 109.289807 -54.579041)
			(xy 109.205948 -54.566984) (xy 109.123615 -54.54701) (xy 109.043553 -54.519301) (xy 108.966488 -54.484106)
			(xy 108.893118 -54.441746) (xy 108.824106 -54.392603) (xy 108.760078 -54.337122) (xy 108.701613 -54.275807)
			(xy 108.649242 -54.209211) (xy 108.603439 -54.137939) (xy 108.564617 -54.062636) (xy 108.533129 -53.983984)
			(xy 108.509261 -53.902694) (xy 108.493227 -53.819504) (xy 108.485174 -53.735167) (xy 0.509016 -53.735167)
			(xy 0.509016 -56.150961) (xy 111.362994 -56.150961) (xy 111.362994 -56.066239) (xy 111.371047 -55.981902)
			(xy 111.387081 -55.898712) (xy 111.410949 -55.817422) (xy 111.442437 -55.73877) (xy 111.481259 -55.663467)
			(xy 111.527062 -55.592195) (xy 111.579433 -55.525599) (xy 111.637898 -55.464284) (xy 111.701926 -55.408803)
			(xy 111.770938 -55.35966) (xy 111.844308 -55.3173) (xy 111.921373 -55.282105) (xy 112.001435 -55.254396)
			(xy 112.083768 -55.234422) (xy 112.167627 -55.222365) (xy 112.252252 -55.218334) (xy 112.336877 -55.222365)
			(xy 112.420736 -55.234422) (xy 112.503069 -55.254396) (xy 112.583131 -55.282105) (xy 112.660196 -55.3173)
			(xy 112.733566 -55.35966) (xy 112.802578 -55.408803) (xy 112.866606 -55.464284) (xy 112.925071 -55.525599)
			(xy 112.977442 -55.592195) (xy 113.023245 -55.663467) (xy 113.062067 -55.73877) (xy 113.093555 -55.817422)
			(xy 113.117423 -55.898712) (xy 113.133457 -55.981902) (xy 113.14151 -56.066239) (xy 113.142014 -56.1086)
			(xy 113.14151 -56.150961) (xy 113.133457 -56.235298) (xy 113.117423 -56.318488) (xy 113.093555 -56.399778)
			(xy 113.062067 -56.47843) (xy 113.023245 -56.553733) (xy 112.977442 -56.625005) (xy 112.925071 -56.691601)
			(xy 112.866606 -56.752916) (xy 112.802578 -56.808397) (xy 112.733566 -56.85754) (xy 112.660196 -56.8999)
			(xy 112.583131 -56.935095) (xy 112.503069 -56.962804) (xy 112.420736 -56.982778) (xy 112.336877 -56.994835)
			(xy 112.252252 -56.998867) (xy 112.167627 -56.994835) (xy 112.083768 -56.982778) (xy 112.001435 -56.962804)
			(xy 111.921373 -56.935095) (xy 111.844308 -56.8999) (xy 111.770938 -56.85754) (xy 111.701926 -56.808397)
			(xy 111.637898 -56.752916) (xy 111.579433 -56.691601) (xy 111.527062 -56.625005) (xy 111.481259 -56.553733)
			(xy 111.442437 -56.47843) (xy 111.410949 -56.399778) (xy 111.387081 -56.318488) (xy 111.371047 -56.235298)
			(xy 111.362994 -56.150961) (xy 0.509016 -56.150961) (xy 0.509016 -60.099956) (xy 12.484104 -60.099956)
			(xy 12.488134 -59.957621) (xy 12.500209 -59.815741) (xy 12.520292 -59.674773) (xy 12.548319 -59.535166)
			(xy 12.584199 -59.397368) (xy 12.627817 -59.261821) (xy 12.679034 -59.128959) (xy 12.737685 -58.999207)
			(xy 12.803583 -58.872981) (xy 12.876517 -58.750685) (xy 12.956254 -58.632712) (xy 13.042536 -58.519439)
			(xy 13.135089 -58.411228) (xy 13.233616 -58.308427) (xy 13.337801 -58.211365) (xy 13.44731 -58.120353)
			(xy 13.561793 -58.035681) (xy 13.680883 -57.957623) (xy 13.804198 -57.886427) (xy 13.931344 -57.822321)
			(xy 14.061913 -57.765512) (xy 14.195487 -57.71618) (xy 14.331638 -57.674484) (xy 14.469929 -57.640558)
			(xy 14.609919 -57.61451) (xy 14.751158 -57.596424) (xy 14.893194 -57.586357) (xy 15.035572 -57.584342)
			(xy 15.177836 -57.590385) (xy 15.31953 -57.604467) (xy 15.4602 -57.626543) (xy 15.599397 -57.656543)
			(xy 15.736673 -57.694369) (xy 15.871589 -57.739901) (xy 16.003713 -57.792992) (xy 16.132622 -57.853474)
			(xy 16.257903 -57.921152) (xy 16.379154 -57.995809) (xy 16.495987 -58.077207) (xy 16.608028 -58.165084)
			(xy 16.714918 -58.259159) (xy 16.816315 -58.359131) (xy 16.871434 -58.42) (xy 40.838131 -58.42) (xy 40.842106 -58.309941)
			(xy 40.854014 -58.200455) (xy 40.87379 -58.092114) (xy 40.901333 -57.985483) (xy 40.936498 -57.881117)
			(xy 40.979102 -57.77956) (xy 41.028923 -57.681343) (xy 41.085702 -57.586976) (xy 41.149141 -57.496952)
			(xy 41.218912 -57.411741) (xy 41.294649 -57.331786) (xy 41.375958 -57.257505) (xy 41.462415 -57.189285)
			(xy 41.553569 -57.12748) (xy 41.648946 -57.072415) (xy 41.748047 -57.024375) (xy 41.850356 -56.983611)
			(xy 41.95534 -56.950336) (xy 42.062451 -56.924723) (xy 42.171131 -56.906906) (xy 42.280814 -56.896977)
			(xy 42.390927 -56.894989) (xy 42.500897 -56.900951) (xy 42.61015 -56.914833) (xy 42.718116 -56.936563)
			(xy 42.824233 -56.966026) (xy 42.927947 -57.003069) (xy 43.028718 -57.0475) (xy 43.12602 -57.099087)
			(xy 43.219346 -57.157559) (xy 43.308209 -57.222614) (xy 43.392147 -57.293912) (xy 43.470722 -57.37108)
			(xy 43.543523 -57.453717) (xy 43.610171 -57.541391) (xy 43.67032 -57.633647) (xy 43.723654 -57.730002)
			(xy 43.769897 -57.829954) (xy 43.808807 -57.932982) (xy 43.840181 -58.03855) (xy 43.863856 -58.146106)
			(xy 43.879708 -58.25509) (xy 43.887655 -58.364934) (xy 43.888152 -58.42) (xy 60.396131 -58.42) (xy 60.400106 -58.309941)
			(xy 60.412014 -58.200455) (xy 60.43179 -58.092114) (xy 60.459333 -57.985483) (xy 60.494498 -57.881117)
			(xy 60.537102 -57.77956) (xy 60.586923 -57.681343) (xy 60.643702 -57.586976) (xy 60.707141 -57.496952)
			(xy 60.776912 -57.411741) (xy 60.852649 -57.331786) (xy 60.933958 -57.257505) (xy 61.020415 -57.189285)
			(xy 61.111569 -57.12748) (xy 61.206946 -57.072415) (xy 61.306047 -57.024375) (xy 61.408356 -56.983611)
			(xy 61.51334 -56.950336) (xy 61.620451 -56.924723) (xy 61.729131 -56.906906) (xy 61.838814 -56.896977)
			(xy 61.948927 -56.894989) (xy 62.058897 -56.900951) (xy 62.16815 -56.914833) (xy 62.276116 -56.936563)
			(xy 62.382233 -56.966026) (xy 62.485947 -57.003069) (xy 62.586718 -57.0475) (xy 62.68402 -57.099087)
			(xy 62.777346 -57.157559) (xy 62.866209 -57.222614) (xy 62.950147 -57.293912) (xy 63.028722 -57.37108)
			(xy 63.101523 -57.453717) (xy 63.168171 -57.541391) (xy 63.22832 -57.633647) (xy 63.281654 -57.730002)
			(xy 63.327897 -57.829954) (xy 63.366807 -57.932982) (xy 63.398181 -58.03855) (xy 63.421856 -58.146106)
			(xy 63.437708 -58.25509) (xy 63.445655 -58.364934) (xy 63.446152 -58.42) (xy 63.445655 -58.475066)
			(xy 63.437708 -58.58491) (xy 63.421856 -58.693894) (xy 63.398181 -58.80145) (xy 63.366807 -58.907018)
			(xy 63.327897 -59.010046) (xy 63.281654 -59.109998) (xy 63.22832 -59.206353) (xy 63.168171 -59.298609)
			(xy 63.101523 -59.386283) (xy 63.028722 -59.46892) (xy 62.950147 -59.546088) (xy 62.866209 -59.617386)
			(xy 62.777346 -59.682441) (xy 62.68402 -59.740913) (xy 62.586718 -59.7925) (xy 62.485947 -59.836931)
			(xy 62.382233 -59.873974) (xy 62.276116 -59.903437) (xy 62.16815 -59.925167) (xy 62.058897 -59.939049)
			(xy 61.948927 -59.945011) (xy 61.838814 -59.943023) (xy 61.729131 -59.933094) (xy 61.620451 -59.915277)
			(xy 61.51334 -59.889664) (xy 61.408356 -59.856389) (xy 61.306047 -59.815625) (xy 61.206946 -59.767585)
			(xy 61.111569 -59.71252) (xy 61.020415 -59.650715) (xy 60.933958 -59.582495) (xy 60.852649 -59.508214)
			(xy 60.776912 -59.428259) (xy 60.707141 -59.343048) (xy 60.643702 -59.253024) (xy 60.586923 -59.158657)
			(xy 60.537102 -59.06044) (xy 60.494498 -58.958883) (xy 60.459333 -58.854517) (xy 60.43179 -58.747886)
			(xy 60.412014 -58.639545) (xy 60.400106 -58.530059) (xy 60.396131 -58.42) (xy 43.888152 -58.42) (xy 43.887655 -58.475066)
			(xy 43.879708 -58.58491) (xy 43.863856 -58.693894) (xy 43.840181 -58.80145) (xy 43.808807 -58.907018)
			(xy 43.769897 -59.010046) (xy 43.723654 -59.109998) (xy 43.67032 -59.206353) (xy 43.610171 -59.298609)
			(xy 43.543523 -59.386283) (xy 43.470722 -59.46892) (xy 43.392147 -59.546088) (xy 43.308209 -59.617386)
			(xy 43.219346 -59.682441) (xy 43.12602 -59.740913) (xy 43.028718 -59.7925) (xy 42.927947 -59.836931)
			(xy 42.824233 -59.873974) (xy 42.718116 -59.903437) (xy 42.61015 -59.925167) (xy 42.500897 -59.939049)
			(xy 42.390927 -59.945011) (xy 42.280814 -59.943023) (xy 42.171131 -59.933094) (xy 42.062451 -59.915277)
			(xy 41.95534 -59.889664) (xy 41.850356 -59.856389) (xy 41.748047 -59.815625) (xy 41.648946 -59.767585)
			(xy 41.553569 -59.71252) (xy 41.462415 -59.650715) (xy 41.375958 -59.582495) (xy 41.294649 -59.508214)
			(xy 41.218912 -59.428259) (xy 41.149141 -59.343048) (xy 41.085702 -59.253024) (xy 41.028923 -59.158657)
			(xy 40.979102 -59.06044) (xy 40.936498 -58.958883) (xy 40.901333 -58.854517) (xy 40.87379 -58.747886)
			(xy 40.854014 -58.639545) (xy 40.842106 -58.530059) (xy 40.838131 -58.42) (xy 16.871434 -58.42) (xy 16.911893 -58.464679)
			(xy 17.001347 -58.575465) (xy 17.084389 -58.691134) (xy 17.160755 -58.811317) (xy 17.230199 -58.935627)
			(xy 17.292499 -59.063668) (xy 17.347455 -59.195027) (xy 17.394892 -59.329286) (xy 17.434656 -59.466013)
			(xy 17.466622 -59.604771) (xy 17.490687 -59.745115) (xy 17.506773 -59.886596) (xy 17.514828 -60.02876)
			(xy 17.515332 -60.099956) (xy 17.514828 -60.171152) (xy 17.506773 -60.313316) (xy 17.490687 -60.454797)
			(xy 17.466622 -60.595141) (xy 17.434656 -60.733899) (xy 17.394892 -60.870626) (xy 17.347455 -61.004885)
			(xy 17.292499 -61.136244) (xy 17.230199 -61.264285) (xy 17.160755 -61.388595) (xy 17.084389 -61.508778)
			(xy 17.001347 -61.624447) (xy 16.911893 -61.735233) (xy 16.816315 -61.840781) (xy 16.714918 -61.940753)
			(xy 16.608028 -62.034828) (xy 16.495987 -62.122705) (xy 16.379154 -62.204103) (xy 16.257903 -62.27876)
			(xy 16.132622 -62.346438) (xy 16.055974 -62.3824) (xy 111.565944 -62.3824) (xy 111.565944 -62.381892)
			(xy 111.566546 -62.33556) (xy 111.576218 -62.243402) (xy 111.595414 -62.152748) (xy 111.623928 -62.064579)
			(xy 111.642144 -62.021974) (xy 111.645952 -62.012032) (xy 111.645952 -61.990768) (xy 111.642144 -61.980826)
			(xy 111.623902 -61.938162) (xy 111.595357 -61.849871) (xy 111.576163 -61.759086) (xy 111.566529 -61.666796)
			(xy 111.565944 -61.6204) (xy 111.566522 -61.574004) (xy 111.576168 -61.481716) (xy 111.595365 -61.390932)
			(xy 111.623905 -61.302639) (xy 111.642144 -61.259974) (xy 111.645952 -61.250032) (xy 111.645952 -61.228768)
			(xy 111.642144 -61.218826) (xy 111.623902 -61.176162) (xy 111.595357 -61.087871) (xy 111.576163 -60.997086)
			(xy 111.566529 -60.904796) (xy 111.565944 -60.8584) (xy 111.566522 -60.812004) (xy 111.576168 -60.719716)
			(xy 111.595365 -60.628932) (xy 111.623905 -60.540639) (xy 111.642144 -60.497974) (xy 111.645952 -60.488032)
			(xy 111.645952 -60.466768) (xy 111.642144 -60.456826) (xy 111.623902 -60.414162) (xy 111.595357 -60.325871)
			(xy 111.576163 -60.235086) (xy 111.566529 -60.142796) (xy 111.565944 -60.0964) (xy 111.566522 -60.050004)
			(xy 111.576168 -59.957716) (xy 111.595365 -59.866932) (xy 111.623905 -59.778639) (xy 111.642144 -59.735974)
			(xy 111.645952 -59.726032) (xy 111.645952 -59.704768) (xy 111.642144 -59.694826) (xy 111.623919 -59.652224)
			(xy 111.595403 -59.564056) (xy 111.576211 -59.4734) (xy 111.566552 -59.38124) (xy 111.565944 -59.334908)
			(xy 111.565944 -59.3344) (xy 111.566467 -59.293299) (xy 111.574051 -59.211447) (xy 111.589155 -59.130645)
			(xy 111.61165 -59.05158) (xy 111.641344 -58.974929) (xy 111.677983 -58.901344) (xy 111.721256 -58.831453)
			(xy 111.770792 -58.765854) (xy 111.82617 -58.705104) (xy 111.886917 -58.649723) (xy 111.952514 -58.600183)
			(xy 112.022402 -58.556907) (xy 112.095985 -58.520263) (xy 112.172635 -58.490565) (xy 112.251698 -58.468066)
			(xy 112.3325 -58.452958) (xy 112.414351 -58.445369) (xy 112.455452 -58.444892) (xy 112.45596 -58.444892)
			(xy 112.502291 -58.445515) (xy 112.594449 -58.455181) (xy 112.685103 -58.474372) (xy 112.773272 -58.502879)
			(xy 112.815878 -58.521092) (xy 112.82582 -58.524898) (xy 112.847084 -58.524898) (xy 112.857026 -58.521092)
			(xy 112.899695 -58.502863) (xy 112.987985 -58.474315) (xy 113.078768 -58.455117) (xy 113.171056 -58.445479)
			(xy 113.217452 -58.444892) (xy 113.263847 -58.445492) (xy 113.356135 -58.455132) (xy 113.446919 -58.474323)
			(xy 113.535213 -58.502856) (xy 113.577878 -58.521092) (xy 113.58782 -58.524898) (xy 113.609084 -58.524898)
			(xy 113.619026 -58.521092) (xy 113.661695 -58.502863) (xy 113.749985 -58.474315) (xy 113.840768 -58.455117)
			(xy 113.933056 -58.445479) (xy 113.979452 -58.444892) (xy 114.025847 -58.445492) (xy 114.118135 -58.455132)
			(xy 114.208919 -58.474323) (xy 114.297213 -58.502856) (xy 114.339878 -58.521092) (xy 114.34982 -58.524898)
			(xy 114.371084 -58.524898) (xy 114.381026 -58.521092) (xy 114.423695 -58.502863) (xy 114.511985 -58.474315)
			(xy 114.602768 -58.455117) (xy 114.695056 -58.445479) (xy 114.741452 -58.444892) (xy 114.787847 -58.445492)
			(xy 114.880135 -58.455132) (xy 114.970919 -58.474323) (xy 115.059213 -58.502856) (xy 115.101878 -58.521092)
			(xy 115.11182 -58.524898) (xy 115.133084 -58.524898) (xy 115.143026 -58.521092) (xy 115.185635 -58.502886)
			(xy 115.2738 -58.474364) (xy 115.364454 -58.455167) (xy 115.456612 -58.445503) (xy 115.502944 -58.444892)
			(xy 115.503452 -58.444892) (xy 115.544554 -58.445398) (xy 115.626409 -58.452979) (xy 115.707215 -58.46808)
			(xy 115.786282 -58.490573) (xy 115.862937 -58.520265) (xy 115.936525 -58.556904) (xy 116.006418 -58.600177)
			(xy 116.072021 -58.649714) (xy 116.132772 -58.705094) (xy 116.188155 -58.765842) (xy 116.237696 -58.831442)
			(xy 116.280972 -58.901333) (xy 116.317615 -58.974919) (xy 116.347312 -59.051572) (xy 116.369809 -59.130639)
			(xy 116.384915 -59.211444) (xy 116.3925 -59.293298) (xy 116.39296 -59.3344) (xy 116.39296 -59.334908)
			(xy 116.392358 -59.38124) (xy 116.382686 -59.473398) (xy 116.363489 -59.564052) (xy 116.334976 -59.652221)
			(xy 116.31676 -59.694826) (xy 116.312952 -59.704768) (xy 116.312952 -59.726032) (xy 116.31676 -59.735974)
			(xy 116.335002 -59.778637) (xy 116.363547 -59.866929) (xy 116.382741 -59.957714) (xy 116.392375 -60.050004)
			(xy 116.39296 -60.0964) (xy 116.392381 -60.142796) (xy 116.382736 -60.235084) (xy 116.363539 -60.325868)
			(xy 116.334999 -60.414161) (xy 116.31676 -60.456826) (xy 116.312952 -60.466768) (xy 116.312952 -60.488032)
			(xy 116.31676 -60.497974) (xy 116.335002 -60.540637) (xy 116.363547 -60.628929) (xy 116.382741 -60.719714)
			(xy 116.392375 -60.812004) (xy 116.39296 -60.8584) (xy 116.392381 -60.904796) (xy 116.382736 -60.997084)
			(xy 116.363539 -61.087868) (xy 116.334999 -61.176161) (xy 116.31676 -61.218826) (xy 116.312952 -61.228768)
			(xy 116.312952 -61.250032) (xy 116.31676 -61.259974) (xy 116.335002 -61.302637) (xy 116.363547 -61.390929)
			(xy 116.382741 -61.481714) (xy 116.392375 -61.574004) (xy 116.39296 -61.6204) (xy 116.392381 -61.666796)
			(xy 116.382736 -61.759084) (xy 116.363539 -61.849868) (xy 116.334999 -61.938161) (xy 116.31676 -61.980826)
			(xy 116.312952 -61.990768) (xy 116.312952 -62.012032) (xy 116.31676 -62.021974) (xy 116.334985 -62.064576)
			(xy 116.363501 -62.152744) (xy 116.382693 -62.243399) (xy 116.392352 -62.33556) (xy 116.39296 -62.381892)
			(xy 116.39296 -62.3824) (xy 116.392548 -62.423505) (xy 116.384962 -62.505363) (xy 116.369856 -62.586172)
			(xy 116.347357 -62.665243) (xy 116.317659 -62.7419) (xy 116.281014 -62.81549) (xy 116.237735 -62.885385)
			(xy 116.188192 -62.950988) (xy 116.132806 -63.01174) (xy 116.072051 -63.067122) (xy 116.006446 -63.116662)
			(xy 115.936548 -63.159938) (xy 115.862956 -63.196579) (xy 115.786297 -63.226273) (xy 115.707226 -63.248767)
			(xy 115.626415 -63.263869) (xy 115.544557 -63.27145) (xy 115.503452 -63.271908) (xy 115.502944 -63.271908)
			(xy 115.456613 -63.271284) (xy 115.364455 -63.261618) (xy 115.273801 -63.242427) (xy 115.185632 -63.213921)
			(xy 115.143026 -63.195708) (xy 115.133084 -63.191902) (xy 115.11182 -63.191902) (xy 115.101878 -63.195708)
			(xy 115.059209 -63.213936) (xy 114.970919 -63.242484) (xy 114.880136 -63.261682) (xy 114.787847 -63.27132)
			(xy 114.741452 -63.271908) (xy 114.695057 -63.271307) (xy 114.602769 -63.261667) (xy 114.511985 -63.242476)
			(xy 114.423691 -63.213943) (xy 114.381026 -63.195708) (xy 114.371084 -63.191902) (xy 114.34982 -63.191902)
			(xy 114.339878 -63.195708) (xy 114.297209 -63.213936) (xy 114.208919 -63.242484) (xy 114.118136 -63.261682)
			(xy 114.025847 -63.27132) (xy 113.979452 -63.271908) (xy 113.933057 -63.271307) (xy 113.840769 -63.261667)
			(xy 113.749985 -63.242476) (xy 113.661691 -63.213943) (xy 113.619026 -63.195708) (xy 113.609084 -63.191902)
			(xy 113.58782 -63.191902) (xy 113.577878 -63.195708) (xy 113.535209 -63.213936) (xy 113.446919 -63.242484)
			(xy 113.356136 -63.261682) (xy 113.263847 -63.27132) (xy 113.217452 -63.271908) (xy 113.171057 -63.271307)
			(xy 113.078769 -63.261667) (xy 112.987985 -63.242476) (xy 112.899691 -63.213943) (xy 112.857026 -63.195708)
			(xy 112.847084 -63.191902) (xy 112.82582 -63.191902) (xy 112.815878 -63.195708) (xy 112.773268 -63.213913)
			(xy 112.685103 -63.242435) (xy 112.59445 -63.261633) (xy 112.502292 -63.271297) (xy 112.45596 -63.271908)
			(xy 112.455452 -63.271908) (xy 112.414349 -63.271479) (xy 112.332493 -63.26389) (xy 112.251687 -63.248781)
			(xy 112.17262 -63.22628) (xy 112.095965 -63.196581) (xy 112.022379 -63.159935) (xy 111.952487 -63.116657)
			(xy 111.886886 -63.067114) (xy 111.826136 -63.01173) (xy 111.770755 -62.950977) (xy 111.721216 -62.885374)
			(xy 111.677941 -62.815479) (xy 111.6413 -62.741891) (xy 111.611604 -62.665235) (xy 111.589108 -62.586166)
			(xy 111.574003 -62.505359) (xy 111.566419 -62.423503) (xy 111.565944 -62.3824) (xy 16.055974 -62.3824)
			(xy 16.003713 -62.40692) (xy 15.871589 -62.460011) (xy 15.736673 -62.505543) (xy 15.599397 -62.543369)
			(xy 15.4602 -62.573369) (xy 15.31953 -62.595445) (xy 15.177836 -62.609527) (xy 15.035572 -62.61557)
			(xy 14.893194 -62.613555) (xy 14.751158 -62.603488) (xy 14.609919 -62.585402) (xy 14.469929 -62.559354)
			(xy 14.331638 -62.525428) (xy 14.195487 -62.483732) (xy 14.061913 -62.4344) (xy 13.931344 -62.377591)
			(xy 13.804198 -62.313485) (xy 13.680883 -62.242289) (xy 13.561793 -62.164231) (xy 13.44731 -62.079559)
			(xy 13.337801 -61.988547) (xy 13.233616 -61.891485) (xy 13.135089 -61.788684) (xy 13.042536 -61.680473)
			(xy 12.956254 -61.5672) (xy 12.876517 -61.449227) (xy 12.803583 -61.326931) (xy 12.737685 -61.200705)
			(xy 12.679034 -61.070953) (xy 12.627817 -60.938091) (xy 12.584199 -60.802544) (xy 12.548319 -60.664746)
			(xy 12.520292 -60.525139) (xy 12.500209 -60.384171) (xy 12.488134 -60.242291) (xy 12.484104 -60.099956)
			(xy 0.509016 -60.099956) (xy 0.509016 -67.428561) (xy 111.362994 -67.428561) (xy 111.362994 -67.343839)
			(xy 111.371047 -67.259502) (xy 111.387081 -67.176312) (xy 111.410949 -67.095022) (xy 111.442437 -67.01637)
			(xy 111.481259 -66.941067) (xy 111.527062 -66.869795) (xy 111.579433 -66.803199) (xy 111.637898 -66.741884)
			(xy 111.701926 -66.686403) (xy 111.770938 -66.63726) (xy 111.844308 -66.5949) (xy 111.921373 -66.559705)
			(xy 112.001435 -66.531996) (xy 112.083768 -66.512022) (xy 112.167627 -66.499965) (xy 112.252252 -66.495934)
			(xy 112.336877 -66.499965) (xy 112.420736 -66.512022) (xy 112.503069 -66.531996) (xy 112.583131 -66.559705)
			(xy 112.660196 -66.5949) (xy 112.733566 -66.63726) (xy 112.802578 -66.686403) (xy 112.866606 -66.741884)
			(xy 112.925071 -66.803199) (xy 112.977442 -66.869795) (xy 113.023245 -66.941067) (xy 113.062067 -67.01637)
			(xy 113.093555 -67.095022) (xy 113.117423 -67.176312) (xy 113.133457 -67.259502) (xy 113.14151 -67.343839)
			(xy 113.142014 -67.3862) (xy 113.14151 -67.428561) (xy 113.133457 -67.512898) (xy 113.117423 -67.596088)
			(xy 113.093555 -67.677378) (xy 113.062067 -67.75603) (xy 113.023245 -67.831333) (xy 112.977442 -67.902605)
			(xy 112.925071 -67.969201) (xy 112.866606 -68.030516) (xy 112.802578 -68.085997) (xy 112.733566 -68.13514)
			(xy 112.660196 -68.1775) (xy 112.583131 -68.212695) (xy 112.503069 -68.240404) (xy 112.420736 -68.260378)
			(xy 112.336877 -68.272435) (xy 112.252252 -68.276467) (xy 112.167627 -68.272435) (xy 112.083768 -68.260378)
			(xy 112.001435 -68.240404) (xy 111.921373 -68.212695) (xy 111.844308 -68.1775) (xy 111.770938 -68.13514)
			(xy 111.701926 -68.085997) (xy 111.637898 -68.030516) (xy 111.579433 -67.969201) (xy 111.527062 -67.902605)
			(xy 111.481259 -67.831333) (xy 111.442437 -67.75603) (xy 111.410949 -67.677378) (xy 111.387081 -67.596088)
			(xy 111.371047 -67.512898) (xy 111.362994 -67.428561) (xy 0.509016 -67.428561) (xy 0.509016 -71.239888)
			(xy 41.345622 -71.239888) (xy 41.349604 -71.149938) (xy 41.361521 -71.060691) (xy 41.381279 -70.972847)
			(xy 41.408723 -70.887093) (xy 41.443639 -70.8041) (xy 41.485753 -70.724518) (xy 41.534736 -70.648969)
			(xy 41.590204 -70.578045) (xy 41.651724 -70.5123) (xy 41.718813 -70.45225) (xy 41.790947 -70.398365)
			(xy 41.867561 -70.351065) (xy 41.948055 -70.310722) (xy 42.0318 -70.27765) (xy 42.118141 -70.25211)
			(xy 42.2064 -70.2343) (xy 42.295889 -70.22436) (xy 42.385905 -70.222369) (xy 42.475746 -70.22834)
			(xy 42.564707 -70.242229) (xy 42.652092 -70.263925) (xy 42.737218 -70.29326) (xy 42.819418 -70.330003)
			(xy 42.898049 -70.373867) (xy 42.972496 -70.424509) (xy 43.042176 -70.481533) (xy 43.106543 -70.544492)
			(xy 43.165094 -70.612893) (xy 43.217371 -70.686201) (xy 43.262964 -70.763843) (xy 43.301517 -70.84521)
			(xy 43.332728 -70.929666) (xy 43.356352 -71.01655) (xy 43.372205 -71.105182) (xy 43.380162 -71.194869)
			(xy 43.38066 -71.239888) (xy 60.903622 -71.239888) (xy 60.907604 -71.149938) (xy 60.919521 -71.060691)
			(xy 60.939279 -70.972847) (xy 60.966723 -70.887093) (xy 61.001639 -70.8041) (xy 61.043753 -70.724518)
			(xy 61.092736 -70.648969) (xy 61.148204 -70.578045) (xy 61.209724 -70.5123) (xy 61.276813 -70.45225)
			(xy 61.348947 -70.398365) (xy 61.425561 -70.351065) (xy 61.506055 -70.310722) (xy 61.5898 -70.27765)
			(xy 61.676141 -70.25211) (xy 61.7644 -70.2343) (xy 61.853889 -70.22436) (xy 61.943905 -70.222369)
			(xy 62.033746 -70.22834) (xy 62.122707 -70.242229) (xy 62.210092 -70.263925) (xy 62.295218 -70.29326)
			(xy 62.377418 -70.330003) (xy 62.456049 -70.373867) (xy 62.530496 -70.424509) (xy 62.600176 -70.481533)
			(xy 62.664543 -70.544492) (xy 62.723094 -70.612893) (xy 62.775371 -70.686201) (xy 62.820964 -70.763843)
			(xy 62.859517 -70.84521) (xy 62.890728 -70.929666) (xy 62.914352 -71.01655) (xy 62.930205 -71.105182)
			(xy 62.938162 -71.194869) (xy 62.93866 -71.239888) (xy 62.938162 -71.284907) (xy 62.930205 -71.374594)
			(xy 62.914352 -71.463226) (xy 62.890728 -71.55011) (xy 62.859517 -71.634566) (xy 62.820964 -71.715933)
			(xy 62.775371 -71.793575) (xy 62.723094 -71.866883) (xy 62.664543 -71.935284) (xy 62.600176 -71.998243)
			(xy 62.530496 -72.055267) (xy 62.456049 -72.105909) (xy 62.377418 -72.149773) (xy 62.295218 -72.186516)
			(xy 62.210092 -72.215851) (xy 62.122707 -72.237547) (xy 62.033746 -72.251436) (xy 61.943905 -72.257407)
			(xy 61.853889 -72.255416) (xy 61.7644 -72.245476) (xy 61.676141 -72.227666) (xy 61.5898 -72.202126)
			(xy 61.506055 -72.169054) (xy 61.425561 -72.128711) (xy 61.348947 -72.081411) (xy 61.276813 -72.027526)
			(xy 61.209724 -71.967476) (xy 61.148204 -71.901731) (xy 61.092736 -71.830807) (xy 61.043753 -71.755258)
			(xy 61.001639 -71.675676) (xy 60.966723 -71.592683) (xy 60.939279 -71.506929) (xy 60.919521 -71.419085)
			(xy 60.907604 -71.329838) (xy 60.903622 -71.239888) (xy 43.38066 -71.239888) (xy 43.380162 -71.284907)
			(xy 43.372205 -71.374594) (xy 43.356352 -71.463226) (xy 43.332728 -71.55011) (xy 43.301517 -71.634566)
			(xy 43.262964 -71.715933) (xy 43.217371 -71.793575) (xy 43.165094 -71.866883) (xy 43.106543 -71.935284)
			(xy 43.042176 -71.998243) (xy 42.972496 -72.055267) (xy 42.898049 -72.105909) (xy 42.819418 -72.149773)
			(xy 42.737218 -72.186516) (xy 42.652092 -72.215851) (xy 42.564707 -72.237547) (xy 42.475746 -72.251436)
			(xy 42.385905 -72.257407) (xy 42.295889 -72.255416) (xy 42.2064 -72.245476) (xy 42.118141 -72.227666)
			(xy 42.0318 -72.202126) (xy 41.948055 -72.169054) (xy 41.867561 -72.128711) (xy 41.790947 -72.081411)
			(xy 41.718813 -72.027526) (xy 41.651724 -71.967476) (xy 41.590204 -71.901731) (xy 41.534736 -71.830807)
			(xy 41.485753 -71.755258) (xy 41.443639 -71.675676) (xy 41.408723 -71.592683) (xy 41.381279 -71.506929)
			(xy 41.361521 -71.419085) (xy 41.349604 -71.329838) (xy 41.345622 -71.239888) (xy 0.509016 -71.239888)
			(xy 0.509016 -73.66) (xy 111.565944 -73.66) (xy 111.565944 -73.659492) (xy 111.566546 -73.61316)
			(xy 111.576218 -73.521002) (xy 111.595414 -73.430348) (xy 111.623928 -73.342179) (xy 111.642144 -73.299574)
			(xy 111.645952 -73.289632) (xy 111.645952 -73.268368) (xy 111.642144 -73.258426) (xy 111.623902 -73.215762)
			(xy 111.595357 -73.127471) (xy 111.576163 -73.036686) (xy 111.566529 -72.944396) (xy 111.565944 -72.898)
			(xy 111.566522 -72.851604) (xy 111.576168 -72.759316) (xy 111.595365 -72.668532) (xy 111.623905 -72.580239)
			(xy 111.642144 -72.537574) (xy 111.645952 -72.527632) (xy 111.645952 -72.506368) (xy 111.642144 -72.496426)
			(xy 111.623902 -72.453762) (xy 111.595357 -72.365471) (xy 111.576163 -72.274686) (xy 111.566529 -72.182396)
			(xy 111.565944 -72.136) (xy 111.566522 -72.089604) (xy 111.576168 -71.997316) (xy 111.595365 -71.906532)
			(xy 111.623905 -71.818239) (xy 111.642144 -71.775574) (xy 111.645952 -71.765632) (xy 111.645952 -71.744368)
			(xy 111.642144 -71.734426) (xy 111.623902 -71.691762) (xy 111.595357 -71.603471) (xy 111.576163 -71.512686)
			(xy 111.566529 -71.420396) (xy 111.565944 -71.374) (xy 111.566522 -71.327604) (xy 111.576168 -71.235316)
			(xy 111.595365 -71.144532) (xy 111.623905 -71.056239) (xy 111.642144 -71.013574) (xy 111.645952 -71.003632)
			(xy 111.645952 -70.982368) (xy 111.642144 -70.972426) (xy 111.623919 -70.929824) (xy 111.595403 -70.841656)
			(xy 111.576211 -70.751) (xy 111.566552 -70.65884) (xy 111.565944 -70.612508) (xy 111.565944 -70.612)
			(xy 111.566467 -70.570899) (xy 111.574051 -70.489047) (xy 111.589155 -70.408245) (xy 111.61165 -70.32918)
			(xy 111.641344 -70.252529) (xy 111.677983 -70.178944) (xy 111.721256 -70.109053) (xy 111.770792 -70.043454)
			(xy 111.82617 -69.982704) (xy 111.886917 -69.927323) (xy 111.952514 -69.877783) (xy 112.022402 -69.834507)
			(xy 112.095985 -69.797863) (xy 112.172635 -69.768165) (xy 112.251698 -69.745666) (xy 112.3325 -69.730558)
			(xy 112.414351 -69.722969) (xy 112.455452 -69.722492) (xy 112.45596 -69.722492) (xy 112.502291 -69.723115)
			(xy 112.594449 -69.732781) (xy 112.685103 -69.751972) (xy 112.773272 -69.780479) (xy 112.815878 -69.798692)
			(xy 112.82582 -69.802498) (xy 112.847084 -69.802498) (xy 112.857026 -69.798692) (xy 112.899695 -69.780463)
			(xy 112.987985 -69.751915) (xy 113.078768 -69.732717) (xy 113.171056 -69.723079) (xy 113.217452 -69.722492)
			(xy 113.263847 -69.723092) (xy 113.356135 -69.732732) (xy 113.446919 -69.751923) (xy 113.535213 -69.780456)
			(xy 113.577878 -69.798692) (xy 113.58782 -69.802498) (xy 113.609084 -69.802498) (xy 113.619026 -69.798692)
			(xy 113.661695 -69.780463) (xy 113.749985 -69.751915) (xy 113.840768 -69.732717) (xy 113.933056 -69.723079)
			(xy 113.979452 -69.722492) (xy 114.025847 -69.723092) (xy 114.118135 -69.732732) (xy 114.208919 -69.751923)
			(xy 114.297213 -69.780456) (xy 114.339878 -69.798692) (xy 114.34982 -69.802498) (xy 114.371084 -69.802498)
			(xy 114.381026 -69.798692) (xy 114.423695 -69.780463) (xy 114.511985 -69.751915) (xy 114.602768 -69.732717)
			(xy 114.695056 -69.723079) (xy 114.741452 -69.722492) (xy 114.787847 -69.723092) (xy 114.880135 -69.732732)
			(xy 114.970919 -69.751923) (xy 115.059213 -69.780456) (xy 115.101878 -69.798692) (xy 115.11182 -69.802498)
			(xy 115.133084 -69.802498) (xy 115.143026 -69.798692) (xy 115.185635 -69.780486) (xy 115.2738 -69.751964)
			(xy 115.364454 -69.732767) (xy 115.456612 -69.723103) (xy 115.502944 -69.722492) (xy 115.503452 -69.722492)
			(xy 115.544554 -69.722998) (xy 115.626409 -69.730579) (xy 115.707215 -69.74568) (xy 115.786282 -69.768173)
			(xy 115.862937 -69.797865) (xy 115.936525 -69.834504) (xy 116.006418 -69.877777) (xy 116.072021 -69.927314)
			(xy 116.132772 -69.982694) (xy 116.188155 -70.043442) (xy 116.237696 -70.109042) (xy 116.280972 -70.178933)
			(xy 116.317615 -70.252519) (xy 116.347312 -70.329172) (xy 116.369809 -70.408239) (xy 116.384915 -70.489044)
			(xy 116.3925 -70.570898) (xy 116.39296 -70.612) (xy 116.39296 -70.612508) (xy 116.392358 -70.65884)
			(xy 116.382686 -70.750998) (xy 116.363489 -70.841652) (xy 116.334976 -70.929821) (xy 116.31676 -70.972426)
			(xy 116.312952 -70.982368) (xy 116.312952 -71.003632) (xy 116.31676 -71.013574) (xy 116.335002 -71.056237)
			(xy 116.363547 -71.144529) (xy 116.382741 -71.235314) (xy 116.392375 -71.327604) (xy 116.39296 -71.374)
			(xy 116.392381 -71.420396) (xy 116.382736 -71.512684) (xy 116.363539 -71.603468) (xy 116.334999 -71.691761)
			(xy 116.31676 -71.734426) (xy 116.312952 -71.744368) (xy 116.312952 -71.765632) (xy 116.31676 -71.775574)
			(xy 116.335002 -71.818237) (xy 116.363547 -71.906529) (xy 116.382741 -71.997314) (xy 116.392375 -72.089604)
			(xy 116.39296 -72.136) (xy 116.392381 -72.182396) (xy 116.382736 -72.274684) (xy 116.363539 -72.365468)
			(xy 116.334999 -72.453761) (xy 116.31676 -72.496426) (xy 116.312952 -72.506368) (xy 116.312952 -72.527632)
			(xy 116.31676 -72.537574) (xy 116.335002 -72.580237) (xy 116.363547 -72.668529) (xy 116.382741 -72.759314)
			(xy 116.392375 -72.851604) (xy 116.39296 -72.898) (xy 116.392381 -72.944396) (xy 116.382736 -73.036684)
			(xy 116.363539 -73.127468) (xy 116.334999 -73.215761) (xy 116.31676 -73.258426) (xy 116.312952 -73.268368)
			(xy 116.312952 -73.289632) (xy 116.31676 -73.299574) (xy 116.334985 -73.342176) (xy 116.363501 -73.430344)
			(xy 116.382693 -73.520999) (xy 116.392352 -73.61316) (xy 116.39296 -73.659492) (xy 116.39296 -73.66)
			(xy 116.392548 -73.701105) (xy 116.384962 -73.782963) (xy 116.369856 -73.863772) (xy 116.347357 -73.942843)
			(xy 116.317659 -74.0195) (xy 116.281014 -74.09309) (xy 116.237735 -74.162985) (xy 116.188192 -74.228588)
			(xy 116.132806 -74.28934) (xy 116.072051 -74.344722) (xy 116.006446 -74.394262) (xy 115.936548 -74.437538)
			(xy 115.862956 -74.474179) (xy 115.786297 -74.503873) (xy 115.707226 -74.526367) (xy 115.626415 -74.541469)
			(xy 115.544557 -74.54905) (xy 115.503452 -74.549508) (xy 115.502944 -74.549508) (xy 115.456613 -74.548884)
			(xy 115.364455 -74.539218) (xy 115.273801 -74.520027) (xy 115.185632 -74.491521) (xy 115.143026 -74.473308)
			(xy 115.133084 -74.469502) (xy 115.11182 -74.469502) (xy 115.101878 -74.473308) (xy 115.059209 -74.491536)
			(xy 114.970919 -74.520084) (xy 114.880136 -74.539282) (xy 114.787847 -74.54892) (xy 114.741452 -74.549508)
			(xy 114.695057 -74.548907) (xy 114.602769 -74.539267) (xy 114.511985 -74.520076) (xy 114.423691 -74.491543)
			(xy 114.381026 -74.473308) (xy 114.371084 -74.469502) (xy 114.34982 -74.469502) (xy 114.339878 -74.473308)
			(xy 114.297209 -74.491536) (xy 114.208919 -74.520084) (xy 114.118136 -74.539282) (xy 114.025847 -74.54892)
			(xy 113.979452 -74.549508) (xy 113.933057 -74.548907) (xy 113.840769 -74.539267) (xy 113.749985 -74.520076)
			(xy 113.661691 -74.491543) (xy 113.619026 -74.473308) (xy 113.609084 -74.469502) (xy 113.58782 -74.469502)
			(xy 113.577878 -74.473308) (xy 113.535209 -74.491536) (xy 113.446919 -74.520084) (xy 113.356136 -74.539282)
			(xy 113.263847 -74.54892) (xy 113.217452 -74.549508) (xy 113.171057 -74.548907) (xy 113.078769 -74.539267)
			(xy 112.987985 -74.520076) (xy 112.899691 -74.491543) (xy 112.857026 -74.473308) (xy 112.847084 -74.469502)
			(xy 112.82582 -74.469502) (xy 112.815878 -74.473308) (xy 112.773268 -74.491513) (xy 112.685103 -74.520035)
			(xy 112.59445 -74.539233) (xy 112.502292 -74.548897) (xy 112.45596 -74.549508) (xy 112.455452 -74.549508)
			(xy 112.414349 -74.549079) (xy 112.332493 -74.54149) (xy 112.251687 -74.526381) (xy 112.17262 -74.50388)
			(xy 112.095965 -74.474181) (xy 112.022379 -74.437535) (xy 111.952487 -74.394257) (xy 111.886886 -74.344714)
			(xy 111.826136 -74.28933) (xy 111.770755 -74.228577) (xy 111.721216 -74.162974) (xy 111.677941 -74.093079)
			(xy 111.6413 -74.019491) (xy 111.611604 -73.942835) (xy 111.589108 -73.863766) (xy 111.574003 -73.782959)
			(xy 111.566419 -73.701103) (xy 111.565944 -73.66) (xy 0.509016 -73.66) (xy 0.509016 -78.74) (xy 40.838131 -78.74)
			(xy 40.842106 -78.629941) (xy 40.854014 -78.520455) (xy 40.87379 -78.412114) (xy 40.901333 -78.305483)
			(xy 40.936498 -78.201117) (xy 40.979102 -78.09956) (xy 41.028923 -78.001343) (xy 41.085702 -77.906976)
			(xy 41.149141 -77.816952) (xy 41.218912 -77.731741) (xy 41.294649 -77.651786) (xy 41.375958 -77.577505)
			(xy 41.462415 -77.509285) (xy 41.553569 -77.44748) (xy 41.648946 -77.392415) (xy 41.748047 -77.344375)
			(xy 41.850356 -77.303611) (xy 41.95534 -77.270336) (xy 42.062451 -77.244723) (xy 42.171131 -77.226906)
			(xy 42.280814 -77.216977) (xy 42.390927 -77.214989) (xy 42.500897 -77.220951) (xy 42.61015 -77.234833)
			(xy 42.718116 -77.256563) (xy 42.824233 -77.286026) (xy 42.927947 -77.323069) (xy 43.028718 -77.3675)
			(xy 43.12602 -77.419087) (xy 43.219346 -77.477559) (xy 43.308209 -77.542614) (xy 43.392147 -77.613912)
			(xy 43.470722 -77.69108) (xy 43.543523 -77.773717) (xy 43.610171 -77.861391) (xy 43.67032 -77.953647)
			(xy 43.723654 -78.050002) (xy 43.769897 -78.149954) (xy 43.808807 -78.252982) (xy 43.840181 -78.35855)
			(xy 43.863856 -78.466106) (xy 43.879708 -78.57509) (xy 43.887655 -78.684934) (xy 43.888152 -78.74)
			(xy 60.396131 -78.74) (xy 60.400106 -78.629941) (xy 60.412014 -78.520455) (xy 60.43179 -78.412114)
			(xy 60.459333 -78.305483) (xy 60.494498 -78.201117) (xy 60.537102 -78.09956) (xy 60.586923 -78.001343)
			(xy 60.643702 -77.906976) (xy 60.707141 -77.816952) (xy 60.776912 -77.731741) (xy 60.852649 -77.651786)
			(xy 60.933958 -77.577505) (xy 61.020415 -77.509285) (xy 61.111569 -77.44748) (xy 61.206946 -77.392415)
			(xy 61.306047 -77.344375) (xy 61.408356 -77.303611) (xy 61.51334 -77.270336) (xy 61.620451 -77.244723)
			(xy 61.729131 -77.226906) (xy 61.838814 -77.216977) (xy 61.948927 -77.214989) (xy 62.058897 -77.220951)
			(xy 62.16815 -77.234833) (xy 62.276116 -77.256563) (xy 62.382233 -77.286026) (xy 62.485947 -77.323069)
			(xy 62.586718 -77.3675) (xy 62.68402 -77.419087) (xy 62.777346 -77.477559) (xy 62.866209 -77.542614)
			(xy 62.950147 -77.613912) (xy 63.028722 -77.69108) (xy 63.101523 -77.773717) (xy 63.168171 -77.861391)
			(xy 63.22832 -77.953647) (xy 63.281654 -78.050002) (xy 63.327897 -78.149954) (xy 63.366807 -78.252982)
			(xy 63.398181 -78.35855) (xy 63.421856 -78.466106) (xy 63.437708 -78.57509) (xy 63.445655 -78.684934)
			(xy 63.445847 -78.706161) (xy 111.362994 -78.706161) (xy 111.362994 -78.621439) (xy 111.371047 -78.537102)
			(xy 111.387081 -78.453912) (xy 111.410949 -78.372622) (xy 111.442437 -78.29397) (xy 111.481259 -78.218667)
			(xy 111.527062 -78.147395) (xy 111.579433 -78.080799) (xy 111.637898 -78.019484) (xy 111.701926 -77.964003)
			(xy 111.770938 -77.91486) (xy 111.844308 -77.8725) (xy 111.921373 -77.837305) (xy 112.001435 -77.809596)
			(xy 112.083768 -77.789622) (xy 112.167627 -77.777565) (xy 112.252252 -77.773534) (xy 112.336877 -77.777565)
			(xy 112.420736 -77.789622) (xy 112.503069 -77.809596) (xy 112.583131 -77.837305) (xy 112.660196 -77.8725)
			(xy 112.733566 -77.91486) (xy 112.802578 -77.964003) (xy 112.866606 -78.019484) (xy 112.925071 -78.080799)
			(xy 112.977442 -78.147395) (xy 113.023245 -78.218667) (xy 113.062067 -78.29397) (xy 113.093555 -78.372622)
			(xy 113.117423 -78.453912) (xy 113.133457 -78.537102) (xy 113.14151 -78.621439) (xy 113.142014 -78.6638)
			(xy 113.14151 -78.706161) (xy 113.133457 -78.790498) (xy 113.117423 -78.873688) (xy 113.093555 -78.954978)
			(xy 113.062067 -79.03363) (xy 113.023245 -79.108933) (xy 112.977442 -79.180205) (xy 112.925071 -79.246801)
			(xy 112.866606 -79.308116) (xy 112.802578 -79.363597) (xy 112.733566 -79.41274) (xy 112.660196 -79.4551)
			(xy 112.583131 -79.490295) (xy 112.503069 -79.518004) (xy 112.420736 -79.537978) (xy 112.336877 -79.550035)
			(xy 112.252252 -79.554067) (xy 112.167627 -79.550035) (xy 112.083768 -79.537978) (xy 112.001435 -79.518004)
			(xy 111.921373 -79.490295) (xy 111.844308 -79.4551) (xy 111.770938 -79.41274) (xy 111.701926 -79.363597)
			(xy 111.637898 -79.308116) (xy 111.579433 -79.246801) (xy 111.527062 -79.180205) (xy 111.481259 -79.108933)
			(xy 111.442437 -79.03363) (xy 111.410949 -78.954978) (xy 111.387081 -78.873688) (xy 111.371047 -78.790498)
			(xy 111.362994 -78.706161) (xy 63.445847 -78.706161) (xy 63.446152 -78.74) (xy 63.445655 -78.795066)
			(xy 63.437708 -78.90491) (xy 63.421856 -79.013894) (xy 63.398181 -79.12145) (xy 63.366807 -79.227018)
			(xy 63.327897 -79.330046) (xy 63.281654 -79.429998) (xy 63.22832 -79.526353) (xy 63.168171 -79.618609)
			(xy 63.101523 -79.706283) (xy 63.028722 -79.78892) (xy 62.950147 -79.866088) (xy 62.930237 -79.883)
			(xy 122.3264 -79.883) (xy 122.3264 -13.081) (xy 122.326939 -13.047741) (xy 122.335625 -12.981791)
			(xy 122.352847 -12.91754) (xy 122.378311 -12.856089) (xy 122.411582 -12.798488) (xy 122.452088 -12.745724)
			(xy 122.475244 -12.721844) (xy 123.110244 -12.086844) (xy 123.134129 -12.063692) (xy 123.186889 -12.023179)
			(xy 123.244488 -11.989903) (xy 123.305939 -11.964434) (xy 123.37019 -11.947209) (xy 123.43614 -11.938521)
			(xy 123.4694 -11.938) (xy 156.980382 -11.938) (xy 157.013641 -11.938551) (xy 157.07959 -11.947234)
			(xy 157.143841 -11.964454) (xy 157.205292 -11.989916) (xy 157.262894 -12.023184) (xy 157.315658 -12.063689)
			(xy 157.339538 -12.086844) (xy 161.039556 -15.786862) (xy 161.062716 -15.810739) (xy 161.103229 -15.863501)
			(xy 161.136504 -15.921101) (xy 161.161971 -15.982554) (xy 161.179195 -16.046806) (xy 161.18788 -16.112758)
			(xy 161.1884 -16.146018) (xy 161.1884 -22.560114) (xy 205.177635 -22.560114) (xy 205.177635 -22.389758)
			(xy 205.18562 -22.21959) (xy 205.201572 -22.049983) (xy 205.225457 -21.881311) (xy 205.257221 -21.713943)
			(xy 205.296796 -21.548248) (xy 205.344093 -21.38459) (xy 205.39901 -21.223329) (xy 205.461425 -21.064819)
			(xy 205.531201 -20.909409) (xy 205.608184 -20.757441) (xy 205.692206 -20.609247) (xy 205.783082 -20.465155)
			(xy 205.880612 -20.325481) (xy 205.984582 -20.190532) (xy 206.094763 -20.060604) (xy 206.210912 -19.935984)
			(xy 206.332776 -19.816945) (xy 206.460084 -19.703749) (xy 206.592559 -19.596644) (xy 206.729909 -19.495867)
			(xy 206.871831 -19.401638) (xy 207.018013 -19.314165) (xy 207.168136 -19.23364) (xy 207.321867 -19.16024)
			(xy 207.47887 -19.094126) (xy 207.6388 -19.035444) (xy 207.801304 -18.984323) (xy 207.966025 -18.940875)
			(xy 208.132603 -18.905196) (xy 208.300669 -18.877364) (xy 208.469855 -18.85744) (xy 208.639789 -18.845468)
			(xy 208.810098 -18.841475) (xy 208.980407 -18.845468) (xy 209.150341 -18.85744) (xy 209.319527 -18.877364)
			(xy 209.487593 -18.905196) (xy 209.654171 -18.940875) (xy 209.818892 -18.984323) (xy 209.981396 -19.035444)
			(xy 210.141326 -19.094126) (xy 210.298329 -19.16024) (xy 210.45206 -19.23364) (xy 210.602183 -19.314165)
			(xy 210.748365 -19.401638) (xy 210.890287 -19.495867) (xy 211.027637 -19.596644) (xy 211.160112 -19.703749)
			(xy 211.28742 -19.816945) (xy 211.409284 -19.935984) (xy 211.525433 -20.060604) (xy 211.635614 -20.190532)
			(xy 211.739584 -20.325481) (xy 211.837114 -20.465155) (xy 211.92799 -20.609247) (xy 212.012012 -20.757441)
			(xy 212.088995 -20.909409) (xy 212.158771 -21.064819) (xy 212.221186 -21.223329) (xy 212.276103 -21.38459)
			(xy 212.3234 -21.548248) (xy 212.362975 -21.713943) (xy 212.394739 -21.881311) (xy 212.418624 -22.049983)
			(xy 212.434576 -22.21959) (xy 212.442561 -22.389758) (xy 212.44306 -22.474936) (xy 212.442561 -22.560114)
			(xy 235.177575 -22.560114) (xy 235.177575 -22.389758) (xy 235.18556 -22.21959) (xy 235.201512 -22.049983)
			(xy 235.225397 -21.881311) (xy 235.257161 -21.713943) (xy 235.296736 -21.548248) (xy 235.344033 -21.38459)
			(xy 235.39895 -21.223329) (xy 235.461365 -21.064819) (xy 235.531141 -20.909409) (xy 235.608124 -20.757441)
			(xy 235.692146 -20.609247) (xy 235.783022 -20.465155) (xy 235.880552 -20.325481) (xy 235.984522 -20.190532)
			(xy 236.094703 -20.060604) (xy 236.210852 -19.935984) (xy 236.332716 -19.816945) (xy 236.460024 -19.703749)
			(xy 236.592499 -19.596644) (xy 236.729849 -19.495867) (xy 236.871771 -19.401638) (xy 237.017953 -19.314165)
			(xy 237.168076 -19.23364) (xy 237.321807 -19.16024) (xy 237.47881 -19.094126) (xy 237.63874 -19.035444)
			(xy 237.801244 -18.984323) (xy 237.965965 -18.940875) (xy 238.132543 -18.905196) (xy 238.300609 -18.877364)
			(xy 238.469795 -18.85744) (xy 238.639729 -18.845468) (xy 238.810038 -18.841475) (xy 238.980347 -18.845468)
			(xy 239.150281 -18.85744) (xy 239.319467 -18.877364) (xy 239.487533 -18.905196) (xy 239.654111 -18.940875)
			(xy 239.818832 -18.984323) (xy 239.981336 -19.035444) (xy 240.141266 -19.094126) (xy 240.298269 -19.16024)
			(xy 240.452 -19.23364) (xy 240.602123 -19.314165) (xy 240.748305 -19.401638) (xy 240.890227 -19.495867)
			(xy 241.027577 -19.596644) (xy 241.160052 -19.703749) (xy 241.28736 -19.816945) (xy 241.409224 -19.935984)
			(xy 241.525373 -20.060604) (xy 241.635554 -20.190532) (xy 241.739524 -20.325481) (xy 241.837054 -20.465155)
			(xy 241.92793 -20.609247) (xy 242.011952 -20.757441) (xy 242.088935 -20.909409) (xy 242.158711 -21.064819)
			(xy 242.221126 -21.223329) (xy 242.276043 -21.38459) (xy 242.32334 -21.548248) (xy 242.362915 -21.713943)
			(xy 242.394679 -21.881311) (xy 242.418564 -22.049983) (xy 242.434516 -22.21959) (xy 242.442501 -22.389758)
			(xy 242.443 -22.474936) (xy 242.442501 -22.560114) (xy 242.434516 -22.730282) (xy 242.418564 -22.899889)
			(xy 242.394679 -23.068561) (xy 242.362915 -23.235929) (xy 242.32334 -23.401624) (xy 242.276043 -23.565282)
			(xy 242.221126 -23.726543) (xy 242.158711 -23.885053) (xy 242.088935 -24.040463) (xy 242.011952 -24.192431)
			(xy 241.92793 -24.340625) (xy 241.837054 -24.484717) (xy 241.739524 -24.624391) (xy 241.635554 -24.75934)
			(xy 241.525373 -24.889268) (xy 241.409224 -25.013888) (xy 241.28736 -25.132927) (xy 241.160052 -25.246123)
			(xy 241.027577 -25.353228) (xy 240.890227 -25.454005) (xy 240.748305 -25.548234) (xy 240.602123 -25.635707)
			(xy 240.452 -25.716232) (xy 240.298269 -25.789632) (xy 240.141266 -25.855746) (xy 239.981336 -25.914428)
			(xy 239.818832 -25.965549) (xy 239.654111 -26.008997) (xy 239.487533 -26.044676) (xy 239.319467 -26.072508)
			(xy 239.150281 -26.092432) (xy 238.980347 -26.104404) (xy 238.810038 -26.108398) (xy 238.639729 -26.104404)
			(xy 238.469795 -26.092432) (xy 238.300609 -26.072508) (xy 238.132543 -26.044676) (xy 237.965965 -26.008997)
			(xy 237.801244 -25.965549) (xy 237.63874 -25.914428) (xy 237.47881 -25.855746) (xy 237.321807 -25.789632)
			(xy 237.168076 -25.716232) (xy 237.017953 -25.635707) (xy 236.871771 -25.548234) (xy 236.729849 -25.454005)
			(xy 236.592499 -25.353228) (xy 236.460024 -25.246123) (xy 236.332716 -25.132927) (xy 236.210852 -25.013888)
			(xy 236.094703 -24.889268) (xy 235.984522 -24.75934) (xy 235.880552 -24.624391) (xy 235.783022 -24.484717)
			(xy 235.692146 -24.340625) (xy 235.608124 -24.192431) (xy 235.531141 -24.040463) (xy 235.461365 -23.885053)
			(xy 235.39895 -23.726543) (xy 235.344033 -23.565282) (xy 235.296736 -23.401624) (xy 235.257161 -23.235929)
			(xy 235.225397 -23.068561) (xy 235.201512 -22.899889) (xy 235.18556 -22.730282) (xy 235.177575 -22.560114)
			(xy 212.442561 -22.560114) (xy 212.434576 -22.730282) (xy 212.418624 -22.899889) (xy 212.394739 -23.068561)
			(xy 212.362975 -23.235929) (xy 212.3234 -23.401624) (xy 212.276103 -23.565282) (xy 212.221186 -23.726543)
			(xy 212.158771 -23.885053) (xy 212.088995 -24.040463) (xy 212.012012 -24.192431) (xy 211.92799 -24.340625)
			(xy 211.837114 -24.484717) (xy 211.739584 -24.624391) (xy 211.635614 -24.75934) (xy 211.525433 -24.889268)
			(xy 211.409284 -25.013888) (xy 211.28742 -25.132927) (xy 211.160112 -25.246123) (xy 211.027637 -25.353228)
			(xy 210.890287 -25.454005) (xy 210.748365 -25.548234) (xy 210.602183 -25.635707) (xy 210.45206 -25.716232)
			(xy 210.298329 -25.789632) (xy 210.141326 -25.855746) (xy 209.981396 -25.914428) (xy 209.818892 -25.965549)
			(xy 209.654171 -26.008997) (xy 209.487593 -26.044676) (xy 209.319527 -26.072508) (xy 209.150341 -26.092432)
			(xy 208.980407 -26.104404) (xy 208.810098 -26.108398) (xy 208.639789 -26.104404) (xy 208.469855 -26.092432)
			(xy 208.300669 -26.072508) (xy 208.132603 -26.044676) (xy 207.966025 -26.008997) (xy 207.801304 -25.965549)
			(xy 207.6388 -25.914428) (xy 207.47887 -25.855746) (xy 207.321867 -25.789632) (xy 207.168136 -25.716232)
			(xy 207.018013 -25.635707) (xy 206.871831 -25.548234) (xy 206.729909 -25.454005) (xy 206.592559 -25.353228)
			(xy 206.460084 -25.246123) (xy 206.332776 -25.132927) (xy 206.210912 -25.013888) (xy 206.094763 -24.889268)
			(xy 205.984582 -24.75934) (xy 205.880612 -24.624391) (xy 205.783082 -24.484717) (xy 205.692206 -24.340625)
			(xy 205.608184 -24.192431) (xy 205.531201 -24.040463) (xy 205.461425 -23.885053) (xy 205.39901 -23.726543)
			(xy 205.344093 -23.565282) (xy 205.296796 -23.401624) (xy 205.257221 -23.235929) (xy 205.225457 -23.068561)
			(xy 205.201572 -22.899889) (xy 205.18562 -22.730282) (xy 205.177635 -22.560114) (xy 161.1884 -22.560114)
			(xy 161.1884 -26.950924) (xy 161.188786 -26.960998) (xy 161.196532 -26.979597) (xy 161.203386 -26.986992)
			(xy 162.141408 -27.925014) (xy 162.14881 -27.931852) (xy 162.167408 -27.939572) (xy 162.177476 -27.94)
			(xy 209.1944 -27.94) (xy 209.227659 -27.940539) (xy 209.293609 -27.949225) (xy 209.35786 -27.966447)
			(xy 209.419311 -27.991911) (xy 209.476912 -28.025182) (xy 209.529676 -28.065688) (xy 209.553556 -28.088844)
			(xy 211.331556 -29.866844) (xy 211.354708 -29.890729) (xy 211.395221 -29.943489) (xy 211.428497 -30.001088)
			(xy 211.453966 -30.062539) (xy 211.471191 -30.12679) (xy 211.479879 -30.19274) (xy 211.4804 -30.226)
			(xy 211.4804 -46.99) (xy 228.854 -46.99) (xy 228.854 -30.226) (xy 228.854539 -30.192741) (xy 228.863225 -30.126791)
			(xy 228.880447 -30.06254) (xy 228.905911 -30.001089) (xy 228.939182 -29.943488) (xy 228.979688 -29.890724)
			(xy 229.002844 -29.866844) (xy 230.780844 -28.088844) (xy 230.804729 -28.065692) (xy 230.857489 -28.025179)
			(xy 230.915088 -27.991903) (xy 230.976539 -27.966434) (xy 231.04079 -27.949209) (xy 231.10674 -27.940521)
			(xy 231.14 -27.94) (xy 278.156924 -27.94) (xy 278.166998 -27.939614) (xy 278.185597 -27.931868) (xy 278.192992 -27.925014)
			(xy 279.131014 -26.986992) (xy 279.137852 -26.97959) (xy 279.145572 -26.960992) (xy 279.146 -26.950924)
			(xy 279.146 -16.146018) (xy 279.146551 -16.112759) (xy 279.155234 -16.04681) (xy 279.172454 -15.982559)
			(xy 279.197916 -15.921108) (xy 279.231184 -15.863506) (xy 279.271689 -15.810742) (xy 279.294844 -15.786862)
			(xy 282.994862 -12.086844) (xy 283.018739 -12.063684) (xy 283.071501 -12.023171) (xy 283.129101 -11.989896)
			(xy 283.190554 -11.964429) (xy 283.254806 -11.947205) (xy 283.320758 -11.93852) (xy 283.354018 -11.938)
			(xy 323.977 -11.938) (xy 324.010259 -11.938539) (xy 324.076209 -11.947225) (xy 324.14046 -11.964447)
			(xy 324.201911 -11.989911) (xy 324.259512 -12.023182) (xy 324.312276 -12.063688) (xy 324.336156 -12.086844)
			(xy 324.971156 -12.721844) (xy 324.994308 -12.745729) (xy 325.034821 -12.798489) (xy 325.068097 -12.856088)
			(xy 325.093566 -12.917539) (xy 325.110791 -12.98179) (xy 325.119479 -13.04774) (xy 325.12 -13.081)
			(xy 325.12 -17.288961) (xy 334.478626 -17.288961) (xy 334.478626 -17.204239) (xy 334.486679 -17.119902)
			(xy 334.502713 -17.036712) (xy 334.526581 -16.955422) (xy 334.558069 -16.87677) (xy 334.596891 -16.801467)
			(xy 334.642694 -16.730195) (xy 334.695065 -16.663599) (xy 334.75353 -16.602284) (xy 334.817558 -16.546803)
			(xy 334.88657 -16.49766) (xy 334.95994 -16.4553) (xy 335.037005 -16.420105) (xy 335.117067 -16.392396)
			(xy 335.1994 -16.372422) (xy 335.283259 -16.360365) (xy 335.367884 -16.356334) (xy 335.452509 -16.360365)
			(xy 335.536368 -16.372422) (xy 335.618701 -16.392396) (xy 335.698763 -16.420105) (xy 335.775828 -16.4553)
			(xy 335.849198 -16.49766) (xy 335.91821 -16.546803) (xy 335.982238 -16.602284) (xy 336.040703 -16.663599)
			(xy 336.093074 -16.730195) (xy 336.138877 -16.801467) (xy 336.177699 -16.87677) (xy 336.209187 -16.955422)
			(xy 336.233055 -17.036712) (xy 336.249089 -17.119902) (xy 336.257142 -17.204239) (xy 336.257646 -17.2466)
			(xy 336.257142 -17.288961) (xy 336.249089 -17.373298) (xy 336.233055 -17.456488) (xy 336.209187 -17.537778)
			(xy 336.177699 -17.61643) (xy 336.138877 -17.691733) (xy 336.093074 -17.763005) (xy 336.040703 -17.829601)
			(xy 335.982238 -17.890916) (xy 335.91821 -17.946397) (xy 335.849198 -17.99554) (xy 335.775828 -18.0379)
			(xy 335.698763 -18.073095) (xy 335.618701 -18.100804) (xy 335.536368 -18.120778) (xy 335.452509 -18.132835)
			(xy 335.367884 -18.136867) (xy 335.283259 -18.132835) (xy 335.1994 -18.120778) (xy 335.117067 -18.100804)
			(xy 335.037005 -18.073095) (xy 334.95994 -18.0379) (xy 334.88657 -17.99554) (xy 334.817558 -17.946397)
			(xy 334.75353 -17.890916) (xy 334.695065 -17.829601) (xy 334.642694 -17.763005) (xy 334.596891 -17.691733)
			(xy 334.558069 -17.61643) (xy 334.526581 -17.537778) (xy 334.502713 -17.456488) (xy 334.486679 -17.373298)
			(xy 334.478626 -17.288961) (xy 325.12 -17.288961) (xy 325.12 -23.0886) (xy 331.266292 -23.0886) (xy 331.266292 -23.088092)
			(xy 331.266898 -23.04176) (xy 331.276569 -22.949602) (xy 331.295765 -22.858948) (xy 331.324277 -22.770779)
			(xy 331.342492 -22.728174) (xy 331.346298 -22.718232) (xy 331.346298 -22.696968) (xy 331.342492 -22.687026)
			(xy 331.324247 -22.644364) (xy 331.295703 -22.556071) (xy 331.27651 -22.465286) (xy 331.266877 -22.372996)
			(xy 331.266292 -22.3266) (xy 331.266875 -22.280204) (xy 331.27652 -22.187916) (xy 331.295716 -22.097132)
			(xy 331.324254 -22.008839) (xy 331.342492 -21.966174) (xy 331.346298 -21.956232) (xy 331.346298 -21.934968)
			(xy 331.342492 -21.925026) (xy 331.324247 -21.882364) (xy 331.295703 -21.794071) (xy 331.27651 -21.703286)
			(xy 331.266877 -21.610996) (xy 331.266292 -21.5646) (xy 331.266875 -21.518204) (xy 331.27652 -21.425916)
			(xy 331.295716 -21.335132) (xy 331.324254 -21.246839) (xy 331.342492 -21.204174) (xy 331.346298 -21.194232)
			(xy 331.346298 -21.172968) (xy 331.342492 -21.163026) (xy 331.324247 -21.120364) (xy 331.295703 -21.032071)
			(xy 331.27651 -20.941286) (xy 331.266877 -20.848996) (xy 331.266292 -20.8026) (xy 331.266875 -20.756204)
			(xy 331.27652 -20.663916) (xy 331.295716 -20.573132) (xy 331.324254 -20.484839) (xy 331.342492 -20.442174)
			(xy 331.346298 -20.432232) (xy 331.346298 -20.410968) (xy 331.342492 -20.401026) (xy 331.32427 -20.358423)
			(xy 331.295752 -20.270256) (xy 331.27656 -20.1796) (xy 331.2669 -20.08744) (xy 331.266292 -20.041108)
			(xy 331.266292 -20.0406) (xy 331.266767 -19.999498) (xy 331.274352 -19.917643) (xy 331.289457 -19.836838)
			(xy 331.311953 -19.757771) (xy 331.341649 -19.681117) (xy 331.378291 -19.60753) (xy 331.421566 -19.537638)
			(xy 331.471106 -19.472037) (xy 331.526487 -19.411287) (xy 331.587237 -19.355906) (xy 331.652838 -19.306366)
			(xy 331.72273 -19.263091) (xy 331.796317 -19.226449) (xy 331.872971 -19.196753) (xy 331.952038 -19.174257)
			(xy 332.032843 -19.159152) (xy 332.114698 -19.151567) (xy 332.1558 -19.151092) (xy 332.156308 -19.151092)
			(xy 332.20264 -19.151698) (xy 332.294798 -19.161369) (xy 332.385452 -19.180565) (xy 332.473621 -19.209077)
			(xy 332.516226 -19.227292) (xy 332.526168 -19.231098) (xy 332.547432 -19.231098) (xy 332.557374 -19.227292)
			(xy 332.600036 -19.209047) (xy 332.688329 -19.180503) (xy 332.779114 -19.16131) (xy 332.871404 -19.151677)
			(xy 332.9178 -19.151092) (xy 332.964196 -19.151675) (xy 333.056484 -19.16132) (xy 333.147268 -19.180516)
			(xy 333.235561 -19.209054) (xy 333.278226 -19.227292) (xy 333.288168 -19.231098) (xy 333.309432 -19.231098)
			(xy 333.319374 -19.227292) (xy 333.362036 -19.209047) (xy 333.450329 -19.180503) (xy 333.541114 -19.16131)
			(xy 333.633404 -19.151677) (xy 333.6798 -19.151092) (xy 333.726196 -19.151675) (xy 333.818484 -19.16132)
			(xy 333.909268 -19.180516) (xy 333.997561 -19.209054) (xy 334.040226 -19.227292) (xy 334.050168 -19.231098)
			(xy 334.071432 -19.231098) (xy 334.081374 -19.227292) (xy 334.124036 -19.209047) (xy 334.212329 -19.180503)
			(xy 334.303114 -19.16131) (xy 334.395404 -19.151677) (xy 334.4418 -19.151092) (xy 334.488196 -19.151675)
			(xy 334.580484 -19.16132) (xy 334.671268 -19.180516) (xy 334.759561 -19.209054) (xy 334.802226 -19.227292)
			(xy 334.812168 -19.231098) (xy 334.833432 -19.231098) (xy 334.843374 -19.227292) (xy 334.885977 -19.20907)
			(xy 334.974144 -19.180552) (xy 335.0648 -19.16136) (xy 335.15696 -19.1517) (xy 335.203292 -19.151092)
			(xy 335.2038 -19.151092) (xy 335.244902 -19.151567) (xy 335.326757 -19.159152) (xy 335.407562 -19.174257)
			(xy 335.486629 -19.196753) (xy 335.563283 -19.226449) (xy 335.63687 -19.263091) (xy 335.706762 -19.306366)
			(xy 335.772363 -19.355906) (xy 335.833113 -19.411287) (xy 335.888494 -19.472037) (xy 335.938034 -19.537638)
			(xy 335.981309 -19.60753) (xy 336.017951 -19.681117) (xy 336.047647 -19.757771) (xy 336.070143 -19.836838)
			(xy 336.085248 -19.917643) (xy 336.092833 -19.999498) (xy 336.09288 -20.00357) (xy 386.295635 -20.00357)
			(xy 386.295635 -19.87443) (xy 386.303585 -19.745535) (xy 386.319455 -19.617375) (xy 386.343184 -19.490434)
			(xy 386.374683 -19.365195) (xy 386.413832 -19.242132) (xy 386.460483 -19.121713) (xy 386.514458 -19.004394)
			(xy 386.575553 -18.89062) (xy 386.643536 -18.780823) (xy 386.71815 -18.67542) (xy 386.799111 -18.57481)
			(xy 386.886111 -18.479375) (xy 386.978822 -18.389476) (xy 387.076892 -18.305455) (xy 387.179947 -18.227631)
			(xy 387.287598 -18.156299) (xy 387.399437 -18.091729) (xy 387.515038 -18.034167) (xy 387.633963 -17.98383)
			(xy 387.755762 -17.94091) (xy 387.879972 -17.905569) (xy 388.006121 -17.877942) (xy 388.133733 -17.858133)
			(xy 388.262322 -17.846217) (xy 388.3914 -17.842241) (xy 388.520478 -17.846217) (xy 388.649067 -17.858133)
			(xy 388.776679 -17.877942) (xy 388.902828 -17.905569) (xy 389.027038 -17.94091) (xy 389.148837 -17.98383)
			(xy 389.267762 -18.034167) (xy 389.383363 -18.091729) (xy 389.495202 -18.156299) (xy 389.602853 -18.227631)
			(xy 389.705908 -18.305455) (xy 389.803978 -18.389476) (xy 389.896689 -18.479375) (xy 389.983689 -18.57481)
			(xy 390.06465 -18.67542) (xy 390.139264 -18.780823) (xy 390.207247 -18.89062) (xy 390.268342 -19.004394)
			(xy 390.322317 -19.121713) (xy 390.368968 -19.242132) (xy 390.408117 -19.365195) (xy 390.439616 -19.490434)
			(xy 390.463345 -19.617375) (xy 390.479215 -19.745535) (xy 390.487165 -19.87443) (xy 390.487662 -19.939)
			(xy 390.487165 -20.00357) (xy 390.479215 -20.132465) (xy 390.463345 -20.260625) (xy 390.439616 -20.387566)
			(xy 390.408117 -20.512805) (xy 390.368968 -20.635868) (xy 390.322317 -20.756287) (xy 390.268342 -20.873606)
			(xy 390.207247 -20.98738) (xy 390.139264 -21.097177) (xy 390.06465 -21.20258) (xy 389.983689 -21.30319)
			(xy 389.896689 -21.398625) (xy 389.803978 -21.488524) (xy 389.705908 -21.572545) (xy 389.602853 -21.650369)
			(xy 389.495202 -21.721701) (xy 389.383363 -21.786271) (xy 389.267762 -21.843833) (xy 389.148837 -21.89417)
			(xy 389.027038 -21.93709) (xy 388.902828 -21.972431) (xy 388.776679 -22.000058) (xy 388.649067 -22.019867)
			(xy 388.520478 -22.031783) (xy 388.3914 -22.03576) (xy 388.262322 -22.031783) (xy 388.133733 -22.019867)
			(xy 388.006121 -22.000058) (xy 387.879972 -21.972431) (xy 387.755762 -21.93709) (xy 387.633963 -21.89417)
			(xy 387.515038 -21.843833) (xy 387.399437 -21.786271) (xy 387.287598 -21.721701) (xy 387.179947 -21.650369)
			(xy 387.076892 -21.572545) (xy 386.978822 -21.488524) (xy 386.886111 -21.398625) (xy 386.799111 -21.30319)
			(xy 386.71815 -21.20258) (xy 386.643536 -21.097177) (xy 386.575553 -20.98738) (xy 386.514458 -20.873606)
			(xy 386.460483 -20.756287) (xy 386.413832 -20.635868) (xy 386.374683 -20.512805) (xy 386.343184 -20.387566)
			(xy 386.319455 -20.260625) (xy 386.303585 -20.132465) (xy 386.295635 -20.00357) (xy 336.09288 -20.00357)
			(xy 336.093308 -20.0406) (xy 336.093308 -20.041108) (xy 336.092702 -20.08744) (xy 336.083031 -20.179598)
			(xy 336.063835 -20.270252) (xy 336.035323 -20.358421) (xy 336.017108 -20.401026) (xy 336.013302 -20.410968)
			(xy 336.013302 -20.432232) (xy 336.017108 -20.442174) (xy 336.035353 -20.484836) (xy 336.063897 -20.573129)
			(xy 336.08309 -20.663914) (xy 336.092723 -20.756204) (xy 336.093308 -20.8026) (xy 336.092725 -20.848996)
			(xy 336.08308 -20.941284) (xy 336.063884 -21.032068) (xy 336.035346 -21.120361) (xy 336.017108 -21.163026)
			(xy 336.013302 -21.172968) (xy 336.013302 -21.194232) (xy 336.017108 -21.204174) (xy 336.035353 -21.246836)
			(xy 336.063897 -21.335129) (xy 336.08309 -21.425914) (xy 336.092723 -21.518204) (xy 336.093308 -21.5646)
			(xy 336.092725 -21.610996) (xy 336.08308 -21.703284) (xy 336.063884 -21.794068) (xy 336.035346 -21.882361)
			(xy 336.017108 -21.925026) (xy 336.013302 -21.934968) (xy 336.013302 -21.956232) (xy 336.017108 -21.966174)
			(xy 336.035353 -22.008836) (xy 336.063897 -22.097129) (xy 336.08309 -22.187914) (xy 336.092723 -22.280204)
			(xy 336.093308 -22.3266) (xy 336.092725 -22.372996) (xy 336.08308 -22.465284) (xy 336.063884 -22.556068)
			(xy 336.035346 -22.644361) (xy 336.017108 -22.687026) (xy 336.013302 -22.696968) (xy 336.013302 -22.718232)
			(xy 336.017108 -22.728174) (xy 336.03533 -22.770777) (xy 336.063848 -22.858944) (xy 336.08304 -22.9496)
			(xy 336.0927 -23.04176) (xy 336.093308 -23.088092) (xy 336.093308 -23.0886) (xy 336.092833 -23.129702)
			(xy 336.085248 -23.211557) (xy 336.070143 -23.292362) (xy 336.047647 -23.371429) (xy 336.017951 -23.448083)
			(xy 335.981309 -23.52167) (xy 335.938034 -23.591562) (xy 335.888494 -23.657163) (xy 335.833113 -23.717913)
			(xy 335.772363 -23.773294) (xy 335.706762 -23.822834) (xy 335.63687 -23.866109) (xy 335.563283 -23.902751)
			(xy 335.486629 -23.932447) (xy 335.407562 -23.954943) (xy 335.326757 -23.970048) (xy 335.244902 -23.977633)
			(xy 335.2038 -23.978108) (xy 335.203292 -23.978108) (xy 335.15696 -23.977502) (xy 335.064802 -23.967831)
			(xy 334.974148 -23.948635) (xy 334.885979 -23.920123) (xy 334.843374 -23.901908) (xy 334.833432 -23.898102)
			(xy 334.812168 -23.898102) (xy 334.802226 -23.901908) (xy 334.759564 -23.920153) (xy 334.671271 -23.948697)
			(xy 334.580486 -23.96789) (xy 334.488196 -23.977523) (xy 334.4418 -23.978108) (xy 334.395404 -23.977525)
			(xy 334.303116 -23.96788) (xy 334.212332 -23.948684) (xy 334.124039 -23.920146) (xy 334.081374 -23.901908)
			(xy 334.071432 -23.898102) (xy 334.050168 -23.898102) (xy 334.040226 -23.901908) (xy 333.997564 -23.920153)
			(xy 333.909271 -23.948697) (xy 333.818486 -23.96789) (xy 333.726196 -23.977523) (xy 333.6798 -23.978108)
			(xy 333.633404 -23.977525) (xy 333.541116 -23.96788) (xy 333.450332 -23.948684) (xy 333.362039 -23.920146)
			(xy 333.319374 -23.901908) (xy 333.309432 -23.898102) (xy 333.288168 -23.898102) (xy 333.278226 -23.901908)
			(xy 333.235564 -23.920153) (xy 333.147271 -23.948697) (xy 333.056486 -23.96789) (xy 332.964196 -23.977523)
			(xy 332.9178 -23.978108) (xy 332.871404 -23.977525) (xy 332.779116 -23.96788) (xy 332.688332 -23.948684)
			(xy 332.600039 -23.920146) (xy 332.557374 -23.901908) (xy 332.547432 -23.898102) (xy 332.526168 -23.898102)
			(xy 332.516226 -23.901908) (xy 332.473623 -23.92013) (xy 332.385456 -23.948648) (xy 332.2948 -23.96784)
			(xy 332.20264 -23.9775) (xy 332.156308 -23.978108) (xy 332.1558 -23.978108) (xy 332.114698 -23.977633)
			(xy 332.032843 -23.970048) (xy 331.952038 -23.954943) (xy 331.872971 -23.932447) (xy 331.796317 -23.902751)
			(xy 331.72273 -23.866109) (xy 331.652838 -23.822834) (xy 331.587237 -23.773294) (xy 331.526487 -23.717913)
			(xy 331.471106 -23.657163) (xy 331.421566 -23.591562) (xy 331.378291 -23.52167) (xy 331.341649 -23.448083)
			(xy 331.311953 -23.371429) (xy 331.289457 -23.292362) (xy 331.274352 -23.211557) (xy 331.266767 -23.129702)
			(xy 331.266292 -23.0886) (xy 325.12 -23.0886) (xy 325.12 -28.566561) (xy 334.478626 -28.566561) (xy 334.478626 -28.481839)
			(xy 334.486679 -28.397502) (xy 334.502713 -28.314312) (xy 334.526581 -28.233022) (xy 334.558069 -28.15437)
			(xy 334.596891 -28.079067) (xy 334.642694 -28.007795) (xy 334.695065 -27.941199) (xy 334.75353 -27.879884)
			(xy 334.817558 -27.824403) (xy 334.88657 -27.77526) (xy 334.95994 -27.7329) (xy 335.037005 -27.697705)
			(xy 335.117067 -27.669996) (xy 335.1994 -27.650022) (xy 335.283259 -27.637965) (xy 335.367884 -27.633934)
			(xy 335.452509 -27.637965) (xy 335.536368 -27.650022) (xy 335.618701 -27.669996) (xy 335.698763 -27.697705)
			(xy 335.775828 -27.7329) (xy 335.849198 -27.77526) (xy 335.91821 -27.824403) (xy 335.982238 -27.879884)
			(xy 336.040703 -27.941199) (xy 336.093074 -28.007795) (xy 336.138877 -28.079067) (xy 336.177699 -28.15437)
			(xy 336.209187 -28.233022) (xy 336.233055 -28.314312) (xy 336.249089 -28.397502) (xy 336.257142 -28.481839)
			(xy 336.257646 -28.5242) (xy 336.257142 -28.566561) (xy 336.249089 -28.650898) (xy 336.233055 -28.734088)
			(xy 336.209187 -28.815378) (xy 336.177699 -28.89403) (xy 336.138877 -28.969333) (xy 336.093074 -29.040605)
			(xy 336.040703 -29.107201) (xy 335.982238 -29.168516) (xy 335.91821 -29.223997) (xy 335.849198 -29.27314)
			(xy 335.775828 -29.3155) (xy 335.698763 -29.350695) (xy 335.618701 -29.378404) (xy 335.536368 -29.398378)
			(xy 335.452509 -29.410435) (xy 335.367884 -29.414467) (xy 335.283259 -29.410435) (xy 335.1994 -29.398378)
			(xy 335.117067 -29.378404) (xy 335.037005 -29.350695) (xy 334.95994 -29.3155) (xy 334.88657 -29.27314)
			(xy 334.817558 -29.223997) (xy 334.75353 -29.168516) (xy 334.695065 -29.107201) (xy 334.642694 -29.040605)
			(xy 334.596891 -28.969333) (xy 334.558069 -28.89403) (xy 334.526581 -28.815378) (xy 334.502713 -28.734088)
			(xy 334.486679 -28.650898) (xy 334.478626 -28.566561) (xy 325.12 -28.566561) (xy 325.12 -34.3662)
			(xy 331.266292 -34.3662) (xy 331.266292 -34.365692) (xy 331.266898 -34.31936) (xy 331.276569 -34.227202)
			(xy 331.295765 -34.136548) (xy 331.324277 -34.048379) (xy 331.342492 -34.005774) (xy 331.346298 -33.995832)
			(xy 331.346298 -33.974568) (xy 331.342492 -33.964626) (xy 331.324247 -33.921964) (xy 331.295703 -33.833671)
			(xy 331.27651 -33.742886) (xy 331.266877 -33.650596) (xy 331.266292 -33.6042) (xy 331.266875 -33.557804)
			(xy 331.27652 -33.465516) (xy 331.295716 -33.374732) (xy 331.324254 -33.286439) (xy 331.342492 -33.243774)
			(xy 331.346298 -33.233832) (xy 331.346298 -33.212568) (xy 331.342492 -33.202626) (xy 331.324247 -33.159964)
			(xy 331.295703 -33.071671) (xy 331.27651 -32.980886) (xy 331.266877 -32.888596) (xy 331.266292 -32.8422)
			(xy 331.266875 -32.795804) (xy 331.27652 -32.703516) (xy 331.295716 -32.612732) (xy 331.324254 -32.524439)
			(xy 331.342492 -32.481774) (xy 331.346298 -32.471832) (xy 331.346298 -32.450568) (xy 331.342492 -32.440626)
			(xy 331.324247 -32.397964) (xy 331.295703 -32.309671) (xy 331.27651 -32.218886) (xy 331.266877 -32.126596)
			(xy 331.266292 -32.0802) (xy 331.266875 -32.033804) (xy 331.27652 -31.941516) (xy 331.295716 -31.850732)
			(xy 331.324254 -31.762439) (xy 331.342492 -31.719774) (xy 331.346298 -31.709832) (xy 331.346298 -31.688568)
			(xy 331.342492 -31.678626) (xy 331.32427 -31.636023) (xy 331.295752 -31.547856) (xy 331.27656 -31.4572)
			(xy 331.2669 -31.36504) (xy 331.266292 -31.318708) (xy 331.266292 -31.3182) (xy 331.266767 -31.277098)
			(xy 331.274352 -31.195243) (xy 331.289457 -31.114438) (xy 331.311953 -31.035371) (xy 331.341649 -30.958717)
			(xy 331.378291 -30.88513) (xy 331.421566 -30.815238) (xy 331.471106 -30.749637) (xy 331.526487 -30.688887)
			(xy 331.587237 -30.633506) (xy 331.652838 -30.583966) (xy 331.72273 -30.540691) (xy 331.796317 -30.504049)
			(xy 331.872971 -30.474353) (xy 331.952038 -30.451857) (xy 332.032843 -30.436752) (xy 332.114698 -30.429167)
			(xy 332.1558 -30.428692) (xy 332.156308 -30.428692) (xy 332.20264 -30.429298) (xy 332.294798 -30.438969)
			(xy 332.385452 -30.458165) (xy 332.473621 -30.486677) (xy 332.516226 -30.504892) (xy 332.526168 -30.508698)
			(xy 332.547432 -30.508698) (xy 332.557374 -30.504892) (xy 332.600036 -30.486647) (xy 332.688329 -30.458103)
			(xy 332.779114 -30.43891) (xy 332.871404 -30.429277) (xy 332.9178 -30.428692) (xy 332.964196 -30.429275)
			(xy 333.056484 -30.43892) (xy 333.147268 -30.458116) (xy 333.235561 -30.486654) (xy 333.278226 -30.504892)
			(xy 333.288168 -30.508698) (xy 333.309432 -30.508698) (xy 333.319374 -30.504892) (xy 333.362036 -30.486647)
			(xy 333.450329 -30.458103) (xy 333.541114 -30.43891) (xy 333.633404 -30.429277) (xy 333.6798 -30.428692)
			(xy 333.726196 -30.429275) (xy 333.818484 -30.43892) (xy 333.909268 -30.458116) (xy 333.997561 -30.486654)
			(xy 334.040226 -30.504892) (xy 334.050168 -30.508698) (xy 334.071432 -30.508698) (xy 334.081374 -30.504892)
			(xy 334.124036 -30.486647) (xy 334.212329 -30.458103) (xy 334.303114 -30.43891) (xy 334.395404 -30.429277)
			(xy 334.4418 -30.428692) (xy 334.488196 -30.429275) (xy 334.580484 -30.43892) (xy 334.671268 -30.458116)
			(xy 334.759561 -30.486654) (xy 334.802226 -30.504892) (xy 334.812168 -30.508698) (xy 334.833432 -30.508698)
			(xy 334.843374 -30.504892) (xy 334.885977 -30.48667) (xy 334.974144 -30.458152) (xy 335.0648 -30.43896)
			(xy 335.15696 -30.4293) (xy 335.203292 -30.428692) (xy 335.2038 -30.428692) (xy 335.244902 -30.429167)
			(xy 335.326757 -30.436752) (xy 335.407562 -30.451857) (xy 335.486629 -30.474353) (xy 335.563283 -30.504049)
			(xy 335.63687 -30.540691) (xy 335.706762 -30.583966) (xy 335.772363 -30.633506) (xy 335.833113 -30.688887)
			(xy 335.888494 -30.749637) (xy 335.938034 -30.815238) (xy 335.981309 -30.88513) (xy 336.017951 -30.958717)
			(xy 336.047647 -31.035371) (xy 336.070143 -31.114438) (xy 336.085248 -31.195243) (xy 336.092833 -31.277098)
			(xy 336.093308 -31.3182) (xy 336.093308 -31.318708) (xy 336.092702 -31.36504) (xy 336.083031 -31.457198)
			(xy 336.063835 -31.547852) (xy 336.035323 -31.636021) (xy 336.017108 -31.678626) (xy 336.013302 -31.688568)
			(xy 336.013302 -31.709832) (xy 336.017108 -31.719774) (xy 336.035353 -31.762436) (xy 336.063897 -31.850729)
			(xy 336.08309 -31.941514) (xy 336.092723 -32.033804) (xy 336.093308 -32.0802) (xy 336.092725 -32.126596)
			(xy 336.08308 -32.218884) (xy 336.063884 -32.309668) (xy 336.035346 -32.397961) (xy 336.017108 -32.440626)
			(xy 336.013302 -32.450568) (xy 336.013302 -32.471832) (xy 336.017108 -32.481774) (xy 336.035353 -32.524436)
			(xy 336.063897 -32.612729) (xy 336.08309 -32.703514) (xy 336.092723 -32.795804) (xy 336.093308 -32.8422)
			(xy 336.092725 -32.888596) (xy 336.08308 -32.980884) (xy 336.063884 -33.071668) (xy 336.035346 -33.159961)
			(xy 336.017108 -33.202626) (xy 336.013302 -33.212568) (xy 336.013302 -33.233832) (xy 336.017108 -33.243774)
			(xy 336.035353 -33.286436) (xy 336.063897 -33.374729) (xy 336.08309 -33.465514) (xy 336.092723 -33.557804)
			(xy 336.093308 -33.6042) (xy 336.092725 -33.650596) (xy 336.08308 -33.742884) (xy 336.063884 -33.833668)
			(xy 336.035346 -33.921961) (xy 336.017108 -33.964626) (xy 336.013302 -33.974568) (xy 336.013302 -33.995832)
			(xy 336.017108 -34.005774) (xy 336.03533 -34.048377) (xy 336.063848 -34.136544) (xy 336.08304 -34.2272)
			(xy 336.0927 -34.31936) (xy 336.093308 -34.365692) (xy 336.093308 -34.3662) (xy 336.092833 -34.407302)
			(xy 336.085248 -34.489157) (xy 336.070143 -34.569962) (xy 336.047647 -34.649029) (xy 336.017951 -34.725683)
			(xy 335.981309 -34.79927) (xy 335.938034 -34.869162) (xy 335.888494 -34.934763) (xy 335.833113 -34.995513)
			(xy 335.772363 -35.050894) (xy 335.706762 -35.100434) (xy 335.63687 -35.143709) (xy 335.563283 -35.180351)
			(xy 335.486629 -35.210047) (xy 335.407562 -35.232543) (xy 335.326757 -35.247648) (xy 335.244902 -35.255233)
			(xy 335.2038 -35.255708) (xy 335.203292 -35.255708) (xy 335.15696 -35.255102) (xy 335.064802 -35.245431)
			(xy 334.974148 -35.226235) (xy 334.885979 -35.197723) (xy 334.843374 -35.179508) (xy 334.833432 -35.175702)
			(xy 334.812168 -35.175702) (xy 334.802226 -35.179508) (xy 334.759564 -35.197753) (xy 334.671271 -35.226297)
			(xy 334.580486 -35.24549) (xy 334.488196 -35.255123) (xy 334.4418 -35.255708) (xy 334.395404 -35.255125)
			(xy 334.303116 -35.24548) (xy 334.212332 -35.226284) (xy 334.124039 -35.197746) (xy 334.081374 -35.179508)
			(xy 334.071432 -35.175702) (xy 334.050168 -35.175702) (xy 334.040226 -35.179508) (xy 333.997564 -35.197753)
			(xy 333.909271 -35.226297) (xy 333.818486 -35.24549) (xy 333.726196 -35.255123) (xy 333.6798 -35.255708)
			(xy 333.633404 -35.255125) (xy 333.541116 -35.24548) (xy 333.450332 -35.226284) (xy 333.362039 -35.197746)
			(xy 333.319374 -35.179508) (xy 333.309432 -35.175702) (xy 333.288168 -35.175702) (xy 333.278226 -35.179508)
			(xy 333.235564 -35.197753) (xy 333.147271 -35.226297) (xy 333.056486 -35.24549) (xy 332.964196 -35.255123)
			(xy 332.9178 -35.255708) (xy 332.871404 -35.255125) (xy 332.779116 -35.24548) (xy 332.688332 -35.226284)
			(xy 332.600039 -35.197746) (xy 332.557374 -35.179508) (xy 332.547432 -35.175702) (xy 332.526168 -35.175702)
			(xy 332.516226 -35.179508) (xy 332.473623 -35.19773) (xy 332.385456 -35.226248) (xy 332.2948 -35.24544)
			(xy 332.20264 -35.2551) (xy 332.156308 -35.255708) (xy 332.1558 -35.255708) (xy 332.114698 -35.255233)
			(xy 332.032843 -35.247648) (xy 331.952038 -35.232543) (xy 331.872971 -35.210047) (xy 331.796317 -35.180351)
			(xy 331.72273 -35.143709) (xy 331.652838 -35.100434) (xy 331.587237 -35.050894) (xy 331.526487 -34.995513)
			(xy 331.471106 -34.934763) (xy 331.421566 -34.869162) (xy 331.378291 -34.79927) (xy 331.341649 -34.725683)
			(xy 331.311953 -34.649029) (xy 331.289457 -34.569962) (xy 331.274352 -34.489157) (xy 331.266767 -34.407302)
			(xy 331.266292 -34.3662) (xy 325.12 -34.3662) (xy 325.12 -37.289429) (xy 337.982302 -37.289429) (xy 337.982302 -37.204707)
			(xy 337.990355 -37.12037) (xy 338.006389 -37.03718) (xy 338.030257 -36.95589) (xy 338.061745 -36.877238)
			(xy 338.100567 -36.801935) (xy 338.14637 -36.730663) (xy 338.198741 -36.664067) (xy 338.257206 -36.602752)
			(xy 338.321234 -36.547271) (xy 338.390246 -36.498128) (xy 338.463616 -36.455768) (xy 338.540681 -36.420573)
			(xy 338.620743 -36.392864) (xy 338.703076 -36.37289) (xy 338.786935 -36.360833) (xy 338.87156 -36.356802)
			(xy 338.956185 -36.360833) (xy 339.040044 -36.37289) (xy 339.122377 -36.392864) (xy 339.202439 -36.420573)
			(xy 339.279504 -36.455768) (xy 339.352874 -36.498128) (xy 339.421886 -36.547271) (xy 339.485914 -36.602752)
			(xy 339.544379 -36.664067) (xy 339.59675 -36.730663) (xy 339.642553 -36.801935) (xy 339.681375 -36.877238)
			(xy 339.712863 -36.95589) (xy 339.736731 -37.03718) (xy 339.752765 -37.12037) (xy 339.760818 -37.204707)
			(xy 339.761322 -37.247068) (xy 339.760818 -37.289429) (xy 339.752765 -37.373766) (xy 339.736731 -37.456956)
			(xy 339.712863 -37.538246) (xy 339.681375 -37.616898) (xy 339.642553 -37.692201) (xy 339.59675 -37.763473)
			(xy 339.544379 -37.830069) (xy 339.485914 -37.891384) (xy 339.421886 -37.946865) (xy 339.352874 -37.996008)
			(xy 339.279504 -38.038368) (xy 339.202439 -38.073563) (xy 339.122377 -38.101272) (xy 339.040044 -38.121246)
			(xy 338.956185 -38.133303) (xy 338.87156 -38.137335) (xy 338.786935 -38.133303) (xy 338.703076 -38.121246)
			(xy 338.620743 -38.101272) (xy 338.540681 -38.073563) (xy 338.463616 -38.038368) (xy 338.390246 -37.996008)
			(xy 338.321234 -37.946865) (xy 338.257206 -37.891384) (xy 338.198741 -37.830069) (xy 338.14637 -37.763473)
			(xy 338.100567 -37.692201) (xy 338.061745 -37.616898) (xy 338.030257 -37.538246) (xy 338.006389 -37.456956)
			(xy 337.990355 -37.373766) (xy 337.982302 -37.289429) (xy 325.12 -37.289429) (xy 325.12 -39.787831)
			(xy 334.477997 -39.787831) (xy 334.483261 -39.704146) (xy 334.496377 -39.621328) (xy 334.517229 -39.540112)
			(xy 334.545631 -39.461218) (xy 334.581332 -39.385348) (xy 334.624014 -39.313173) (xy 334.673299 -39.245336)
			(xy 334.728749 -39.182438) (xy 334.789873 -39.125038) (xy 334.856127 -39.073645) (xy 334.926923 -39.028714)
			(xy 335.001634 -38.990646) (xy 335.079595 -38.959777) (xy 335.160116 -38.936382) (xy 335.242481 -38.920669)
			(xy 335.325959 -38.912776) (xy 335.367884 -38.912292) (xy 335.368392 -38.912292) (xy 335.404819 -38.912666)
			(xy 335.477428 -38.918641) (xy 335.513426 -38.92423) (xy 335.528472 -38.926165) (xy 335.558521 -38.922119)
			(xy 335.586063 -38.909441) (xy 335.608678 -38.889246) (xy 335.624379 -38.863308) (xy 335.631785 -38.833906)
			(xy 335.630246 -38.803626) (xy 335.619897 -38.775127) (xy 335.611216 -38.762686) (xy 335.586864 -38.729613)
			(xy 335.543671 -38.659752) (xy 335.507099 -38.586206) (xy 335.477461 -38.509604) (xy 335.455009 -38.430596)
			(xy 335.439934 -38.349855) (xy 335.432365 -38.268068) (xy 335.431892 -38.227) (xy 335.432376 -38.185075)
			(xy 335.440267 -38.101596) (xy 335.455979 -38.019231) (xy 335.479372 -37.938709) (xy 335.51024 -37.860747)
			(xy 335.548307 -37.786036) (xy 335.593237 -37.715238) (xy 335.644629 -37.648983) (xy 335.702029 -37.587859)
			(xy 335.764926 -37.532407) (xy 335.832763 -37.483121) (xy 335.904937 -37.440438) (xy 335.980807 -37.404736)
			(xy 336.0597 -37.376332) (xy 336.140917 -37.355479) (xy 336.223735 -37.342362) (xy 336.30742 -37.337097)
			(xy 336.39123 -37.339731) (xy 336.474419 -37.35024) (xy 336.55625 -37.368532) (xy 336.635997 -37.394443)
			(xy 336.712951 -37.427744) (xy 336.78643 -37.46814) (xy 336.855782 -37.515271) (xy 336.92039 -37.568719)
			(xy 336.979681 -37.62801) (xy 337.033129 -37.692618) (xy 337.08026 -37.76197) (xy 337.120656 -37.835449)
			(xy 337.153957 -37.912403) (xy 337.179868 -37.99215) (xy 337.19816 -38.073981) (xy 337.208669 -38.15717)
			(xy 337.211303 -38.24098) (xy 337.206038 -38.324665) (xy 337.192921 -38.407483) (xy 337.172068 -38.4887)
			(xy 337.143664 -38.567593) (xy 337.107962 -38.643463) (xy 337.065279 -38.715637) (xy 337.015993 -38.783474)
			(xy 336.960541 -38.846371) (xy 336.899417 -38.903771) (xy 336.833162 -38.955163) (xy 336.762364 -39.000093)
			(xy 336.687653 -39.03816) (xy 336.609691 -39.069028) (xy 336.529169 -39.092421) (xy 336.446804 -39.108133)
			(xy 336.363325 -39.116024) (xy 336.3214 -39.116508) (xy 336.320892 -39.116508) (xy 336.284465 -39.116136)
			(xy 336.211856 -39.110159) (xy 336.175858 -39.10457) (xy 336.160814 -39.102622) (xy 336.130765 -39.106672)
			(xy 336.103223 -39.119352) (xy 336.080609 -39.139549) (xy 336.064909 -39.165489) (xy 336.057502 -39.194891)
			(xy 336.05904 -39.225172) (xy 336.069388 -39.253672) (xy 336.078068 -39.266114) (xy 336.102418 -39.299188)
			(xy 336.145612 -39.36905) (xy 336.182184 -39.442594) (xy 336.211822 -39.519197) (xy 336.234274 -39.598205)
			(xy 336.249349 -39.678945) (xy 336.256919 -39.760732) (xy 336.257392 -39.8018) (xy 336.256924 -39.843725)
			(xy 336.249033 -39.927203) (xy 336.233322 -40.009569) (xy 336.209928 -40.090089) (xy 336.179061 -40.168052)
			(xy 336.140994 -40.242763) (xy 336.096065 -40.31356) (xy 336.044672 -40.379815) (xy 335.987273 -40.440939)
			(xy 335.924376 -40.496391) (xy 335.85654 -40.545677) (xy 335.784367 -40.588361) (xy 335.708497 -40.624063)
			(xy 335.629604 -40.652466) (xy 335.548388 -40.67332) (xy 335.46557 -40.686437) (xy 335.381885 -40.691703)
			(xy 335.298076 -40.689069) (xy 335.214887 -40.678561) (xy 335.133056 -40.66027) (xy 335.053309 -40.634359)
			(xy 334.976355 -40.601059) (xy 334.902876 -40.560664) (xy 334.833525 -40.513534) (xy 334.768916 -40.460086)
			(xy 334.709625 -40.400796) (xy 334.656176 -40.336188) (xy 334.609044 -40.266838) (xy 334.568648 -40.19336)
			(xy 334.535346 -40.116406) (xy 334.509434 -40.03666) (xy 334.491142 -39.954829) (xy 334.480632 -39.87164)
			(xy 334.477997 -39.787831) (xy 325.12 -39.787831) (xy 325.12 -45.6438) (xy 331.266292 -45.6438) (xy 331.266292 -45.643292)
			(xy 331.266898 -45.59696) (xy 331.276569 -45.504802) (xy 331.295765 -45.414148) (xy 331.324277 -45.325979)
			(xy 331.342492 -45.283374) (xy 331.346298 -45.273432) (xy 331.346298 -45.252168) (xy 331.342492 -45.242226)
			(xy 331.324247 -45.199564) (xy 331.295703 -45.111271) (xy 331.27651 -45.020486) (xy 331.266877 -44.928196)
			(xy 331.266292 -44.8818) (xy 331.266875 -44.835404) (xy 331.27652 -44.743116) (xy 331.295716 -44.652332)
			(xy 331.324254 -44.564039) (xy 331.342492 -44.521374) (xy 331.346298 -44.511432) (xy 331.346298 -44.490168)
			(xy 331.342492 -44.480226) (xy 331.324247 -44.437564) (xy 331.295703 -44.349271) (xy 331.27651 -44.258486)
			(xy 331.266877 -44.166196) (xy 331.266292 -44.1198) (xy 331.266875 -44.073404) (xy 331.27652 -43.981116)
			(xy 331.295716 -43.890332) (xy 331.324254 -43.802039) (xy 331.342492 -43.759374) (xy 331.346298 -43.749432)
			(xy 331.346298 -43.728168) (xy 331.342492 -43.718226) (xy 331.324247 -43.675564) (xy 331.295703 -43.587271)
			(xy 331.27651 -43.496486) (xy 331.266877 -43.404196) (xy 331.266292 -43.3578) (xy 331.266875 -43.311404)
			(xy 331.27652 -43.219116) (xy 331.295716 -43.128332) (xy 331.324254 -43.040039) (xy 331.342492 -42.997374)
			(xy 331.346298 -42.987432) (xy 331.346298 -42.966168) (xy 331.342492 -42.956226) (xy 331.32427 -42.913623)
			(xy 331.295752 -42.825456) (xy 331.27656 -42.7348) (xy 331.2669 -42.64264) (xy 331.266292 -42.596308)
			(xy 331.266292 -42.5958) (xy 331.266767 -42.554698) (xy 331.274352 -42.472843) (xy 331.289457 -42.392038)
			(xy 331.311953 -42.312971) (xy 331.341649 -42.236317) (xy 331.378291 -42.16273) (xy 331.421566 -42.092838)
			(xy 331.471106 -42.027237) (xy 331.526487 -41.966487) (xy 331.587237 -41.911106) (xy 331.652838 -41.861566)
			(xy 331.72273 -41.818291) (xy 331.796317 -41.781649) (xy 331.872971 -41.751953) (xy 331.952038 -41.729457)
			(xy 332.032843 -41.714352) (xy 332.114698 -41.706767) (xy 332.1558 -41.706292) (xy 332.156308 -41.706292)
			(xy 332.20264 -41.706898) (xy 332.294798 -41.716569) (xy 332.385452 -41.735765) (xy 332.473621 -41.764277)
			(xy 332.516226 -41.782492) (xy 332.526168 -41.786298) (xy 332.547432 -41.786298) (xy 332.557374 -41.782492)
			(xy 332.600036 -41.764247) (xy 332.688329 -41.735703) (xy 332.779114 -41.71651) (xy 332.871404 -41.706877)
			(xy 332.9178 -41.706292) (xy 332.964196 -41.706875) (xy 333.056484 -41.71652) (xy 333.147268 -41.735716)
			(xy 333.235561 -41.764254) (xy 333.278226 -41.782492) (xy 333.288168 -41.786298) (xy 333.309432 -41.786298)
			(xy 333.319374 -41.782492) (xy 333.362036 -41.764247) (xy 333.450329 -41.735703) (xy 333.541114 -41.71651)
			(xy 333.633404 -41.706877) (xy 333.6798 -41.706292) (xy 333.726196 -41.706875) (xy 333.818484 -41.71652)
			(xy 333.909268 -41.735716) (xy 333.997561 -41.764254) (xy 334.040226 -41.782492) (xy 334.050168 -41.786298)
			(xy 334.071432 -41.786298) (xy 334.081374 -41.782492) (xy 334.124036 -41.764247) (xy 334.212329 -41.735703)
			(xy 334.303114 -41.71651) (xy 334.395404 -41.706877) (xy 334.4418 -41.706292) (xy 334.488196 -41.706875)
			(xy 334.580484 -41.71652) (xy 334.671268 -41.735716) (xy 334.759561 -41.764254) (xy 334.802226 -41.782492)
			(xy 334.812168 -41.786298) (xy 334.833432 -41.786298) (xy 334.843374 -41.782492) (xy 334.885977 -41.76427)
			(xy 334.974144 -41.735752) (xy 335.0648 -41.71656) (xy 335.15696 -41.7069) (xy 335.203292 -41.706292)
			(xy 335.2038 -41.706292) (xy 335.244902 -41.706767) (xy 335.326757 -41.714352) (xy 335.407562 -41.729457)
			(xy 335.486629 -41.751953) (xy 335.563283 -41.781649) (xy 335.63687 -41.818291) (xy 335.706762 -41.861566)
			(xy 335.772363 -41.911106) (xy 335.833113 -41.966487) (xy 335.888494 -42.027237) (xy 335.938034 -42.092838)
			(xy 335.981309 -42.16273) (xy 336.017951 -42.236317) (xy 336.047647 -42.312971) (xy 336.070143 -42.392038)
			(xy 336.085248 -42.472843) (xy 336.092833 -42.554698) (xy 336.093308 -42.5958) (xy 336.093308 -42.596308)
			(xy 336.092702 -42.64264) (xy 336.083031 -42.734798) (xy 336.063835 -42.825452) (xy 336.035323 -42.913621)
			(xy 336.017108 -42.956226) (xy 336.013302 -42.966168) (xy 336.013302 -42.987432) (xy 336.017108 -42.997374)
			(xy 336.035353 -43.040036) (xy 336.063897 -43.128329) (xy 336.08309 -43.219114) (xy 336.092723 -43.311404)
			(xy 336.093308 -43.3578) (xy 336.092725 -43.404196) (xy 336.08308 -43.496484) (xy 336.063884 -43.587268)
			(xy 336.035346 -43.675561) (xy 336.017108 -43.718226) (xy 336.013302 -43.728168) (xy 336.013302 -43.749432)
			(xy 336.017108 -43.759374) (xy 336.035353 -43.802036) (xy 336.063897 -43.890329) (xy 336.08309 -43.981114)
			(xy 336.092723 -44.073404) (xy 336.093308 -44.1198) (xy 336.092725 -44.166196) (xy 336.08308 -44.258484)
			(xy 336.063884 -44.349268) (xy 336.035346 -44.437561) (xy 336.017108 -44.480226) (xy 336.013302 -44.490168)
			(xy 336.013302 -44.511432) (xy 336.017108 -44.521374) (xy 336.03533 -44.563977) (xy 336.063848 -44.652144)
			(xy 336.08304 -44.7428) (xy 336.0927 -44.83496) (xy 336.093308 -44.881292) (xy 336.093308 -44.8818)
			(xy 336.092833 -44.922902) (xy 336.085248 -45.004757) (xy 336.070143 -45.085562) (xy 336.047647 -45.164629)
			(xy 336.017951 -45.241283) (xy 335.981309 -45.31487) (xy 335.938034 -45.384762) (xy 335.888494 -45.450363)
			(xy 335.833113 -45.511113) (xy 335.772363 -45.566494) (xy 335.706762 -45.616034) (xy 335.63687 -45.659309)
			(xy 335.563283 -45.695951) (xy 335.486629 -45.725647) (xy 335.407562 -45.748143) (xy 335.326757 -45.763248)
			(xy 335.244902 -45.770833) (xy 335.2038 -45.771308) (xy 335.203292 -45.771308) (xy 335.15696 -45.770702)
			(xy 335.064802 -45.761031) (xy 334.974148 -45.741835) (xy 334.885979 -45.713323) (xy 334.843374 -45.695108)
			(xy 334.833432 -45.691302) (xy 334.812168 -45.691302) (xy 334.802226 -45.695108) (xy 334.769307 -45.709337)
			(xy 334.701622 -45.733057) (xy 334.632242 -45.751237) (xy 334.596994 -45.757846) (xy 334.58687 -45.760144)
			(xy 334.569549 -45.771549) (xy 334.558144 -45.78887) (xy 334.555846 -45.798994) (xy 334.548139 -45.839659)
			(xy 334.526175 -45.919465) (xy 334.496893 -45.996885) (xy 334.460547 -46.071251) (xy 334.417451 -46.14192)
			(xy 334.367977 -46.20828) (xy 334.312554 -46.269759) (xy 334.251659 -46.325823) (xy 334.185821 -46.375989)
			(xy 334.115608 -46.419824) (xy 334.041627 -46.456947) (xy 333.964517 -46.487038) (xy 333.884946 -46.509837)
			(xy 333.803601 -46.525147) (xy 333.721186 -46.532835) (xy 333.6798 -46.533308) (xy 333.679292 -46.533308)
			(xy 333.63296 -46.532702) (xy 333.540802 -46.523031) (xy 333.450148 -46.503835) (xy 333.361979 -46.475323)
			(xy 333.319374 -46.457108) (xy 333.309432 -46.453302) (xy 333.288168 -46.453302) (xy 333.278226 -46.457108)
			(xy 333.235564 -46.475353) (xy 333.147271 -46.503897) (xy 333.056486 -46.52309) (xy 332.964196 -46.532723)
			(xy 332.9178 -46.533308) (xy 332.871404 -46.532725) (xy 332.779116 -46.52308) (xy 332.688332 -46.503884)
			(xy 332.600039 -46.475346) (xy 332.557374 -46.457108) (xy 332.547432 -46.453302) (xy 332.526168 -46.453302)
			(xy 332.516226 -46.457108) (xy 332.473623 -46.47533) (xy 332.385456 -46.503848) (xy 332.2948 -46.52304)
			(xy 332.20264 -46.5327) (xy 332.156308 -46.533308) (xy 332.1558 -46.533308) (xy 332.114698 -46.532833)
			(xy 332.032843 -46.525248) (xy 331.952038 -46.510143) (xy 331.872971 -46.487647) (xy 331.796317 -46.457951)
			(xy 331.72273 -46.421309) (xy 331.652838 -46.378034) (xy 331.587237 -46.328494) (xy 331.526487 -46.273113)
			(xy 331.471106 -46.212363) (xy 331.421566 -46.146762) (xy 331.378291 -46.07687) (xy 331.341649 -46.003283)
			(xy 331.311953 -45.926629) (xy 331.289457 -45.847562) (xy 331.274352 -45.766757) (xy 331.266767 -45.684902)
			(xy 331.266292 -45.6438) (xy 325.12 -45.6438) (xy 325.12 -48.465937) (xy 337.609176 -48.465937) (xy 337.609176 -48.381215)
			(xy 337.617229 -48.296878) (xy 337.633263 -48.213688) (xy 337.657131 -48.132398) (xy 337.688619 -48.053746)
			(xy 337.727441 -47.978443) (xy 337.773244 -47.907171) (xy 337.825615 -47.840575) (xy 337.88408 -47.77926)
			(xy 337.948108 -47.723779) (xy 338.01712 -47.674636) (xy 338.09049 -47.632276) (xy 338.167555 -47.597081)
			(xy 338.247617 -47.569372) (xy 338.32995 -47.549398) (xy 338.413809 -47.537341) (xy 338.498434 -47.53331)
			(xy 338.583059 -47.537341) (xy 338.666918 -47.549398) (xy 338.749251 -47.569372) (xy 338.829313 -47.597081)
			(xy 338.906378 -47.632276) (xy 338.979748 -47.674636) (xy 339.04876 -47.723779) (xy 339.112788 -47.77926)
			(xy 339.171253 -47.840575) (xy 339.223624 -47.907171) (xy 339.269427 -47.978443) (xy 339.308249 -48.053746)
			(xy 339.339737 -48.132398) (xy 339.363605 -48.213688) (xy 339.379639 -48.296878) (xy 339.387692 -48.381215)
			(xy 339.388196 -48.423576) (xy 339.387692 -48.465937) (xy 339.379639 -48.550274) (xy 339.363605 -48.633464)
			(xy 339.339737 -48.714754) (xy 339.308249 -48.793406) (xy 339.269427 -48.868709) (xy 339.223624 -48.939981)
			(xy 339.171253 -49.006577) (xy 339.112788 -49.067892) (xy 339.04876 -49.123373) (xy 338.979748 -49.172516)
			(xy 338.906378 -49.214876) (xy 338.829313 -49.250071) (xy 338.749251 -49.27778) (xy 338.666918 -49.297754)
			(xy 338.583059 -49.309811) (xy 338.498434 -49.313843) (xy 338.413809 -49.309811) (xy 338.32995 -49.297754)
			(xy 338.247617 -49.27778) (xy 338.167555 -49.250071) (xy 338.09049 -49.214876) (xy 338.01712 -49.172516)
			(xy 337.948108 -49.123373) (xy 337.88408 -49.067892) (xy 337.825615 -49.006577) (xy 337.773244 -48.939981)
			(xy 337.727441 -48.868709) (xy 337.688619 -48.793406) (xy 337.657131 -48.714754) (xy 337.633263 -48.633464)
			(xy 337.617229 -48.550274) (xy 337.609176 -48.465937) (xy 325.12 -48.465937) (xy 325.12 -51.065431)
			(xy 334.477997 -51.065431) (xy 334.483261 -50.981746) (xy 334.496377 -50.898928) (xy 334.517229 -50.817712)
			(xy 334.545631 -50.738818) (xy 334.581332 -50.662948) (xy 334.624014 -50.590773) (xy 334.673299 -50.522936)
			(xy 334.728749 -50.460038) (xy 334.789873 -50.402638) (xy 334.856127 -50.351245) (xy 334.926923 -50.306314)
			(xy 335.001634 -50.268246) (xy 335.079595 -50.237377) (xy 335.160116 -50.213982) (xy 335.242481 -50.198269)
			(xy 335.325959 -50.190376) (xy 335.367884 -50.189892) (xy 335.368392 -50.189892) (xy 335.404819 -50.190266)
			(xy 335.477428 -50.196241) (xy 335.513426 -50.20183) (xy 335.528472 -50.203765) (xy 335.558521 -50.199719)
			(xy 335.586063 -50.187041) (xy 335.608678 -50.166846) (xy 335.624379 -50.140908) (xy 335.631785 -50.111506)
			(xy 335.630246 -50.081226) (xy 335.619897 -50.052727) (xy 335.611216 -50.040286) (xy 335.586864 -50.007213)
			(xy 335.543671 -49.937352) (xy 335.507099 -49.863806) (xy 335.477461 -49.787204) (xy 335.455009 -49.708196)
			(xy 335.439934 -49.627455) (xy 335.432365 -49.545668) (xy 335.431892 -49.5046) (xy 335.432376 -49.462675)
			(xy 335.440267 -49.379196) (xy 335.455979 -49.296831) (xy 335.479372 -49.216309) (xy 335.51024 -49.138347)
			(xy 335.548307 -49.063636) (xy 335.593237 -48.992838) (xy 335.644629 -48.926583) (xy 335.702029 -48.865459)
			(xy 335.764926 -48.810007) (xy 335.832763 -48.760721) (xy 335.904937 -48.718038) (xy 335.980807 -48.682336)
			(xy 336.0597 -48.653932) (xy 336.140917 -48.633079) (xy 336.223735 -48.619962) (xy 336.30742 -48.614697)
			(xy 336.39123 -48.617331) (xy 336.474419 -48.62784) (xy 336.55625 -48.646132) (xy 336.635997 -48.672043)
			(xy 336.712951 -48.705344) (xy 336.78643 -48.74574) (xy 336.855782 -48.792871) (xy 336.92039 -48.846319)
			(xy 336.979681 -48.90561) (xy 337.033129 -48.970218) (xy 337.08026 -49.03957) (xy 337.120656 -49.113049)
			(xy 337.153957 -49.190003) (xy 337.179868 -49.26975) (xy 337.19816 -49.351581) (xy 337.208669 -49.43477)
			(xy 337.211303 -49.51858) (xy 337.206038 -49.602265) (xy 337.192921 -49.685083) (xy 337.172068 -49.7663)
			(xy 337.143664 -49.845193) (xy 337.107962 -49.921063) (xy 337.065279 -49.993237) (xy 337.015993 -50.061074)
			(xy 336.960541 -50.123971) (xy 336.899417 -50.181371) (xy 336.833162 -50.232763) (xy 336.762364 -50.277693)
			(xy 336.687653 -50.31576) (xy 336.609691 -50.346628) (xy 336.529169 -50.370021) (xy 336.446804 -50.385733)
			(xy 336.363325 -50.393624) (xy 336.3214 -50.394108) (xy 336.320892 -50.394108) (xy 336.284465 -50.393736)
			(xy 336.211856 -50.387759) (xy 336.175858 -50.38217) (xy 336.160814 -50.380222) (xy 336.130765 -50.384272)
			(xy 336.103223 -50.396952) (xy 336.080609 -50.417149) (xy 336.064909 -50.443089) (xy 336.057502 -50.472491)
			(xy 336.05904 -50.502772) (xy 336.069388 -50.531272) (xy 336.078068 -50.543714) (xy 336.102418 -50.576788)
			(xy 336.145612 -50.64665) (xy 336.182184 -50.720194) (xy 336.211822 -50.796797) (xy 336.234274 -50.875805)
			(xy 336.242505 -50.919888) (xy 377.061232 -50.919888) (xy 377.065214 -50.829938) (xy 377.077131 -50.740691)
			(xy 377.096889 -50.652847) (xy 377.124333 -50.567093) (xy 377.159249 -50.4841) (xy 377.201363 -50.404518)
			(xy 377.250346 -50.328969) (xy 377.305814 -50.258045) (xy 377.367334 -50.1923) (xy 377.434423 -50.13225)
			(xy 377.506557 -50.078365) (xy 377.583171 -50.031065) (xy 377.663665 -49.990722) (xy 377.74741 -49.95765)
			(xy 377.833751 -49.93211) (xy 377.92201 -49.9143) (xy 378.011499 -49.90436) (xy 378.101515 -49.902369)
			(xy 378.191356 -49.90834) (xy 378.280317 -49.922229) (xy 378.367702 -49.943925) (xy 378.452828 -49.97326)
			(xy 378.535028 -50.010003) (xy 378.613659 -50.053867) (xy 378.688106 -50.104509) (xy 378.757786 -50.161533)
			(xy 378.822153 -50.224492) (xy 378.880704 -50.292893) (xy 378.932981 -50.366201) (xy 378.978574 -50.443843)
			(xy 379.017127 -50.52521) (xy 379.048338 -50.609666) (xy 379.071962 -50.69655) (xy 379.087815 -50.785182)
			(xy 379.095772 -50.874869) (xy 379.09627 -50.919888) (xy 396.619232 -50.919888) (xy 396.623214 -50.829938)
			(xy 396.635131 -50.740691) (xy 396.654889 -50.652847) (xy 396.682333 -50.567093) (xy 396.717249 -50.4841)
			(xy 396.759363 -50.404518) (xy 396.808346 -50.328969) (xy 396.863814 -50.258045) (xy 396.925334 -50.1923)
			(xy 396.992423 -50.13225) (xy 397.064557 -50.078365) (xy 397.141171 -50.031065) (xy 397.221665 -49.990722)
			(xy 397.30541 -49.95765) (xy 397.391751 -49.93211) (xy 397.48001 -49.9143) (xy 397.569499 -49.90436)
			(xy 397.659515 -49.902369) (xy 397.749356 -49.90834) (xy 397.838317 -49.922229) (xy 397.925702 -49.943925)
			(xy 398.010828 -49.97326) (xy 398.093028 -50.010003) (xy 398.171659 -50.053867) (xy 398.246106 -50.104509)
			(xy 398.315786 -50.161533) (xy 398.380153 -50.224492) (xy 398.438704 -50.292893) (xy 398.490981 -50.366201)
			(xy 398.536574 -50.443843) (xy 398.575127 -50.52521) (xy 398.606338 -50.609666) (xy 398.629962 -50.69655)
			(xy 398.645815 -50.785182) (xy 398.653772 -50.874869) (xy 398.65427 -50.919888) (xy 398.653772 -50.964907)
			(xy 398.645815 -51.054594) (xy 398.629962 -51.143226) (xy 398.606338 -51.23011) (xy 398.575127 -51.314566)
			(xy 398.536574 -51.395933) (xy 398.490981 -51.473575) (xy 398.438704 -51.546883) (xy 398.380153 -51.615284)
			(xy 398.315786 -51.678243) (xy 398.246106 -51.735267) (xy 398.171659 -51.785909) (xy 398.093028 -51.829773)
			(xy 398.010828 -51.866516) (xy 397.925702 -51.895851) (xy 397.838317 -51.917547) (xy 397.749356 -51.931436)
			(xy 397.659515 -51.937407) (xy 397.569499 -51.935416) (xy 397.48001 -51.925476) (xy 397.391751 -51.907666)
			(xy 397.30541 -51.882126) (xy 397.221665 -51.849054) (xy 397.141171 -51.808711) (xy 397.064557 -51.761411)
			(xy 396.992423 -51.707526) (xy 396.925334 -51.647476) (xy 396.863814 -51.581731) (xy 396.808346 -51.510807)
			(xy 396.759363 -51.435258) (xy 396.717249 -51.355676) (xy 396.682333 -51.272683) (xy 396.654889 -51.186929)
			(xy 396.635131 -51.099085) (xy 396.623214 -51.009838) (xy 396.619232 -50.919888) (xy 379.09627 -50.919888)
			(xy 379.095772 -50.964907) (xy 379.087815 -51.054594) (xy 379.071962 -51.143226) (xy 379.048338 -51.23011)
			(xy 379.017127 -51.314566) (xy 378.978574 -51.395933) (xy 378.932981 -51.473575) (xy 378.880704 -51.546883)
			(xy 378.822153 -51.615284) (xy 378.757786 -51.678243) (xy 378.688106 -51.735267) (xy 378.613659 -51.785909)
			(xy 378.535028 -51.829773) (xy 378.452828 -51.866516) (xy 378.367702 -51.895851) (xy 378.280317 -51.917547)
			(xy 378.191356 -51.931436) (xy 378.101515 -51.937407) (xy 378.011499 -51.935416) (xy 377.92201 -51.925476)
			(xy 377.833751 -51.907666) (xy 377.74741 -51.882126) (xy 377.663665 -51.849054) (xy 377.583171 -51.808711)
			(xy 377.506557 -51.761411) (xy 377.434423 -51.707526) (xy 377.367334 -51.647476) (xy 377.305814 -51.581731)
			(xy 377.250346 -51.510807) (xy 377.201363 -51.435258) (xy 377.159249 -51.355676) (xy 377.124333 -51.272683)
			(xy 377.096889 -51.186929) (xy 377.077131 -51.099085) (xy 377.065214 -51.009838) (xy 377.061232 -50.919888)
			(xy 336.242505 -50.919888) (xy 336.249349 -50.956545) (xy 336.256919 -51.038332) (xy 336.257392 -51.0794)
			(xy 336.256924 -51.121325) (xy 336.249033 -51.204803) (xy 336.233322 -51.287169) (xy 336.209928 -51.367689)
			(xy 336.179061 -51.445652) (xy 336.140994 -51.520363) (xy 336.096065 -51.59116) (xy 336.044672 -51.657415)
			(xy 335.987273 -51.718539) (xy 335.924376 -51.773991) (xy 335.85654 -51.823277) (xy 335.784367 -51.865961)
			(xy 335.708497 -51.901663) (xy 335.629604 -51.930066) (xy 335.548388 -51.95092) (xy 335.46557 -51.964037)
			(xy 335.381885 -51.969303) (xy 335.298076 -51.966669) (xy 335.214887 -51.956161) (xy 335.133056 -51.93787)
			(xy 335.053309 -51.911959) (xy 334.976355 -51.878659) (xy 334.902876 -51.838264) (xy 334.833525 -51.791134)
			(xy 334.768916 -51.737686) (xy 334.709625 -51.678396) (xy 334.656176 -51.613788) (xy 334.609044 -51.544438)
			(xy 334.568648 -51.47096) (xy 334.535346 -51.394006) (xy 334.509434 -51.31426) (xy 334.491142 -51.232429)
			(xy 334.480632 -51.14924) (xy 334.477997 -51.065431) (xy 325.12 -51.065431) (xy 325.12 -56.9214)
			(xy 331.266292 -56.9214) (xy 331.266292 -56.920892) (xy 331.266898 -56.87456) (xy 331.276569 -56.782402)
			(xy 331.295765 -56.691748) (xy 331.324277 -56.603579) (xy 331.342492 -56.560974) (xy 331.346298 -56.551032)
			(xy 331.346298 -56.529768) (xy 331.342492 -56.519826) (xy 331.324247 -56.477164) (xy 331.295703 -56.388871)
			(xy 331.27651 -56.298086) (xy 331.266877 -56.205796) (xy 331.266292 -56.1594) (xy 331.266875 -56.113004)
			(xy 331.27652 -56.020716) (xy 331.295716 -55.929932) (xy 331.324254 -55.841639) (xy 331.342492 -55.798974)
			(xy 331.346298 -55.789032) (xy 331.346298 -55.767768) (xy 331.342492 -55.757826) (xy 331.324247 -55.715164)
			(xy 331.295703 -55.626871) (xy 331.27651 -55.536086) (xy 331.266877 -55.443796) (xy 331.266292 -55.3974)
			(xy 331.266875 -55.351004) (xy 331.27652 -55.258716) (xy 331.295716 -55.167932) (xy 331.324254 -55.079639)
			(xy 331.342492 -55.036974) (xy 331.346298 -55.027032) (xy 331.346298 -55.005768) (xy 331.342492 -54.995826)
			(xy 331.324247 -54.953164) (xy 331.295703 -54.864871) (xy 331.27651 -54.774086) (xy 331.266877 -54.681796)
			(xy 331.266292 -54.6354) (xy 331.266875 -54.589004) (xy 331.27652 -54.496716) (xy 331.295716 -54.405932)
			(xy 331.324254 -54.317639) (xy 331.342492 -54.274974) (xy 331.346298 -54.265032) (xy 331.346298 -54.243768)
			(xy 331.342492 -54.233826) (xy 331.32427 -54.191223) (xy 331.295752 -54.103056) (xy 331.27656 -54.0124)
			(xy 331.2669 -53.92024) (xy 331.266292 -53.873908) (xy 331.266292 -53.8734) (xy 331.266767 -53.832298)
			(xy 331.274352 -53.750443) (xy 331.289457 -53.669638) (xy 331.311953 -53.590571) (xy 331.341649 -53.513917)
			(xy 331.378291 -53.44033) (xy 331.421566 -53.370438) (xy 331.471106 -53.304837) (xy 331.526487 -53.244087)
			(xy 331.587237 -53.188706) (xy 331.652838 -53.139166) (xy 331.72273 -53.095891) (xy 331.796317 -53.059249)
			(xy 331.872971 -53.029553) (xy 331.952038 -53.007057) (xy 332.032843 -52.991952) (xy 332.114698 -52.984367)
			(xy 332.1558 -52.983892) (xy 332.156308 -52.983892) (xy 332.20264 -52.984498) (xy 332.294798 -52.994169)
			(xy 332.385452 -53.013365) (xy 332.473621 -53.041877) (xy 332.516226 -53.060092) (xy 332.526168 -53.063898)
			(xy 332.547432 -53.063898) (xy 332.557374 -53.060092) (xy 332.600036 -53.041847) (xy 332.688329 -53.013303)
			(xy 332.779114 -52.99411) (xy 332.871404 -52.984477) (xy 332.9178 -52.983892) (xy 332.964196 -52.984475)
			(xy 333.056484 -52.99412) (xy 333.147268 -53.013316) (xy 333.235561 -53.041854) (xy 333.278226 -53.060092)
			(xy 333.288168 -53.063898) (xy 333.309432 -53.063898) (xy 333.319374 -53.060092) (xy 333.362036 -53.041847)
			(xy 333.450329 -53.013303) (xy 333.541114 -52.99411) (xy 333.633404 -52.984477) (xy 333.6798 -52.983892)
			(xy 333.726196 -52.984475) (xy 333.818484 -52.99412) (xy 333.909268 -53.013316) (xy 333.997561 -53.041854)
			(xy 334.040226 -53.060092) (xy 334.050168 -53.063898) (xy 334.071432 -53.063898) (xy 334.081374 -53.060092)
			(xy 334.124036 -53.041847) (xy 334.212329 -53.013303) (xy 334.303114 -52.99411) (xy 334.395404 -52.984477)
			(xy 334.4418 -52.983892) (xy 334.488196 -52.984475) (xy 334.580484 -52.99412) (xy 334.671268 -53.013316)
			(xy 334.759561 -53.041854) (xy 334.802226 -53.060092) (xy 334.812168 -53.063898) (xy 334.833432 -53.063898)
			(xy 334.843374 -53.060092) (xy 334.885977 -53.04187) (xy 334.974144 -53.013352) (xy 335.0648 -52.99416)
			(xy 335.15696 -52.9845) (xy 335.203292 -52.983892) (xy 335.2038 -52.983892) (xy 335.244902 -52.984367)
			(xy 335.326757 -52.991952) (xy 335.407562 -53.007057) (xy 335.486629 -53.029553) (xy 335.563283 -53.059249)
			(xy 335.63687 -53.095891) (xy 335.706762 -53.139166) (xy 335.772363 -53.188706) (xy 335.833113 -53.244087)
			(xy 335.888494 -53.304837) (xy 335.938034 -53.370438) (xy 335.981309 -53.44033) (xy 336.017951 -53.513917)
			(xy 336.047647 -53.590571) (xy 336.070143 -53.669638) (xy 336.085248 -53.750443) (xy 336.092833 -53.832298)
			(xy 336.093308 -53.8734) (xy 336.093308 -53.873908) (xy 336.092702 -53.92024) (xy 336.083031 -54.012398)
			(xy 336.063835 -54.103052) (xy 336.035323 -54.191221) (xy 336.017108 -54.233826) (xy 336.013302 -54.243768)
			(xy 336.013302 -54.265032) (xy 336.017108 -54.274974) (xy 336.035353 -54.317636) (xy 336.063897 -54.405929)
			(xy 336.08309 -54.496714) (xy 336.092723 -54.589004) (xy 336.093308 -54.6354) (xy 336.092725 -54.681796)
			(xy 336.08308 -54.774084) (xy 336.063884 -54.864868) (xy 336.035346 -54.953161) (xy 336.017108 -54.995826)
			(xy 336.013302 -55.005768) (xy 336.013302 -55.027032) (xy 336.017108 -55.036974) (xy 336.035353 -55.079636)
			(xy 336.063897 -55.167929) (xy 336.08309 -55.258714) (xy 336.092723 -55.351004) (xy 336.093308 -55.3974)
			(xy 336.092725 -55.443796) (xy 336.08308 -55.536084) (xy 336.063884 -55.626868) (xy 336.035346 -55.715161)
			(xy 336.017108 -55.757826) (xy 336.013302 -55.767768) (xy 336.013302 -55.789032) (xy 336.017108 -55.798974)
			(xy 336.035353 -55.841636) (xy 336.063897 -55.929929) (xy 336.076593 -55.989982) (xy 468.668363 -55.989982)
			(xy 468.672353 -55.876999) (xy 468.684302 -55.764578) (xy 468.704152 -55.653281) (xy 468.731804 -55.543661)
			(xy 468.767118 -55.436264) (xy 468.809921 -55.331626) (xy 468.859998 -55.230268) (xy 468.9171 -55.132695)
			(xy 468.980942 -55.039393) (xy 469.051207 -54.950827) (xy 469.127544 -54.867437) (xy 469.209573 -54.78964)
			(xy 469.296886 -54.717823) (xy 469.389047 -54.652344) (xy 469.485597 -54.593529) (xy 469.586055 -54.541671)
			(xy 469.689922 -54.497029) (xy 469.796678 -54.459824) (xy 469.905793 -54.430242) (xy 470.016723 -54.408431)
			(xy 470.128915 -54.3945) (xy 470.24181 -54.388516) (xy 470.354846 -54.390512) (xy 470.46746 -54.400475)
			(xy 470.579091 -54.418358) (xy 470.689182 -54.44407) (xy 470.797185 -54.477484) (xy 470.902562 -54.518433)
			(xy 471.004788 -54.566714) (xy 471.103353 -54.622085) (xy 471.197768 -54.68427) (xy 471.28756 -54.752961)
			(xy 471.372284 -54.827815) (xy 471.451517 -54.908458) (xy 471.524863 -54.99449) (xy 471.591959 -55.085481)
			(xy 471.652468 -55.180978) (xy 471.706091 -55.280505) (xy 471.75256 -55.383568) (xy 471.791643 -55.489651)
			(xy 471.823146 -55.598227) (xy 471.846911 -55.708754) (xy 471.862821 -55.820683) (xy 471.870795 -55.933455)
			(xy 471.871294 -55.989982) (xy 471.870795 -56.046509) (xy 471.862821 -56.159281) (xy 471.846911 -56.27121)
			(xy 471.823146 -56.381737) (xy 471.791643 -56.490313) (xy 471.75256 -56.596396) (xy 471.706091 -56.699459)
			(xy 471.652468 -56.798986) (xy 471.591959 -56.894483) (xy 471.524863 -56.985474) (xy 471.451517 -57.071506)
			(xy 471.372284 -57.152149) (xy 471.28756 -57.227003) (xy 471.197768 -57.295694) (xy 471.103353 -57.357879)
			(xy 471.004788 -57.41325) (xy 470.902562 -57.461531) (xy 470.797185 -57.50248) (xy 470.689182 -57.535894)
			(xy 470.579091 -57.561606) (xy 470.46746 -57.579489) (xy 470.354846 -57.589452) (xy 470.24181 -57.591448)
			(xy 470.128915 -57.585464) (xy 470.016723 -57.571533) (xy 469.905793 -57.549722) (xy 469.796678 -57.52014)
			(xy 469.689922 -57.482935) (xy 469.586055 -57.438293) (xy 469.485597 -57.386435) (xy 469.389047 -57.32762)
			(xy 469.296886 -57.262141) (xy 469.209573 -57.190324) (xy 469.127544 -57.112527) (xy 469.051207 -57.029137)
			(xy 468.980942 -56.940571) (xy 468.9171 -56.847269) (xy 468.859998 -56.749696) (xy 468.809921 -56.648338)
			(xy 468.767118 -56.5437) (xy 468.731804 -56.436303) (xy 468.704152 -56.326683) (xy 468.684302 -56.215386)
			(xy 468.672353 -56.102965) (xy 468.668363 -55.989982) (xy 336.076593 -55.989982) (xy 336.08309 -56.020714)
			(xy 336.092723 -56.113004) (xy 336.093308 -56.1594) (xy 336.092725 -56.205796) (xy 336.08308 -56.298084)
			(xy 336.063884 -56.388868) (xy 336.035346 -56.477161) (xy 336.017108 -56.519826) (xy 336.013302 -56.529768)
			(xy 336.013302 -56.551032) (xy 336.017108 -56.560974) (xy 336.03533 -56.603577) (xy 336.063848 -56.691744)
			(xy 336.08304 -56.7824) (xy 336.0927 -56.87456) (xy 336.093308 -56.920892) (xy 336.093308 -56.9214)
			(xy 336.092833 -56.962502) (xy 336.085248 -57.044357) (xy 336.070143 -57.125162) (xy 336.047647 -57.204229)
			(xy 336.017951 -57.280883) (xy 335.981309 -57.35447) (xy 335.938034 -57.424362) (xy 335.888494 -57.489963)
			(xy 335.833113 -57.550713) (xy 335.772363 -57.606094) (xy 335.706762 -57.655634) (xy 335.63687 -57.698909)
			(xy 335.563283 -57.735551) (xy 335.486629 -57.765247) (xy 335.407562 -57.787743) (xy 335.326757 -57.802848)
			(xy 335.244902 -57.810433) (xy 335.2038 -57.810908) (xy 335.203292 -57.810908) (xy 335.15696 -57.810302)
			(xy 335.064802 -57.800631) (xy 334.974148 -57.781435) (xy 334.885979 -57.752923) (xy 334.843374 -57.734708)
			(xy 334.833432 -57.730902) (xy 334.812168 -57.730902) (xy 334.802226 -57.734708) (xy 334.759564 -57.752953)
			(xy 334.671271 -57.781497) (xy 334.580486 -57.80069) (xy 334.488196 -57.810323) (xy 334.4418 -57.810908)
			(xy 334.395404 -57.810325) (xy 334.303116 -57.80068) (xy 334.212332 -57.781484) (xy 334.124039 -57.752946)
			(xy 334.081374 -57.734708) (xy 334.071432 -57.730902) (xy 334.050168 -57.730902) (xy 334.040226 -57.734708)
			(xy 333.997564 -57.752953) (xy 333.909271 -57.781497) (xy 333.818486 -57.80069) (xy 333.726196 -57.810323)
			(xy 333.6798 -57.810908) (xy 333.633404 -57.810325) (xy 333.541116 -57.80068) (xy 333.450332 -57.781484)
			(xy 333.362039 -57.752946) (xy 333.319374 -57.734708) (xy 333.309432 -57.730902) (xy 333.288168 -57.730902)
			(xy 333.278226 -57.734708) (xy 333.235564 -57.752953) (xy 333.147271 -57.781497) (xy 333.056486 -57.80069)
			(xy 332.964196 -57.810323) (xy 332.9178 -57.810908) (xy 332.871404 -57.810325) (xy 332.779116 -57.80068)
			(xy 332.688332 -57.781484) (xy 332.600039 -57.752946) (xy 332.557374 -57.734708) (xy 332.547432 -57.730902)
			(xy 332.526168 -57.730902) (xy 332.516226 -57.734708) (xy 332.473623 -57.75293) (xy 332.385456 -57.781448)
			(xy 332.2948 -57.80064) (xy 332.20264 -57.8103) (xy 332.156308 -57.810908) (xy 332.1558 -57.810908)
			(xy 332.114698 -57.810433) (xy 332.032843 -57.802848) (xy 331.952038 -57.787743) (xy 331.872971 -57.765247)
			(xy 331.796317 -57.735551) (xy 331.72273 -57.698909) (xy 331.652838 -57.655634) (xy 331.587237 -57.606094)
			(xy 331.526487 -57.550713) (xy 331.471106 -57.489963) (xy 331.421566 -57.424362) (xy 331.378291 -57.35447)
			(xy 331.341649 -57.280883) (xy 331.311953 -57.204229) (xy 331.289457 -57.125162) (xy 331.274352 -57.044357)
			(xy 331.266767 -56.962502) (xy 331.266292 -56.9214) (xy 325.12 -56.9214) (xy 325.12 -58.42) (xy 376.553741 -58.42)
			(xy 376.557716 -58.309941) (xy 376.569624 -58.200455) (xy 376.5894 -58.092114) (xy 376.616943 -57.985483)
			(xy 376.652108 -57.881117) (xy 376.694712 -57.77956) (xy 376.744533 -57.681343) (xy 376.801312 -57.586976)
			(xy 376.864751 -57.496952) (xy 376.934522 -57.411741) (xy 377.010259 -57.331786) (xy 377.091568 -57.257505)
			(xy 377.178025 -57.189285) (xy 377.269179 -57.12748) (xy 377.364556 -57.072415) (xy 377.463657 -57.024375)
			(xy 377.565966 -56.983611) (xy 377.67095 -56.950336) (xy 377.778061 -56.924723) (xy 377.886741 -56.906906)
			(xy 377.996424 -56.896977) (xy 378.106537 -56.894989) (xy 378.216507 -56.900951) (xy 378.32576 -56.914833)
			(xy 378.433726 -56.936563) (xy 378.539843 -56.966026) (xy 378.643557 -57.003069) (xy 378.744328 -57.0475)
			(xy 378.84163 -57.099087) (xy 378.934956 -57.157559) (xy 379.023819 -57.222614) (xy 379.107757 -57.293912)
			(xy 379.186332 -57.37108) (xy 379.259133 -57.453717) (xy 379.325781 -57.541391) (xy 379.38593 -57.633647)
			(xy 379.439264 -57.730002) (xy 379.485507 -57.829954) (xy 379.524417 -57.932982) (xy 379.555791 -58.03855)
			(xy 379.579466 -58.146106) (xy 379.595318 -58.25509) (xy 379.603265 -58.364934) (xy 379.603762 -58.42)
			(xy 396.111741 -58.42) (xy 396.115716 -58.309941) (xy 396.127624 -58.200455) (xy 396.1474 -58.092114)
			(xy 396.174943 -57.985483) (xy 396.210108 -57.881117) (xy 396.252712 -57.77956) (xy 396.302533 -57.681343)
			(xy 396.359312 -57.586976) (xy 396.422751 -57.496952) (xy 396.492522 -57.411741) (xy 396.568259 -57.331786)
			(xy 396.649568 -57.257505) (xy 396.736025 -57.189285) (xy 396.827179 -57.12748) (xy 396.922556 -57.072415)
			(xy 397.021657 -57.024375) (xy 397.123966 -56.983611) (xy 397.22895 -56.950336) (xy 397.336061 -56.924723)
			(xy 397.444741 -56.906906) (xy 397.554424 -56.896977) (xy 397.664537 -56.894989) (xy 397.774507 -56.900951)
			(xy 397.88376 -56.914833) (xy 397.991726 -56.936563) (xy 398.097843 -56.966026) (xy 398.201557 -57.003069)
			(xy 398.302328 -57.0475) (xy 398.39963 -57.099087) (xy 398.492956 -57.157559) (xy 398.581819 -57.222614)
			(xy 398.665757 -57.293912) (xy 398.744332 -57.37108) (xy 398.817133 -57.453717) (xy 398.883781 -57.541391)
			(xy 398.94393 -57.633647) (xy 398.997264 -57.730002) (xy 399.043507 -57.829954) (xy 399.082417 -57.932982)
			(xy 399.113791 -58.03855) (xy 399.137466 -58.146106) (xy 399.153318 -58.25509) (xy 399.161265 -58.364934)
			(xy 399.161762 -58.42) (xy 399.161265 -58.475066) (xy 399.153318 -58.58491) (xy 399.137466 -58.693894)
			(xy 399.113791 -58.80145) (xy 399.082417 -58.907018) (xy 399.043507 -59.010046) (xy 398.997264 -59.109998)
			(xy 398.94393 -59.206353) (xy 398.883781 -59.298609) (xy 398.817133 -59.386283) (xy 398.744332 -59.46892)
			(xy 398.665757 -59.546088) (xy 398.581819 -59.617386) (xy 398.492956 -59.682441) (xy 398.39963 -59.740913)
			(xy 398.302328 -59.7925) (xy 398.201557 -59.836931) (xy 398.097843 -59.873974) (xy 397.991726 -59.903437)
			(xy 397.88376 -59.925167) (xy 397.774507 -59.939049) (xy 397.664537 -59.945011) (xy 397.554424 -59.943023)
			(xy 397.444741 -59.933094) (xy 397.336061 -59.915277) (xy 397.22895 -59.889664) (xy 397.123966 -59.856389)
			(xy 397.021657 -59.815625) (xy 396.922556 -59.767585) (xy 396.827179 -59.71252) (xy 396.736025 -59.650715)
			(xy 396.649568 -59.582495) (xy 396.568259 -59.508214) (xy 396.492522 -59.428259) (xy 396.422751 -59.343048)
			(xy 396.359312 -59.253024) (xy 396.302533 -59.158657) (xy 396.252712 -59.06044) (xy 396.210108 -58.958883)
			(xy 396.174943 -58.854517) (xy 396.1474 -58.747886) (xy 396.127624 -58.639545) (xy 396.115716 -58.530059)
			(xy 396.111741 -58.42) (xy 379.603762 -58.42) (xy 379.603265 -58.475066) (xy 379.595318 -58.58491)
			(xy 379.579466 -58.693894) (xy 379.555791 -58.80145) (xy 379.524417 -58.907018) (xy 379.485507 -59.010046)
			(xy 379.439264 -59.109998) (xy 379.38593 -59.206353) (xy 379.325781 -59.298609) (xy 379.259133 -59.386283)
			(xy 379.186332 -59.46892) (xy 379.107757 -59.546088) (xy 379.023819 -59.617386) (xy 378.934956 -59.682441)
			(xy 378.84163 -59.740913) (xy 378.744328 -59.7925) (xy 378.643557 -59.836931) (xy 378.539843 -59.873974)
			(xy 378.433726 -59.903437) (xy 378.32576 -59.925167) (xy 378.216507 -59.939049) (xy 378.106537 -59.945011)
			(xy 377.996424 -59.943023) (xy 377.886741 -59.933094) (xy 377.778061 -59.915277) (xy 377.67095 -59.889664)
			(xy 377.565966 -59.856389) (xy 377.463657 -59.815625) (xy 377.364556 -59.767585) (xy 377.269179 -59.71252)
			(xy 377.178025 -59.650715) (xy 377.091568 -59.582495) (xy 377.010259 -59.508214) (xy 376.934522 -59.428259)
			(xy 376.864751 -59.343048) (xy 376.801312 -59.253024) (xy 376.744533 -59.158657) (xy 376.694712 -59.06044)
			(xy 376.652108 -58.958883) (xy 376.616943 -58.854517) (xy 376.5894 -58.747886) (xy 376.569624 -58.639545)
			(xy 376.557716 -58.530059) (xy 376.553741 -58.42) (xy 325.12 -58.42) (xy 325.12 -60.099956) (xy 422.484046 -60.099956)
			(xy 422.488076 -59.957621) (xy 422.500151 -59.815741) (xy 422.520234 -59.674773) (xy 422.548261 -59.535166)
			(xy 422.584141 -59.397368) (xy 422.627759 -59.261821) (xy 422.678976 -59.128959) (xy 422.737627 -58.999207)
			(xy 422.803525 -58.872981) (xy 422.876459 -58.750685) (xy 422.956196 -58.632712) (xy 423.042478 -58.519439)
			(xy 423.135031 -58.411228) (xy 423.233558 -58.308427) (xy 423.337743 -58.211365) (xy 423.447252 -58.120353)
			(xy 423.561735 -58.035681) (xy 423.680825 -57.957623) (xy 423.80414 -57.886427) (xy 423.931286 -57.822321)
			(xy 424.061855 -57.765512) (xy 424.195429 -57.71618) (xy 424.33158 -57.674484) (xy 424.469871 -57.640558)
			(xy 424.609861 -57.61451) (xy 424.7511 -57.596424) (xy 424.893136 -57.586357) (xy 425.035514 -57.584342)
			(xy 425.177778 -57.590385) (xy 425.319472 -57.604467) (xy 425.460142 -57.626543) (xy 425.599339 -57.656543)
			(xy 425.736615 -57.694369) (xy 425.871531 -57.739901) (xy 426.003655 -57.792992) (xy 426.132564 -57.853474)
			(xy 426.257845 -57.921152) (xy 426.379096 -57.995809) (xy 426.495929 -58.077207) (xy 426.60797 -58.165084)
			(xy 426.71486 -58.259159) (xy 426.816257 -58.359131) (xy 426.911835 -58.464679) (xy 427.001289 -58.575465)
			(xy 427.084331 -58.691134) (xy 427.160697 -58.811317) (xy 427.230141 -58.935627) (xy 427.292441 -59.063668)
			(xy 427.347397 -59.195027) (xy 427.394834 -59.329286) (xy 427.434598 -59.466013) (xy 427.466564 -59.604771)
			(xy 427.490629 -59.745115) (xy 427.506715 -59.886596) (xy 427.51477 -60.02876) (xy 427.515274 -60.099956)
			(xy 427.51477 -60.171152) (xy 427.506715 -60.313316) (xy 427.490629 -60.454797) (xy 427.466564 -60.595141)
			(xy 427.434598 -60.733899) (xy 427.394834 -60.870626) (xy 427.347397 -61.004885) (xy 427.292441 -61.136244)
			(xy 427.230141 -61.264285) (xy 427.160697 -61.388595) (xy 427.084331 -61.508778) (xy 427.001289 -61.624447)
			(xy 426.911835 -61.735233) (xy 426.816257 -61.840781) (xy 426.71486 -61.940753) (xy 426.60797 -62.034828)
			(xy 426.495929 -62.122705) (xy 426.379096 -62.204103) (xy 426.257845 -62.27876) (xy 426.132564 -62.346438)
			(xy 426.003655 -62.40692) (xy 425.871531 -62.460011) (xy 425.736615 -62.505543) (xy 425.599339 -62.543369)
			(xy 425.460142 -62.573369) (xy 425.319472 -62.595445) (xy 425.177778 -62.609527) (xy 425.035514 -62.61557)
			(xy 424.893136 -62.613555) (xy 424.7511 -62.603488) (xy 424.609861 -62.585402) (xy 424.469871 -62.559354)
			(xy 424.33158 -62.525428) (xy 424.195429 -62.483732) (xy 424.061855 -62.4344) (xy 423.931286 -62.377591)
			(xy 423.80414 -62.313485) (xy 423.680825 -62.242289) (xy 423.561735 -62.164231) (xy 423.447252 -62.079559)
			(xy 423.337743 -61.988547) (xy 423.233558 -61.891485) (xy 423.135031 -61.788684) (xy 423.042478 -61.680473)
			(xy 422.956196 -61.5672) (xy 422.876459 -61.449227) (xy 422.803525 -61.326931) (xy 422.737627 -61.200705)
			(xy 422.678976 -61.070953) (xy 422.627759 -60.938091) (xy 422.584141 -60.802544) (xy 422.548261 -60.664746)
			(xy 422.520234 -60.525139) (xy 422.500151 -60.384171) (xy 422.488076 -60.242291) (xy 422.484046 -60.099956)
			(xy 325.12 -60.099956) (xy 325.12 -62.399361) (xy 334.478626 -62.399361) (xy 334.478626 -62.314639)
			(xy 334.486679 -62.230302) (xy 334.502713 -62.147112) (xy 334.526581 -62.065822) (xy 334.558069 -61.98717)
			(xy 334.596891 -61.911867) (xy 334.642694 -61.840595) (xy 334.695065 -61.773999) (xy 334.75353 -61.712684)
			(xy 334.817558 -61.657203) (xy 334.88657 -61.60806) (xy 334.95994 -61.5657) (xy 335.037005 -61.530505)
			(xy 335.117067 -61.502796) (xy 335.1994 -61.482822) (xy 335.283259 -61.470765) (xy 335.367884 -61.466734)
			(xy 335.452509 -61.470765) (xy 335.536368 -61.482822) (xy 335.618701 -61.502796) (xy 335.698763 -61.530505)
			(xy 335.775828 -61.5657) (xy 335.849198 -61.60806) (xy 335.91821 -61.657203) (xy 335.982238 -61.712684)
			(xy 336.040703 -61.773999) (xy 336.093074 -61.840595) (xy 336.138877 -61.911867) (xy 336.177699 -61.98717)
			(xy 336.209187 -62.065822) (xy 336.233055 -62.147112) (xy 336.249089 -62.230302) (xy 336.257142 -62.314639)
			(xy 336.257646 -62.357) (xy 336.257142 -62.399361) (xy 336.249089 -62.483698) (xy 336.233055 -62.566888)
			(xy 336.209187 -62.648178) (xy 336.177699 -62.72683) (xy 336.138877 -62.802133) (xy 336.093074 -62.873405)
			(xy 336.040703 -62.940001) (xy 335.982238 -63.001316) (xy 335.91821 -63.056797) (xy 335.849198 -63.10594)
			(xy 335.775828 -63.1483) (xy 335.698763 -63.183495) (xy 335.618701 -63.211204) (xy 335.536368 -63.231178)
			(xy 335.452509 -63.243235) (xy 335.367884 -63.247267) (xy 335.283259 -63.243235) (xy 335.1994 -63.231178)
			(xy 335.117067 -63.211204) (xy 335.037005 -63.183495) (xy 334.95994 -63.1483) (xy 334.88657 -63.10594)
			(xy 334.817558 -63.056797) (xy 334.75353 -63.001316) (xy 334.695065 -62.940001) (xy 334.642694 -62.873405)
			(xy 334.596891 -62.802133) (xy 334.558069 -62.72683) (xy 334.526581 -62.648178) (xy 334.502713 -62.566888)
			(xy 334.486679 -62.483698) (xy 334.478626 -62.399361) (xy 325.12 -62.399361) (xy 325.12 -68.199)
			(xy 331.266292 -68.199) (xy 331.266292 -68.198492) (xy 331.266898 -68.15216) (xy 331.276569 -68.060002)
			(xy 331.295765 -67.969348) (xy 331.324277 -67.881179) (xy 331.342492 -67.838574) (xy 331.346298 -67.828632)
			(xy 331.346298 -67.807368) (xy 331.342492 -67.797426) (xy 331.324247 -67.754764) (xy 331.295703 -67.666471)
			(xy 331.27651 -67.575686) (xy 331.266877 -67.483396) (xy 331.266292 -67.437) (xy 331.266875 -67.390604)
			(xy 331.27652 -67.298316) (xy 331.295716 -67.207532) (xy 331.324254 -67.119239) (xy 331.342492 -67.076574)
			(xy 331.346298 -67.066632) (xy 331.346298 -67.045368) (xy 331.342492 -67.035426) (xy 331.324247 -66.992764)
			(xy 331.295703 -66.904471) (xy 331.27651 -66.813686) (xy 331.266877 -66.721396) (xy 331.266292 -66.675)
			(xy 331.266875 -66.628604) (xy 331.27652 -66.536316) (xy 331.295716 -66.445532) (xy 331.324254 -66.357239)
			(xy 331.342492 -66.314574) (xy 331.346298 -66.304632) (xy 331.346298 -66.283368) (xy 331.342492 -66.273426)
			(xy 331.324247 -66.230764) (xy 331.295703 -66.142471) (xy 331.27651 -66.051686) (xy 331.266877 -65.959396)
			(xy 331.266292 -65.913) (xy 331.266875 -65.866604) (xy 331.27652 -65.774316) (xy 331.295716 -65.683532)
			(xy 331.324254 -65.595239) (xy 331.342492 -65.552574) (xy 331.346298 -65.542632) (xy 331.346298 -65.521368)
			(xy 331.342492 -65.511426) (xy 331.32427 -65.468823) (xy 331.295752 -65.380656) (xy 331.27656 -65.29)
			(xy 331.2669 -65.19784) (xy 331.266292 -65.151508) (xy 331.266292 -65.151) (xy 331.266767 -65.109898)
			(xy 331.274352 -65.028043) (xy 331.289457 -64.947238) (xy 331.311953 -64.868171) (xy 331.341649 -64.791517)
			(xy 331.378291 -64.71793) (xy 331.421566 -64.648038) (xy 331.471106 -64.582437) (xy 331.526487 -64.521687)
			(xy 331.587237 -64.466306) (xy 331.652838 -64.416766) (xy 331.72273 -64.373491) (xy 331.796317 -64.336849)
			(xy 331.872971 -64.307153) (xy 331.952038 -64.284657) (xy 332.032843 -64.269552) (xy 332.114698 -64.261967)
			(xy 332.1558 -64.261492) (xy 332.156308 -64.261492) (xy 332.20264 -64.262098) (xy 332.294798 -64.271769)
			(xy 332.385452 -64.290965) (xy 332.473621 -64.319477) (xy 332.516226 -64.337692) (xy 332.526168 -64.341498)
			(xy 332.547432 -64.341498) (xy 332.557374 -64.337692) (xy 332.600036 -64.319447) (xy 332.688329 -64.290903)
			(xy 332.779114 -64.27171) (xy 332.871404 -64.262077) (xy 332.9178 -64.261492) (xy 332.964196 -64.262075)
			(xy 333.056484 -64.27172) (xy 333.147268 -64.290916) (xy 333.235561 -64.319454) (xy 333.278226 -64.337692)
			(xy 333.288168 -64.341498) (xy 333.309432 -64.341498) (xy 333.319374 -64.337692) (xy 333.362036 -64.319447)
			(xy 333.450329 -64.290903) (xy 333.541114 -64.27171) (xy 333.633404 -64.262077) (xy 333.6798 -64.261492)
			(xy 333.726196 -64.262075) (xy 333.818484 -64.27172) (xy 333.909268 -64.290916) (xy 333.997561 -64.319454)
			(xy 334.040226 -64.337692) (xy 334.050168 -64.341498) (xy 334.071432 -64.341498) (xy 334.081374 -64.337692)
			(xy 334.124036 -64.319447) (xy 334.212329 -64.290903) (xy 334.303114 -64.27171) (xy 334.395404 -64.262077)
			(xy 334.4418 -64.261492) (xy 334.488196 -64.262075) (xy 334.580484 -64.27172) (xy 334.671268 -64.290916)
			(xy 334.759561 -64.319454) (xy 334.802226 -64.337692) (xy 334.812168 -64.341498) (xy 334.833432 -64.341498)
			(xy 334.843374 -64.337692) (xy 334.885977 -64.31947) (xy 334.974144 -64.290952) (xy 335.0648 -64.27176)
			(xy 335.15696 -64.2621) (xy 335.203292 -64.261492) (xy 335.2038 -64.261492) (xy 335.244902 -64.261967)
			(xy 335.326757 -64.269552) (xy 335.407562 -64.284657) (xy 335.486629 -64.307153) (xy 335.563283 -64.336849)
			(xy 335.63687 -64.373491) (xy 335.706762 -64.416766) (xy 335.772363 -64.466306) (xy 335.833113 -64.521687)
			(xy 335.888494 -64.582437) (xy 335.938034 -64.648038) (xy 335.981309 -64.71793) (xy 336.017951 -64.791517)
			(xy 336.047647 -64.868171) (xy 336.070143 -64.947238) (xy 336.085248 -65.028043) (xy 336.092833 -65.109898)
			(xy 336.093308 -65.151) (xy 336.093308 -65.151508) (xy 336.092702 -65.19784) (xy 336.083031 -65.289998)
			(xy 336.063835 -65.380652) (xy 336.035323 -65.468821) (xy 336.017108 -65.511426) (xy 336.013302 -65.521368)
			(xy 336.013302 -65.542632) (xy 336.017108 -65.552574) (xy 336.035353 -65.595236) (xy 336.063897 -65.683529)
			(xy 336.08309 -65.774314) (xy 336.092723 -65.866604) (xy 336.093308 -65.913) (xy 336.092725 -65.959396)
			(xy 336.08308 -66.051684) (xy 336.063884 -66.142468) (xy 336.035346 -66.230761) (xy 336.017108 -66.273426)
			(xy 336.013302 -66.283368) (xy 336.013302 -66.304632) (xy 336.017108 -66.314574) (xy 336.035353 -66.357236)
			(xy 336.063897 -66.445529) (xy 336.08309 -66.536314) (xy 336.092723 -66.628604) (xy 336.093308 -66.675)
			(xy 336.092725 -66.721396) (xy 336.08308 -66.813684) (xy 336.063884 -66.904468) (xy 336.035346 -66.992761)
			(xy 336.017108 -67.035426) (xy 336.013302 -67.045368) (xy 336.013302 -67.066632) (xy 336.017108 -67.076574)
			(xy 336.035353 -67.119236) (xy 336.063897 -67.207529) (xy 336.08309 -67.298314) (xy 336.092723 -67.390604)
			(xy 336.093308 -67.437) (xy 336.092725 -67.483396) (xy 336.08308 -67.575684) (xy 336.063884 -67.666468)
			(xy 336.035346 -67.754761) (xy 336.017108 -67.797426) (xy 336.013302 -67.807368) (xy 336.013302 -67.828632)
			(xy 336.017108 -67.838574) (xy 336.03533 -67.881177) (xy 336.063848 -67.969344) (xy 336.08304 -68.06)
			(xy 336.0927 -68.15216) (xy 336.093308 -68.198492) (xy 336.093308 -68.199) (xy 336.092833 -68.240102)
			(xy 336.085248 -68.321957) (xy 336.070143 -68.402762) (xy 336.047647 -68.481829) (xy 336.017951 -68.558483)
			(xy 335.981309 -68.63207) (xy 335.938034 -68.701962) (xy 335.888494 -68.767563) (xy 335.833113 -68.828313)
			(xy 335.772363 -68.883694) (xy 335.706762 -68.933234) (xy 335.63687 -68.976509) (xy 335.563283 -69.013151)
			(xy 335.486629 -69.042847) (xy 335.407562 -69.065343) (xy 335.326757 -69.080448) (xy 335.244902 -69.088033)
			(xy 335.2038 -69.088508) (xy 335.203292 -69.088508) (xy 335.15696 -69.087902) (xy 335.064802 -69.078231)
			(xy 334.974148 -69.059035) (xy 334.885979 -69.030523) (xy 334.843374 -69.012308) (xy 334.833432 -69.008502)
			(xy 334.812168 -69.008502) (xy 334.802226 -69.012308) (xy 334.759564 -69.030553) (xy 334.671271 -69.059097)
			(xy 334.580486 -69.07829) (xy 334.488196 -69.087923) (xy 334.4418 -69.088508) (xy 334.395404 -69.087925)
			(xy 334.303116 -69.07828) (xy 334.212332 -69.059084) (xy 334.124039 -69.030546) (xy 334.081374 -69.012308)
			(xy 334.071432 -69.008502) (xy 334.050168 -69.008502) (xy 334.040226 -69.012308) (xy 333.997564 -69.030553)
			(xy 333.909271 -69.059097) (xy 333.818486 -69.07829) (xy 333.726196 -69.087923) (xy 333.6798 -69.088508)
			(xy 333.633404 -69.087925) (xy 333.541116 -69.07828) (xy 333.450332 -69.059084) (xy 333.362039 -69.030546)
			(xy 333.319374 -69.012308) (xy 333.309432 -69.008502) (xy 333.288168 -69.008502) (xy 333.278226 -69.012308)
			(xy 333.235564 -69.030553) (xy 333.147271 -69.059097) (xy 333.056486 -69.07829) (xy 332.964196 -69.087923)
			(xy 332.9178 -69.088508) (xy 332.871404 -69.087925) (xy 332.779116 -69.07828) (xy 332.688332 -69.059084)
			(xy 332.600039 -69.030546) (xy 332.557374 -69.012308) (xy 332.547432 -69.008502) (xy 332.526168 -69.008502)
			(xy 332.516226 -69.012308) (xy 332.473623 -69.03053) (xy 332.385456 -69.059048) (xy 332.2948 -69.07824)
			(xy 332.20264 -69.0879) (xy 332.156308 -69.088508) (xy 332.1558 -69.088508) (xy 332.114698 -69.088033)
			(xy 332.032843 -69.080448) (xy 331.952038 -69.065343) (xy 331.872971 -69.042847) (xy 331.796317 -69.013151)
			(xy 331.72273 -68.976509) (xy 331.652838 -68.933234) (xy 331.587237 -68.883694) (xy 331.526487 -68.828313)
			(xy 331.471106 -68.767563) (xy 331.421566 -68.701962) (xy 331.378291 -68.63207) (xy 331.341649 -68.558483)
			(xy 331.311953 -68.481829) (xy 331.289457 -68.402762) (xy 331.274352 -68.321957) (xy 331.266767 -68.240102)
			(xy 331.266292 -68.199) (xy 325.12 -68.199) (xy 325.12 -71.239888) (xy 377.061232 -71.239888) (xy 377.065214 -71.149938)
			(xy 377.077131 -71.060691) (xy 377.096889 -70.972847) (xy 377.124333 -70.887093) (xy 377.159249 -70.8041)
			(xy 377.201363 -70.724518) (xy 377.250346 -70.648969) (xy 377.305814 -70.578045) (xy 377.367334 -70.5123)
			(xy 377.434423 -70.45225) (xy 377.506557 -70.398365) (xy 377.583171 -70.351065) (xy 377.663665 -70.310722)
			(xy 377.74741 -70.27765) (xy 377.833751 -70.25211) (xy 377.92201 -70.2343) (xy 378.011499 -70.22436)
			(xy 378.101515 -70.222369) (xy 378.191356 -70.22834) (xy 378.280317 -70.242229) (xy 378.367702 -70.263925)
			(xy 378.452828 -70.29326) (xy 378.535028 -70.330003) (xy 378.613659 -70.373867) (xy 378.688106 -70.424509)
			(xy 378.757786 -70.481533) (xy 378.822153 -70.544492) (xy 378.880704 -70.612893) (xy 378.932981 -70.686201)
			(xy 378.978574 -70.763843) (xy 379.017127 -70.84521) (xy 379.048338 -70.929666) (xy 379.071962 -71.01655)
			(xy 379.087815 -71.105182) (xy 379.095772 -71.194869) (xy 379.09627 -71.239888) (xy 396.619232 -71.239888)
			(xy 396.623214 -71.149938) (xy 396.635131 -71.060691) (xy 396.654889 -70.972847) (xy 396.682333 -70.887093)
			(xy 396.717249 -70.8041) (xy 396.759363 -70.724518) (xy 396.808346 -70.648969) (xy 396.863814 -70.578045)
			(xy 396.925334 -70.5123) (xy 396.992423 -70.45225) (xy 397.064557 -70.398365) (xy 397.141171 -70.351065)
			(xy 397.221665 -70.310722) (xy 397.30541 -70.27765) (xy 397.391751 -70.25211) (xy 397.48001 -70.2343)
			(xy 397.569499 -70.22436) (xy 397.659515 -70.222369) (xy 397.749356 -70.22834) (xy 397.838317 -70.242229)
			(xy 397.925702 -70.263925) (xy 398.010828 -70.29326) (xy 398.093028 -70.330003) (xy 398.171659 -70.373867)
			(xy 398.246106 -70.424509) (xy 398.315786 -70.481533) (xy 398.380153 -70.544492) (xy 398.438704 -70.612893)
			(xy 398.490981 -70.686201) (xy 398.536574 -70.763843) (xy 398.575127 -70.84521) (xy 398.606338 -70.929666)
			(xy 398.629962 -71.01655) (xy 398.645815 -71.105182) (xy 398.653772 -71.194869) (xy 398.65427 -71.239888)
			(xy 398.653772 -71.284907) (xy 398.645815 -71.374594) (xy 398.629962 -71.463226) (xy 398.606338 -71.55011)
			(xy 398.575127 -71.634566) (xy 398.536574 -71.715933) (xy 398.490981 -71.793575) (xy 398.438704 -71.866883)
			(xy 398.380153 -71.935284) (xy 398.315786 -71.998243) (xy 398.246106 -72.055267) (xy 398.171659 -72.105909)
			(xy 398.093028 -72.149773) (xy 398.010828 -72.186516) (xy 397.925702 -72.215851) (xy 397.838317 -72.237547)
			(xy 397.749356 -72.251436) (xy 397.659515 -72.257407) (xy 397.569499 -72.255416) (xy 397.48001 -72.245476)
			(xy 397.391751 -72.227666) (xy 397.30541 -72.202126) (xy 397.221665 -72.169054) (xy 397.141171 -72.128711)
			(xy 397.064557 -72.081411) (xy 396.992423 -72.027526) (xy 396.925334 -71.967476) (xy 396.863814 -71.901731)
			(xy 396.808346 -71.830807) (xy 396.759363 -71.755258) (xy 396.717249 -71.675676) (xy 396.682333 -71.592683)
			(xy 396.654889 -71.506929) (xy 396.635131 -71.419085) (xy 396.623214 -71.329838) (xy 396.619232 -71.239888)
			(xy 379.09627 -71.239888) (xy 379.095772 -71.284907) (xy 379.087815 -71.374594) (xy 379.071962 -71.463226)
			(xy 379.048338 -71.55011) (xy 379.017127 -71.634566) (xy 378.978574 -71.715933) (xy 378.932981 -71.793575)
			(xy 378.880704 -71.866883) (xy 378.822153 -71.935284) (xy 378.757786 -71.998243) (xy 378.688106 -72.055267)
			(xy 378.613659 -72.105909) (xy 378.535028 -72.149773) (xy 378.452828 -72.186516) (xy 378.367702 -72.215851)
			(xy 378.280317 -72.237547) (xy 378.191356 -72.251436) (xy 378.101515 -72.257407) (xy 378.011499 -72.255416)
			(xy 377.92201 -72.245476) (xy 377.833751 -72.227666) (xy 377.74741 -72.202126) (xy 377.663665 -72.169054)
			(xy 377.583171 -72.128711) (xy 377.506557 -72.081411) (xy 377.434423 -72.027526) (xy 377.367334 -71.967476)
			(xy 377.305814 -71.901731) (xy 377.250346 -71.830807) (xy 377.201363 -71.755258) (xy 377.159249 -71.675676)
			(xy 377.124333 -71.592683) (xy 377.096889 -71.506929) (xy 377.077131 -71.419085) (xy 377.065214 -71.329838)
			(xy 377.061232 -71.239888) (xy 325.12 -71.239888) (xy 325.12 -73.676961) (xy 334.478626 -73.676961)
			(xy 334.478626 -73.592239) (xy 334.486679 -73.507902) (xy 334.502713 -73.424712) (xy 334.526581 -73.343422)
			(xy 334.558069 -73.26477) (xy 334.596891 -73.189467) (xy 334.642694 -73.118195) (xy 334.695065 -73.051599)
			(xy 334.75353 -72.990284) (xy 334.817558 -72.934803) (xy 334.88657 -72.88566) (xy 334.95994 -72.8433)
			(xy 335.037005 -72.808105) (xy 335.117067 -72.780396) (xy 335.1994 -72.760422) (xy 335.283259 -72.748365)
			(xy 335.367884 -72.744334) (xy 335.452509 -72.748365) (xy 335.536368 -72.760422) (xy 335.618701 -72.780396)
			(xy 335.698763 -72.808105) (xy 335.775828 -72.8433) (xy 335.849198 -72.88566) (xy 335.91821 -72.934803)
			(xy 335.982238 -72.990284) (xy 336.040703 -73.051599) (xy 336.093074 -73.118195) (xy 336.138877 -73.189467)
			(xy 336.177699 -73.26477) (xy 336.209187 -73.343422) (xy 336.233055 -73.424712) (xy 336.249089 -73.507902)
			(xy 336.257142 -73.592239) (xy 336.257646 -73.6346) (xy 336.257142 -73.676961) (xy 336.249089 -73.761298)
			(xy 336.233055 -73.844488) (xy 336.209187 -73.925778) (xy 336.177699 -74.00443) (xy 336.138877 -74.079733)
			(xy 336.093074 -74.151005) (xy 336.040703 -74.217601) (xy 335.982238 -74.278916) (xy 335.91821 -74.334397)
			(xy 335.849198 -74.38354) (xy 335.775828 -74.4259) (xy 335.698763 -74.461095) (xy 335.618701 -74.488804)
			(xy 335.536368 -74.508778) (xy 335.452509 -74.520835) (xy 335.367884 -74.524867) (xy 335.283259 -74.520835)
			(xy 335.1994 -74.508778) (xy 335.117067 -74.488804) (xy 335.037005 -74.461095) (xy 334.95994 -74.4259)
			(xy 334.88657 -74.38354) (xy 334.817558 -74.334397) (xy 334.75353 -74.278916) (xy 334.695065 -74.217601)
			(xy 334.642694 -74.151005) (xy 334.596891 -74.079733) (xy 334.558069 -74.00443) (xy 334.526581 -73.925778)
			(xy 334.502713 -73.844488) (xy 334.486679 -73.761298) (xy 334.478626 -73.676961) (xy 325.12 -73.676961)
			(xy 325.12 -79.4766) (xy 331.266292 -79.4766) (xy 331.266292 -79.476092) (xy 331.266898 -79.42976)
			(xy 331.276569 -79.337602) (xy 331.295765 -79.246948) (xy 331.324277 -79.158779) (xy 331.342492 -79.116174)
			(xy 331.346298 -79.106232) (xy 331.346298 -79.084968) (xy 331.342492 -79.075026) (xy 331.324247 -79.032364)
			(xy 331.295703 -78.944071) (xy 331.27651 -78.853286) (xy 331.266877 -78.760996) (xy 331.266292 -78.7146)
			(xy 331.266875 -78.668204) (xy 331.27652 -78.575916) (xy 331.295716 -78.485132) (xy 331.324254 -78.396839)
			(xy 331.342492 -78.354174) (xy 331.346298 -78.344232) (xy 331.346298 -78.322968) (xy 331.342492 -78.313026)
			(xy 331.324247 -78.270364) (xy 331.295703 -78.182071) (xy 331.27651 -78.091286) (xy 331.266877 -77.998996)
			(xy 331.266292 -77.9526) (xy 331.266875 -77.906204) (xy 331.27652 -77.813916) (xy 331.295716 -77.723132)
			(xy 331.324254 -77.634839) (xy 331.342492 -77.592174) (xy 331.346298 -77.582232) (xy 331.346298 -77.560968)
			(xy 331.342492 -77.551026) (xy 331.324247 -77.508364) (xy 331.295703 -77.420071) (xy 331.27651 -77.329286)
			(xy 331.266877 -77.236996) (xy 331.266292 -77.1906) (xy 331.266875 -77.144204) (xy 331.27652 -77.051916)
			(xy 331.295716 -76.961132) (xy 331.324254 -76.872839) (xy 331.342492 -76.830174) (xy 331.346298 -76.820232)
			(xy 331.346298 -76.798968) (xy 331.342492 -76.789026) (xy 331.32427 -76.746423) (xy 331.295752 -76.658256)
			(xy 331.27656 -76.5676) (xy 331.2669 -76.47544) (xy 331.266292 -76.429108) (xy 331.266292 -76.4286)
			(xy 331.266767 -76.387498) (xy 331.274352 -76.305643) (xy 331.289457 -76.224838) (xy 331.311953 -76.145771)
			(xy 331.341649 -76.069117) (xy 331.378291 -75.99553) (xy 331.421566 -75.925638) (xy 331.471106 -75.860037)
			(xy 331.526487 -75.799287) (xy 331.587237 -75.743906) (xy 331.652838 -75.694366) (xy 331.72273 -75.651091)
			(xy 331.796317 -75.614449) (xy 331.872971 -75.584753) (xy 331.952038 -75.562257) (xy 332.032843 -75.547152)
			(xy 332.114698 -75.539567) (xy 332.1558 -75.539092) (xy 332.156308 -75.539092) (xy 332.20264 -75.539698)
			(xy 332.294798 -75.549369) (xy 332.385452 -75.568565) (xy 332.473621 -75.597077) (xy 332.516226 -75.615292)
			(xy 332.526168 -75.619098) (xy 332.547432 -75.619098) (xy 332.557374 -75.615292) (xy 332.600036 -75.597047)
			(xy 332.688329 -75.568503) (xy 332.779114 -75.54931) (xy 332.871404 -75.539677) (xy 332.9178 -75.539092)
			(xy 332.964196 -75.539675) (xy 333.056484 -75.54932) (xy 333.147268 -75.568516) (xy 333.235561 -75.597054)
			(xy 333.278226 -75.615292) (xy 333.288168 -75.619098) (xy 333.309432 -75.619098) (xy 333.319374 -75.615292)
			(xy 333.362036 -75.597047) (xy 333.450329 -75.568503) (xy 333.541114 -75.54931) (xy 333.633404 -75.539677)
			(xy 333.6798 -75.539092) (xy 333.726196 -75.539675) (xy 333.818484 -75.54932) (xy 333.909268 -75.568516)
			(xy 333.997561 -75.597054) (xy 334.040226 -75.615292) (xy 334.050168 -75.619098) (xy 334.071432 -75.619098)
			(xy 334.081374 -75.615292) (xy 334.124036 -75.597047) (xy 334.212329 -75.568503) (xy 334.303114 -75.54931)
			(xy 334.395404 -75.539677) (xy 334.4418 -75.539092) (xy 334.488196 -75.539675) (xy 334.580484 -75.54932)
			(xy 334.671268 -75.568516) (xy 334.759561 -75.597054) (xy 334.802226 -75.615292) (xy 334.812168 -75.619098)
			(xy 334.833432 -75.619098) (xy 334.843374 -75.615292) (xy 334.885977 -75.59707) (xy 334.974144 -75.568552)
			(xy 335.0648 -75.54936) (xy 335.15696 -75.5397) (xy 335.203292 -75.539092) (xy 335.2038 -75.539092)
			(xy 335.244902 -75.539567) (xy 335.326757 -75.547152) (xy 335.407562 -75.562257) (xy 335.486629 -75.584753)
			(xy 335.563283 -75.614449) (xy 335.63687 -75.651091) (xy 335.706762 -75.694366) (xy 335.772363 -75.743906)
			(xy 335.833113 -75.799287) (xy 335.888494 -75.860037) (xy 335.938034 -75.925638) (xy 335.981309 -75.99553)
			(xy 336.017951 -76.069117) (xy 336.047647 -76.145771) (xy 336.070143 -76.224838) (xy 336.085248 -76.305643)
			(xy 336.085697 -76.31049) (xy 467.50986 -76.31049) (xy 467.50986 -76.309982) (xy 467.510348 -76.255884)
			(xy 467.518633 -76.148004) (xy 467.53516 -76.041077) (xy 467.559833 -75.935731) (xy 467.592506 -75.832585)
			(xy 467.632987 -75.732246) (xy 467.681038 -75.635305) (xy 467.736376 -75.54233) (xy 467.798677 -75.45387)
			(xy 467.867573 -75.370444) (xy 467.942659 -75.292543) (xy 468.023495 -75.220625) (xy 468.109603 -75.155112)
			(xy 468.154766 -75.125326) (xy 468.165688 -75.118214) (xy 468.178134 -75.095608) (xy 468.178134 -74.984356)
			(xy 468.165688 -74.96175) (xy 468.154766 -74.954638) (xy 468.109587 -74.924876) (xy 468.023479 -74.85936)
			(xy 467.942644 -74.787439) (xy 467.867558 -74.709536) (xy 467.798662 -74.626108) (xy 467.736361 -74.537647)
			(xy 467.681021 -74.444672) (xy 467.632969 -74.347729) (xy 467.592485 -74.24739) (xy 467.559809 -74.144244)
			(xy 467.535133 -74.038897) (xy 467.518601 -73.93197) (xy 467.510312 -73.824089) (xy 467.510312 -73.715891)
			(xy 467.518604 -73.608011) (xy 467.535137 -73.501083) (xy 467.559815 -73.395737) (xy 467.592492 -73.292591)
			(xy 467.632977 -73.192253) (xy 467.681031 -73.095311) (xy 467.736372 -73.002337) (xy 467.798674 -72.913876)
			(xy 467.867571 -72.830449) (xy 467.942659 -72.752547) (xy 468.023494 -72.680628) (xy 468.109603 -72.615113)
			(xy 468.154766 -72.585326) (xy 468.165688 -72.578214) (xy 468.178134 -72.555608) (xy 468.178134 -72.444356)
			(xy 468.165688 -72.42175) (xy 468.154766 -72.414638) (xy 468.109587 -72.384876) (xy 468.023479 -72.31936)
			(xy 467.942644 -72.247439) (xy 467.867558 -72.169536) (xy 467.798662 -72.086108) (xy 467.736361 -71.997647)
			(xy 467.681021 -71.904672) (xy 467.632969 -71.807729) (xy 467.592485 -71.70739) (xy 467.559809 -71.604244)
			(xy 467.535133 -71.498897) (xy 467.518601 -71.39197) (xy 467.510312 -71.284089) (xy 467.510312 -71.175891)
			(xy 467.518604 -71.068011) (xy 467.535137 -70.961083) (xy 467.559815 -70.855737) (xy 467.592492 -70.752591)
			(xy 467.632977 -70.652253) (xy 467.681031 -70.555311) (xy 467.736372 -70.462337) (xy 467.798674 -70.373876)
			(xy 467.867571 -70.290449) (xy 467.942659 -70.212547) (xy 468.023494 -70.140628) (xy 468.109603 -70.075113)
			(xy 468.154766 -70.045326) (xy 468.165688 -70.038214) (xy 468.178134 -70.015608) (xy 468.178134 -69.904356)
			(xy 468.165688 -69.88175) (xy 468.154766 -69.874638) (xy 468.109595 -69.844866) (xy 468.023492 -69.779347)
			(xy 467.942663 -69.707424) (xy 467.867582 -69.629519) (xy 467.798691 -69.54609) (xy 467.736395 -69.457628)
			(xy 467.681059 -69.364653) (xy 467.633011 -69.267711) (xy 467.592531 -69.167373) (xy 467.559858 -69.064228)
			(xy 467.535184 -68.958884) (xy 467.518654 -68.851958) (xy 467.510366 -68.74408) (xy 467.50986 -68.689982)
			(xy 467.510314 -68.63723) (xy 467.518198 -68.532021) (xy 467.533923 -68.427695) (xy 467.557398 -68.324836)
			(xy 467.588494 -68.224019) (xy 467.627036 -68.125806) (xy 467.672809 -68.030749) (xy 467.725557 -67.939377)
			(xy 467.784984 -67.852202) (xy 467.85076 -67.769712) (xy 467.922515 -67.692367) (xy 467.99985 -67.6206)
			(xy 468.08233 -67.554812) (xy 468.169496 -67.495371) (xy 468.26086 -67.442609) (xy 468.35591 -67.396822)
			(xy 468.454117 -67.358265) (xy 468.554929 -67.327154) (xy 468.657785 -67.303662) (xy 468.762108 -67.287922)
			(xy 468.867316 -67.280022) (xy 468.920068 -67.27952) (xy 468.971968 -67.279989) (xy 469.075487 -67.287612)
			(xy 469.178165 -67.302827) (xy 469.279447 -67.325552) (xy 469.378783 -67.355664) (xy 469.475635 -67.392998)
			(xy 469.56948 -67.437354) (xy 469.659809 -67.488491) (xy 469.746133 -67.546132) (xy 469.827985 -67.609965)
			(xy 469.904921 -67.679645) (xy 469.976524 -67.754793) (xy 470.042407 -67.835004) (xy 470.102214 -67.919842)
			(xy 470.15562 -68.008849) (xy 470.1794 -68.054982) (xy 470.18575 -68.067936) (xy 470.210134 -68.082922)
			(xy 470.330022 -68.082922) (xy 470.354406 -68.067936) (xy 470.360756 -68.054982) (xy 470.38451 -68.008836)
			(xy 470.437926 -67.919837) (xy 470.497742 -67.835006) (xy 470.563632 -67.754803) (xy 470.635241 -67.679661)
			(xy 470.71218 -67.609987) (xy 470.794033 -67.546158) (xy 470.880358 -67.48852) (xy 470.970687 -67.437385)
			(xy 471.064531 -67.393029) (xy 471.161382 -67.355693) (xy 471.260716 -67.325578) (xy 471.361995 -67.302848)
			(xy 471.464671 -67.287626) (xy 471.568189 -67.279993) (xy 471.620088 -67.27952) (xy 471.67283 -67.279996)
			(xy 471.77802 -67.287878) (xy 471.882327 -67.303597) (xy 471.985167 -67.327066) (xy 472.085967 -67.358155)
			(xy 472.184161 -67.396688) (xy 472.279202 -67.442451) (xy 472.370557 -67.495188) (xy 472.457717 -67.554604)
			(xy 472.540193 -67.620366) (xy 472.617524 -67.692108) (xy 472.689278 -67.769427) (xy 472.755055 -67.851892)
			(xy 472.814485 -67.939041) (xy 472.867238 -68.030388) (xy 472.913017 -68.125421) (xy 472.951567 -68.223609)
			(xy 472.982672 -68.324403) (xy 473.006159 -68.427239) (xy 473.021896 -68.531543) (xy 473.029795 -68.636732)
			(xy 473.030296 -68.689474) (xy 473.030296 -68.689982) (xy 473.029754 -68.744079) (xy 473.021472 -68.851956)
			(xy 473.004948 -68.958882) (xy 472.980279 -69.064227) (xy 472.94761 -69.167371) (xy 472.907133 -69.267709)
			(xy 472.859087 -69.36465) (xy 472.803753 -69.457625) (xy 472.741457 -69.546085) (xy 472.672566 -69.629512)
			(xy 472.597485 -69.707415) (xy 472.516654 -69.779335) (xy 472.43055 -69.84485) (xy 472.38539 -69.874638)
			(xy 472.374468 -69.88175) (xy 472.362022 -69.904356) (xy 472.362022 -70.015608) (xy 472.374468 -70.038214)
			(xy 472.38539 -70.045326) (xy 472.430534 -70.075139) (xy 472.516638 -70.140654) (xy 472.597469 -70.212573)
			(xy 472.672552 -70.290475) (xy 472.741445 -70.373901) (xy 472.803743 -70.462359) (xy 472.859081 -70.555332)
			(xy 472.907132 -70.652271) (xy 472.947614 -70.752607) (xy 472.980289 -70.855749) (xy 473.004965 -70.961092)
			(xy 473.021497 -71.068016) (xy 473.029788 -71.175893) (xy 473.029789 -71.284088) (xy 473.021499 -71.391964)
			(xy 473.004969 -71.498888) (xy 472.980294 -71.604232) (xy 472.94762 -71.707375) (xy 472.90714 -71.807711)
			(xy 472.85909 -71.904651) (xy 472.803754 -71.997624) (xy 472.741457 -72.086084) (xy 472.672565 -72.16951)
			(xy 472.597483 -72.247413) (xy 472.516653 -72.319334) (xy 472.43055 -72.38485) (xy 472.38539 -72.414638)
			(xy 472.374468 -72.42175) (xy 472.362022 -72.444356) (xy 472.362022 -72.555608) (xy 472.374468 -72.578214)
			(xy 472.38539 -72.585326) (xy 472.430534 -72.615139) (xy 472.516638 -72.680654) (xy 472.597469 -72.752573)
			(xy 472.672552 -72.830475) (xy 472.741445 -72.913901) (xy 472.803743 -73.002359) (xy 472.859081 -73.095332)
			(xy 472.907132 -73.192271) (xy 472.947614 -73.292607) (xy 472.980289 -73.395749) (xy 473.004965 -73.501092)
			(xy 473.021497 -73.608016) (xy 473.029788 -73.715893) (xy 473.029789 -73.824088) (xy 473.021499 -73.931964)
			(xy 473.004969 -74.038888) (xy 472.980294 -74.144232) (xy 472.94762 -74.247375) (xy 472.90714 -74.347711)
			(xy 472.85909 -74.444651) (xy 472.803754 -74.537624) (xy 472.741457 -74.626084) (xy 472.672565 -74.70951)
			(xy 472.597483 -74.787413) (xy 472.516653 -74.859334) (xy 472.43055 -74.92485) (xy 472.38539 -74.954638)
			(xy 472.374468 -74.96175) (xy 472.362022 -74.984356) (xy 472.362022 -75.095608) (xy 472.374468 -75.118214)
			(xy 472.38539 -75.125326) (xy 472.430558 -75.155102) (xy 472.516659 -75.220622) (xy 472.597487 -75.292546)
			(xy 472.672567 -75.370452) (xy 472.741457 -75.45388) (xy 472.803753 -75.542342) (xy 472.859088 -75.635317)
			(xy 472.907137 -75.732257) (xy 472.947617 -75.832595) (xy 472.980291 -75.935738) (xy 473.004966 -76.041082)
			(xy 473.021498 -76.148007) (xy 473.029789 -76.255884) (xy 473.030296 -76.309982) (xy 473.029752 -76.362732)
			(xy 473.02187 -76.467938) (xy 473.006149 -76.57226) (xy 472.982677 -76.675117) (xy 472.951585 -76.775931)
			(xy 472.913048 -76.874141) (xy 472.867279 -76.969197) (xy 472.814536 -77.060567) (xy 472.755113 -77.147741)
			(xy 472.689342 -77.230231) (xy 472.617592 -77.307575) (xy 472.540263 -77.379343) (xy 472.457787 -77.445131)
			(xy 472.370626 -77.504573) (xy 472.279268 -77.557336) (xy 472.184222 -77.603125) (xy 472.08602 -77.641684)
			(xy 471.985212 -77.672798) (xy 471.882361 -77.696292) (xy 471.778042 -77.712036) (xy 471.672838 -77.71994)
			(xy 471.620088 -77.720444) (xy 471.568188 -77.719978) (xy 471.46467 -77.712352) (xy 471.361992 -77.697134)
			(xy 471.260712 -77.674407) (xy 471.161377 -77.644294) (xy 471.064525 -77.606959) (xy 470.970681 -77.562602)
			(xy 470.880352 -77.511465) (xy 470.794028 -77.453824) (xy 470.712177 -77.389992) (xy 470.635241 -77.320313)
			(xy 470.563637 -77.245166) (xy 470.497753 -77.164956) (xy 470.437945 -77.08012) (xy 470.384537 -76.991115)
			(xy 470.360756 -76.944982) (xy 470.354406 -76.932028) (xy 470.330022 -76.917042) (xy 470.210134 -76.917042)
			(xy 470.18575 -76.932028) (xy 470.1794 -76.944982) (xy 470.155586 -76.991097) (xy 470.102175 -77.080095)
			(xy 470.042364 -77.164927) (xy 469.976479 -77.245131) (xy 469.904875 -77.320274) (xy 469.827941 -77.389949)
			(xy 469.746092 -77.45378) (xy 469.659771 -77.51142) (xy 469.569447 -77.562557) (xy 469.475607 -77.606916)
			(xy 469.37876 -77.644255) (xy 469.279429 -77.674373) (xy 469.178154 -77.697106) (xy 469.075481 -77.712332)
			(xy 468.971966 -77.719969) (xy 468.920068 -77.720444) (xy 468.867327 -77.719946) (xy 468.762139 -77.712062)
			(xy 468.657834 -77.696341) (xy 468.554996 -77.67287) (xy 468.454199 -77.64178) (xy 468.356007 -77.603246)
			(xy 468.260968 -77.557483) (xy 468.169615 -77.504746) (xy 468.082457 -77.445331) (xy 467.999982 -77.37957)
			(xy 467.922652 -77.30783) (xy 467.850898 -77.230513) (xy 467.785122 -77.148051) (xy 467.725691 -77.060904)
			(xy 467.672938 -76.96956) (xy 467.627157 -76.87453) (xy 467.588605 -76.776344) (xy 467.557497 -76.675553)
			(xy 467.534007 -76.572719) (xy 467.518267 -76.468417) (xy 467.510364 -76.363231) (xy 467.50986 -76.31049)
			(xy 336.085697 -76.31049) (xy 336.092833 -76.387498) (xy 336.093308 -76.4286) (xy 336.093308 -76.429108)
			(xy 336.092702 -76.47544) (xy 336.083031 -76.567598) (xy 336.063835 -76.658252) (xy 336.035323 -76.746421)
			(xy 336.017108 -76.789026) (xy 336.013302 -76.798968) (xy 336.013302 -76.820232) (xy 336.017108 -76.830174)
			(xy 336.03533 -76.872777) (xy 336.063848 -76.960944) (xy 336.08304 -77.0516) (xy 336.0927 -77.14376)
			(xy 336.093308 -77.190092) (xy 336.093308 -77.1906) (xy 336.09286 -77.231986) (xy 336.085163 -77.314401)
			(xy 336.069847 -77.395744) (xy 336.047042 -77.475313) (xy 336.016946 -77.552421) (xy 335.97982 -77.6264)
			(xy 335.935983 -77.696612) (xy 335.885816 -77.76245) (xy 335.829751 -77.823344) (xy 335.768274 -77.878768)
			(xy 335.701914 -77.928243) (xy 335.631247 -77.971342) (xy 335.556883 -78.007691) (xy 335.479465 -78.036978)
			(xy 335.399661 -78.058948) (xy 335.358994 -78.066646) (xy 335.34887 -78.068944) (xy 335.331549 -78.080349)
			(xy 335.320144 -78.09767) (xy 335.317846 -78.107794) (xy 335.310093 -78.14883) (xy 335.287881 -78.229342)
			(xy 335.258222 -78.307417) (xy 335.221376 -78.382369) (xy 335.177667 -78.453538) (xy 335.127482 -78.520298)
			(xy 335.07126 -78.58206) (xy 335.009498 -78.638282) (xy 334.942738 -78.688467) (xy 334.871569 -78.732176)
			(xy 334.855653 -78.74) (xy 376.553741 -78.74) (xy 376.557716 -78.629941) (xy 376.569624 -78.520455)
			(xy 376.5894 -78.412114) (xy 376.616943 -78.305483) (xy 376.652108 -78.201117) (xy 376.694712 -78.09956)
			(xy 376.744533 -78.001343) (xy 376.801312 -77.906976) (xy 376.864751 -77.816952) (xy 376.934522 -77.731741)
			(xy 377.010259 -77.651786) (xy 377.091568 -77.577505) (xy 377.178025 -77.509285) (xy 377.269179 -77.44748)
			(xy 377.364556 -77.392415) (xy 377.463657 -77.344375) (xy 377.565966 -77.303611) (xy 377.67095 -77.270336)
			(xy 377.778061 -77.244723) (xy 377.886741 -77.226906) (xy 377.996424 -77.216977) (xy 378.106537 -77.214989)
			(xy 378.216507 -77.220951) (xy 378.32576 -77.234833) (xy 378.433726 -77.256563) (xy 378.539843 -77.286026)
			(xy 378.643557 -77.323069) (xy 378.744328 -77.3675) (xy 378.84163 -77.419087) (xy 378.934956 -77.477559)
			(xy 379.023819 -77.542614) (xy 379.107757 -77.613912) (xy 379.186332 -77.69108) (xy 379.259133 -77.773717)
			(xy 379.325781 -77.861391) (xy 379.38593 -77.953647) (xy 379.439264 -78.050002) (xy 379.485507 -78.149954)
			(xy 379.524417 -78.252982) (xy 379.555791 -78.35855) (xy 379.579466 -78.466106) (xy 379.595318 -78.57509)
			(xy 379.603265 -78.684934) (xy 379.603762 -78.74) (xy 396.111741 -78.74) (xy 396.115716 -78.629941)
			(xy 396.127624 -78.520455) (xy 396.1474 -78.412114) (xy 396.174943 -78.305483) (xy 396.210108 -78.201117)
			(xy 396.252712 -78.09956) (xy 396.302533 -78.001343) (xy 396.359312 -77.906976) (xy 396.422751 -77.816952)
			(xy 396.492522 -77.731741) (xy 396.568259 -77.651786) (xy 396.649568 -77.577505) (xy 396.736025 -77.509285)
			(xy 396.827179 -77.44748) (xy 396.922556 -77.392415) (xy 397.021657 -77.344375) (xy 397.123966 -77.303611)
			(xy 397.22895 -77.270336) (xy 397.336061 -77.244723) (xy 397.444741 -77.226906) (xy 397.554424 -77.216977)
			(xy 397.664537 -77.214989) (xy 397.774507 -77.220951) (xy 397.88376 -77.234833) (xy 397.991726 -77.256563)
			(xy 398.097843 -77.286026) (xy 398.201557 -77.323069) (xy 398.302328 -77.3675) (xy 398.39963 -77.419087)
			(xy 398.492956 -77.477559) (xy 398.581819 -77.542614) (xy 398.665757 -77.613912) (xy 398.744332 -77.69108)
			(xy 398.817133 -77.773717) (xy 398.883781 -77.861391) (xy 398.94393 -77.953647) (xy 398.997264 -78.050002)
			(xy 399.043507 -78.149954) (xy 399.082417 -78.252982) (xy 399.113791 -78.35855) (xy 399.137466 -78.466106)
			(xy 399.153318 -78.57509) (xy 399.161265 -78.684934) (xy 399.161762 -78.74) (xy 399.161265 -78.795066)
			(xy 399.153318 -78.90491) (xy 399.137466 -79.013894) (xy 399.113791 -79.12145) (xy 399.082417 -79.227018)
			(xy 399.043507 -79.330046) (xy 398.997264 -79.429998) (xy 398.94393 -79.526353) (xy 398.883781 -79.618609)
			(xy 398.817133 -79.706283) (xy 398.744332 -79.78892) (xy 398.665757 -79.866088) (xy 398.581819 -79.937386)
			(xy 398.492956 -80.002441) (xy 398.39963 -80.060913) (xy 398.302328 -80.1125) (xy 398.201557 -80.156931)
			(xy 398.097843 -80.193974) (xy 397.991726 -80.223437) (xy 397.88376 -80.245167) (xy 397.774507 -80.259049)
			(xy 397.664537 -80.265011) (xy 397.554424 -80.263023) (xy 397.444741 -80.253094) (xy 397.336061 -80.235277)
			(xy 397.22895 -80.209664) (xy 397.123966 -80.176389) (xy 397.021657 -80.135625) (xy 396.922556 -80.087585)
			(xy 396.827179 -80.03252) (xy 396.736025 -79.970715) (xy 396.649568 -79.902495) (xy 396.568259 -79.828214)
			(xy 396.492522 -79.748259) (xy 396.422751 -79.663048) (xy 396.359312 -79.573024) (xy 396.302533 -79.478657)
			(xy 396.252712 -79.38044) (xy 396.210108 -79.278883) (xy 396.174943 -79.174517) (xy 396.1474 -79.067886)
			(xy 396.127624 -78.959545) (xy 396.115716 -78.850059) (xy 396.111741 -78.74) (xy 379.603762 -78.74)
			(xy 379.603265 -78.795066) (xy 379.595318 -78.90491) (xy 379.579466 -79.013894) (xy 379.555791 -79.12145)
			(xy 379.524417 -79.227018) (xy 379.485507 -79.330046) (xy 379.439264 -79.429998) (xy 379.38593 -79.526353)
			(xy 379.325781 -79.618609) (xy 379.259133 -79.706283) (xy 379.186332 -79.78892) (xy 379.107757 -79.866088)
			(xy 379.023819 -79.937386) (xy 378.934956 -80.002441) (xy 378.84163 -80.060913) (xy 378.744328 -80.1125)
			(xy 378.643557 -80.156931) (xy 378.539843 -80.193974) (xy 378.433726 -80.223437) (xy 378.32576 -80.245167)
			(xy 378.216507 -80.259049) (xy 378.106537 -80.265011) (xy 377.996424 -80.263023) (xy 377.886741 -80.253094)
			(xy 377.778061 -80.235277) (xy 377.67095 -80.209664) (xy 377.565966 -80.176389) (xy 377.463657 -80.135625)
			(xy 377.364556 -80.087585) (xy 377.269179 -80.03252) (xy 377.178025 -79.970715) (xy 377.091568 -79.902495)
			(xy 377.010259 -79.828214) (xy 376.934522 -79.748259) (xy 376.864751 -79.663048) (xy 376.801312 -79.573024)
			(xy 376.744533 -79.478657) (xy 376.694712 -79.38044) (xy 376.652108 -79.278883) (xy 376.616943 -79.174517)
			(xy 376.5894 -79.067886) (xy 376.569624 -78.959545) (xy 376.557716 -78.850059) (xy 376.553741 -78.74)
			(xy 334.855653 -78.74) (xy 334.796617 -78.769022) (xy 334.718542 -78.798681) (xy 334.63803 -78.820893)
			(xy 334.596994 -78.828646) (xy 334.58687 -78.830944) (xy 334.569549 -78.842349) (xy 334.558144 -78.85967)
			(xy 334.555846 -78.869794) (xy 334.548093 -78.91083) (xy 334.525881 -78.991342) (xy 334.496222 -79.069417)
			(xy 334.459376 -79.144369) (xy 334.415667 -79.215538) (xy 334.365482 -79.282298) (xy 334.30926 -79.34406)
			(xy 334.247498 -79.400282) (xy 334.180738 -79.450467) (xy 334.109569 -79.494176) (xy 334.034617 -79.531022)
			(xy 333.956542 -79.560681) (xy 333.87603 -79.582893) (xy 333.834994 -79.590646) (xy 333.82487 -79.592944)
			(xy 333.807549 -79.604349) (xy 333.796144 -79.62167) (xy 333.793846 -79.631794) (xy 333.786139 -79.672459)
			(xy 333.764175 -79.752265) (xy 333.734893 -79.829685) (xy 333.698547 -79.904051) (xy 333.655451 -79.97472)
			(xy 333.605977 -80.04108) (xy 333.550554 -80.102559) (xy 333.489659 -80.158623) (xy 333.423821 -80.208789)
			(xy 333.353608 -80.252624) (xy 333.279627 -80.289747) (xy 333.202517 -80.319838) (xy 333.122946 -80.342637)
			(xy 333.041601 -80.357947) (xy 332.959186 -80.365635) (xy 332.9178 -80.366108) (xy 332.917292 -80.366108)
			(xy 332.87096 -80.365502) (xy 332.778802 -80.355831) (xy 332.688148 -80.336635) (xy 332.599979 -80.308123)
			(xy 332.557374 -80.289908) (xy 332.547432 -80.286102) (xy 332.526168 -80.286102) (xy 332.516226 -80.289908)
			(xy 332.473623 -80.30813) (xy 332.385456 -80.336648) (xy 332.2948 -80.35584) (xy 332.20264 -80.3655)
			(xy 332.156308 -80.366108) (xy 332.1558 -80.366108) (xy 332.114698 -80.365633) (xy 332.032843 -80.358048)
			(xy 331.952038 -80.342943) (xy 331.872971 -80.320447) (xy 331.796317 -80.290751) (xy 331.72273 -80.254109)
			(xy 331.652838 -80.210834) (xy 331.587237 -80.161294) (xy 331.526487 -80.105913) (xy 331.471106 -80.045163)
			(xy 331.421566 -79.979562) (xy 331.378291 -79.90967) (xy 331.341649 -79.836083) (xy 331.311953 -79.759429)
			(xy 331.289457 -79.680362) (xy 331.274352 -79.599557) (xy 331.266767 -79.517702) (xy 331.266292 -79.4766)
			(xy 325.12 -79.4766) (xy 325.12 -79.883) (xy 325.119461 -79.916259) (xy 325.110775 -79.982209) (xy 325.093553 -80.04646)
			(xy 325.068089 -80.107911) (xy 325.034818 -80.165512) (xy 324.994312 -80.218276) (xy 324.971156 -80.242156)
			(xy 324.336156 -80.877156) (xy 324.312271 -80.900308) (xy 324.259511 -80.940821) (xy 324.201912 -80.974097)
			(xy 324.140461 -80.999566) (xy 324.07621 -81.016791) (xy 324.01026 -81.025479) (xy 323.977 -81.026)
			(xy 311.395364 -81.026) (xy 311.362104 -81.025484) (xy 311.296153 -81.016794) (xy 311.231902 -80.999567)
			(xy 311.17045 -80.974099) (xy 311.11285 -80.940824) (xy 311.060087 -80.900314) (xy 311.036208 -80.877156)
			(xy 310.362854 -80.203802) (xy 310.339678 -80.179939) (xy 310.299167 -80.127175) (xy 310.265894 -80.069571)
			(xy 310.240429 -80.008116) (xy 310.223209 -79.943861) (xy 310.214528 -79.877907) (xy 310.21401 -79.844646)
			(xy 310.21401 -68.489322) (xy 310.213597 -68.479251) (xy 310.20587 -68.460652) (xy 310.199024 -68.453254)
			(xy 309.613046 -67.867276) (xy 309.605627 -67.86046) (xy 309.587042 -67.852727) (xy 309.576978 -67.85229)
			(xy 308.297834 -67.85229) (xy 308.288617 -67.852597) (xy 308.27136 -67.859068) (xy 308.25753 -67.87125)
			(xy 308.252876 -67.879214) (xy 308.23281 -67.915996) (xy 308.186744 -67.985991) (xy 308.134301 -68.051344)
			(xy 308.075945 -68.111477) (xy 308.012194 -68.165856) (xy 307.943612 -68.214001) (xy 307.870808 -68.255483)
			(xy 307.794425 -68.289937) (xy 307.715142 -68.317056) (xy 307.633659 -68.3366) (xy 307.550701 -68.348396)
			(xy 307.467 -68.35234) (xy 307.383299 -68.348396) (xy 307.300341 -68.3366) (xy 307.218858 -68.317056)
			(xy 307.139575 -68.289937) (xy 307.063192 -68.255483) (xy 306.990388 -68.214001) (xy 306.921806 -68.165856)
			(xy 306.858055 -68.111477) (xy 306.799699 -68.051344) (xy 306.747256 -67.985991) (xy 306.70119 -67.915996)
			(xy 306.681124 -67.879214) (xy 306.676465 -67.87127) (xy 306.6626 -67.859162) (xy 306.645369 -67.852685)
			(xy 306.636166 -67.85229) (xy 305.487578 -67.85229) (xy 305.476114 -67.85278) (xy 305.455445 -67.862699)
			(xy 305.44113 -67.880606) (xy 305.438048 -67.89166) (xy 305.428779 -67.929708) (xy 305.404431 -68.004145)
			(xy 305.37363 -68.076151) (xy 305.355498 -68.110862) (xy 305.350086 -68.12233) (xy 305.350082 -68.147656)
			(xy 305.355498 -68.159122) (xy 305.375775 -68.198007) (xy 305.409465 -68.27898) (xy 305.43503 -68.362874)
			(xy 305.452222 -68.448875) (xy 305.460875 -68.536149) (xy 305.461416 -68.58) (xy 305.460899 -68.623763)
			(xy 305.4523 -68.710865) (xy 305.435194 -68.796702) (xy 305.409747 -68.880447) (xy 305.376204 -68.961289)
			(xy 305.356006 -69.000116) (xy 305.350776 -69.011509) (xy 305.350889 -69.036543) (xy 305.35626 -69.047868)
			(xy 305.376521 -69.086782) (xy 305.410157 -69.167817) (xy 305.435668 -69.251765) (xy 305.452807 -69.337814)
			(xy 305.461409 -69.42513) (xy 305.461924 -69.469) (xy 305.461407 -69.512819) (xy 305.452768 -69.60003)
			(xy 305.435612 -69.685973) (xy 305.410106 -69.769817) (xy 305.376495 -69.850754) (xy 305.35626 -69.889624)
			(xy 305.35095 -69.90098) (xy 305.35095 -69.92602) (xy 305.35626 -69.937376) (xy 305.376509 -69.976241)
			(xy 305.410141 -70.057171) (xy 305.435652 -70.141016) (xy 305.452795 -70.226963) (xy 305.461403 -70.31418)
			(xy 305.461924 -70.358) (xy 305.46142 -70.400397) (xy 305.45336 -70.484807) (xy 305.437312 -70.568068)
			(xy 305.413423 -70.649427) (xy 305.381908 -70.728147) (xy 305.343054 -70.803515) (xy 305.297211 -70.874848)
			(xy 305.244795 -70.9415) (xy 305.18628 -71.002868) (xy 305.122198 -71.058396) (xy 305.053127 -71.107581)
			(xy 304.979693 -71.149978) (xy 304.902562 -71.185203) (xy 304.822432 -71.212936) (xy 304.740028 -71.232927)
			(xy 304.656098 -71.244994) (xy 304.5714 -71.249029) (xy 304.486702 -71.244994) (xy 304.402772 -71.232927)
			(xy 304.320368 -71.212936) (xy 304.240238 -71.185203) (xy 304.163107 -71.149978) (xy 304.089673 -71.107581)
			(xy 304.020602 -71.058396) (xy 303.95652 -71.002868) (xy 303.898005 -70.9415) (xy 303.845589 -70.874848)
			(xy 303.799746 -70.803515) (xy 303.760892 -70.728147) (xy 303.729377 -70.649427) (xy 303.705488 -70.568068)
			(xy 303.68944 -70.484807) (xy 303.68138 -70.400397) (xy 303.680876 -70.358) (xy 303.681393 -70.314181)
			(xy 303.690032 -70.22697) (xy 303.707188 -70.141027) (xy 303.732694 -70.057183) (xy 303.766305 -69.976246)
			(xy 303.78654 -69.937376) (xy 303.79185 -69.92602) (xy 303.79185 -69.90098) (xy 303.78654 -69.889624)
			(xy 303.766291 -69.850759) (xy 303.732659 -69.769829) (xy 303.707148 -69.685984) (xy 303.690005 -69.600037)
			(xy 303.681397 -69.51282) (xy 303.680876 -69.469) (xy 303.681366 -69.425129) (xy 303.689958 -69.337809)
			(xy 303.707097 -69.251758) (xy 303.732618 -69.167811) (xy 303.766273 -69.08678) (xy 303.78654 -69.047868)
			(xy 303.791948 -69.036553) (xy 303.792061 -69.0115) (xy 303.786794 -69.000116) (xy 303.766602 -68.961287)
			(xy 303.733053 -68.880446) (xy 303.707604 -68.796703) (xy 303.6905 -68.710865) (xy 303.681907 -68.623763)
			(xy 303.681384 -68.58) (xy 303.681935 -68.536149) (xy 303.690574 -68.448872) (xy 303.707759 -68.36287)
			(xy 303.733323 -68.278975) (xy 303.767017 -68.198003) (xy 303.787302 -68.159122) (xy 303.792725 -68.147658)
			(xy 303.792722 -68.122328) (xy 303.787302 -68.110862) (xy 303.769177 -68.076148) (xy 303.738379 -68.004141)
			(xy 303.714026 -67.929707) (xy 303.704752 -67.89166) (xy 303.701577 -67.88066) (xy 303.68727 -67.862821)
			(xy 303.666655 -67.852924) (xy 303.655222 -67.85229) (xy 302.506634 -67.85229) (xy 302.497417 -67.852597)
			(xy 302.48016 -67.859068) (xy 302.46633 -67.87125) (xy 302.461676 -67.879214) (xy 302.44161 -67.915996)
			(xy 302.395544 -67.985991) (xy 302.343101 -68.051344) (xy 302.284745 -68.111477) (xy 302.220994 -68.165856)
			(xy 302.152412 -68.214001) (xy 302.079608 -68.255483) (xy 302.003225 -68.289937) (xy 301.923942 -68.317056)
			(xy 301.842459 -68.3366) (xy 301.759501 -68.348396) (xy 301.6758 -68.35234) (xy 301.592099 -68.348396)
			(xy 301.509141 -68.3366) (xy 301.427658 -68.317056) (xy 301.348375 -68.289937) (xy 301.271992 -68.255483)
			(xy 301.199188 -68.214001) (xy 301.130606 -68.165856) (xy 301.066855 -68.111477) (xy 301.008499 -68.051344)
			(xy 300.956056 -67.985991) (xy 300.90999 -67.915996) (xy 300.889924 -67.879214) (xy 300.885265 -67.87127)
			(xy 300.8714 -67.859162) (xy 300.854169 -67.852685) (xy 300.844966 -67.85229) (xy 298.591224 -67.85229)
			(xy 298.578545 -67.852998) (xy 298.556276 -67.865134) (xy 298.548806 -67.875404) (xy 298.495212 -67.957446)
			(xy 298.49318 -67.982846) (xy 298.498514 -67.994784) (xy 298.516563 -68.037163) (xy 298.544786 -68.124852)
			(xy 298.563783 -68.21499) (xy 298.57335 -68.306611) (xy 298.573952 -68.35267) (xy 298.573952 -68.35394)
			(xy 298.573428 -68.396357) (xy 298.565359 -68.480805) (xy 298.549288 -68.564102) (xy 298.525362 -68.645491)
			(xy 298.493797 -68.724233) (xy 298.454881 -68.799613) (xy 298.408966 -68.870947) (xy 298.35647 -68.937587)
			(xy 298.297869 -68.998927) (xy 298.266104 -69.02704) (xy 298.258204 -69.034606) (xy 298.249106 -69.05447)
			(xy 298.248578 -69.065394) (xy 298.248578 -69.14261) (xy 298.2491 -69.153536) (xy 298.258191 -69.173411)
			(xy 298.266104 -69.180964) (xy 298.297847 -69.209103) (xy 298.356452 -69.270438) (xy 298.408954 -69.337073)
			(xy 298.454874 -69.408403) (xy 298.493797 -69.48378) (xy 298.525369 -69.562519) (xy 298.549303 -69.643905)
			(xy 298.565381 -69.7272) (xy 298.573459 -69.811648) (xy 298.573952 -69.854064) (xy 298.573448 -69.896412)
			(xy 298.565397 -69.980726) (xy 298.549368 -70.063892) (xy 298.525507 -70.145159) (xy 298.494028 -70.223789)
			(xy 298.455217 -70.29907) (xy 298.409427 -70.370322) (xy 298.357071 -70.436898) (xy 298.298623 -70.498196)
			(xy 298.234613 -70.553661) (xy 298.165621 -70.60279) (xy 298.092271 -70.645139) (xy 298.015228 -70.680323)
			(xy 297.935189 -70.708025) (xy 297.85288 -70.727993) (xy 297.769045 -70.740046) (xy 297.684444 -70.744077)
			(xy 297.599843 -70.740046) (xy 297.516008 -70.727993) (xy 297.433699 -70.708025) (xy 297.35366 -70.680323)
			(xy 297.276617 -70.645139) (xy 297.203267 -70.60279) (xy 297.134275 -70.553661) (xy 297.070265 -70.498196)
			(xy 297.011817 -70.436898) (xy 296.959461 -70.370322) (xy 296.913671 -70.29907) (xy 296.87486 -70.223789)
			(xy 296.843381 -70.145159) (xy 296.81952 -70.063892) (xy 296.803491 -69.980726) (xy 296.79544 -69.896412)
			(xy 296.794936 -69.854064) (xy 296.795467 -69.811648) (xy 296.803535 -69.727199) (xy 296.819606 -69.643903)
			(xy 296.843531 -69.562514) (xy 296.875095 -69.483772) (xy 296.91401 -69.408392) (xy 296.959924 -69.337058)
			(xy 297.012419 -69.270418) (xy 297.071019 -69.209078) (xy 297.102784 -69.180964) (xy 297.110696 -69.173409)
			(xy 297.119784 -69.153536) (xy 297.12031 -69.14261) (xy 297.12031 -69.065394) (xy 297.119789 -69.054467)
			(xy 297.110698 -69.034593) (xy 297.102784 -69.02704) (xy 297.07104 -68.998902) (xy 297.012435 -68.937566)
			(xy 296.959935 -68.870931) (xy 296.914014 -68.799601) (xy 296.875092 -68.724224) (xy 296.84352 -68.645485)
			(xy 296.819586 -68.564099) (xy 296.803507 -68.480804) (xy 296.795429 -68.396356) (xy 296.794936 -68.35394)
			(xy 296.795441 -68.312106) (xy 296.803292 -68.228806) (xy 296.818929 -68.146612) (xy 296.842213 -68.066249)
			(xy 296.872939 -67.988426) (xy 296.910835 -67.913832) (xy 296.955566 -67.843124) (xy 297.006738 -67.776929)
			(xy 297.063899 -67.71583) (xy 297.126543 -67.660367) (xy 297.194117 -67.61103) (xy 297.266025 -67.568255)
			(xy 297.34163 -67.532419) (xy 297.420267 -67.50384) (xy 297.501238 -67.482769) (xy 297.542458 -67.475608)
			(xy 297.556682 -67.473322) (xy 297.578272 -67.45478) (xy 297.61053 -67.354958) (xy 297.612969 -67.345949)
			(xy 297.611952 -67.32733) (xy 297.60437 -67.310294) (xy 297.598084 -67.303396) (xy 296.363644 -66.068956)
			(xy 296.340492 -66.045071) (xy 296.299979 -65.992311) (xy 296.266703 -65.934712) (xy 296.241234 -65.873261)
			(xy 296.224009 -65.80901) (xy 296.215321 -65.74306) (xy 296.2148 -65.7098) (xy 296.2148 -62.258194)
			(xy 296.214404 -62.248121) (xy 296.206666 -62.229522) (xy 296.199814 -62.222126) (xy 293.225474 -59.247786)
			(xy 293.218079 -59.24094) (xy 293.199476 -59.233224) (xy 293.189406 -59.2328) (xy 282.2448 -59.2328)
			(xy 282.211541 -59.232261) (xy 282.145591 -59.223575) (xy 282.08134 -59.206353) (xy 282.019889 -59.180889)
			(xy 281.962288 -59.147618) (xy 281.909524 -59.107112) (xy 281.885644 -59.083956) (xy 267.901674 -45.099986)
			(xy 267.894279 -45.09314) (xy 267.875676 -45.085424) (xy 267.865606 -45.085) (xy 259.333238 -45.085)
			(xy 259.322011 -45.085616) (xy 259.301721 -45.095252) (xy 259.294122 -45.103542) (xy 259.28631 -45.112836)
			(xy 259.269921 -45.130751) (xy 259.261356 -45.139356) (xy 258.713986 -45.68698) (xy 258.70716 -45.694391)
			(xy 258.699433 -45.712982) (xy 258.699 -45.723048) (xy 258.699 -47.032361) (xy 259.359142 -47.032361)
			(xy 259.359142 -46.947639) (xy 259.367195 -46.863302) (xy 259.383229 -46.780112) (xy 259.407097 -46.698822)
			(xy 259.438585 -46.62017) (xy 259.477407 -46.544867) (xy 259.52321 -46.473595) (xy 259.575581 -46.406999)
			(xy 259.634046 -46.345684) (xy 259.698074 -46.290203) (xy 259.767086 -46.24106) (xy 259.840456 -46.1987)
			(xy 259.917521 -46.163505) (xy 259.997583 -46.135796) (xy 260.079916 -46.115822) (xy 260.163775 -46.103765)
			(xy 260.2484 -46.099734) (xy 260.333025 -46.103765) (xy 260.416884 -46.115822) (xy 260.499217 -46.135796)
			(xy 260.579279 -46.163505) (xy 260.656344 -46.1987) (xy 260.729714 -46.24106) (xy 260.798726 -46.290203)
			(xy 260.862754 -46.345684) (xy 260.921219 -46.406999) (xy 260.97359 -46.473595) (xy 261.019393 -46.544867)
			(xy 261.058215 -46.62017) (xy 261.089703 -46.698822) (xy 261.113571 -46.780112) (xy 261.129605 -46.863302)
			(xy 261.137658 -46.947639) (xy 261.138162 -46.99) (xy 261.137658 -47.032361) (xy 261.129605 -47.116698)
			(xy 261.113571 -47.199888) (xy 261.089703 -47.281178) (xy 261.058215 -47.35983) (xy 261.019393 -47.435133)
			(xy 260.97359 -47.506405) (xy 260.921219 -47.573001) (xy 260.862754 -47.634316) (xy 260.798726 -47.689797)
			(xy 260.729714 -47.73894) (xy 260.656344 -47.7813) (xy 260.579279 -47.816495) (xy 260.499217 -47.844204)
			(xy 260.416884 -47.864178) (xy 260.333025 -47.876235) (xy 260.2484 -47.880267) (xy 260.163775 -47.876235)
			(xy 260.079916 -47.864178) (xy 259.997583 -47.844204) (xy 259.917521 -47.816495) (xy 259.840456 -47.7813)
			(xy 259.767086 -47.73894) (xy 259.698074 -47.689797) (xy 259.634046 -47.634316) (xy 259.575581 -47.573001)
			(xy 259.52321 -47.506405) (xy 259.477407 -47.435133) (xy 259.438585 -47.35983) (xy 259.407097 -47.281178)
			(xy 259.383229 -47.199888) (xy 259.367195 -47.116698) (xy 259.359142 -47.032361) (xy 258.699 -47.032361)
			(xy 258.699 -50.894996) (xy 258.698458 -50.928255) (xy 258.689773 -50.994205) (xy 258.672551 -51.058455)
			(xy 258.647088 -51.119907) (xy 258.613818 -51.177508) (xy 258.573312 -51.230272) (xy 258.550156 -51.254152)
			(xy 257.878072 -51.926236) (xy 257.854176 -51.949376) (xy 257.801419 -51.989891) (xy 257.743823 -52.023169)
			(xy 257.682374 -52.04864) (xy 257.618124 -52.065868) (xy 257.552175 -52.074558) (xy 257.518916 -52.07508)
			(xy 247.302782 -52.07508) (xy 247.269522 -52.074558) (xy 247.203572 -52.06587) (xy 247.13932 -52.048645)
			(xy 247.077868 -52.023177) (xy 247.020268 -51.989904) (xy 246.967505 -51.949394) (xy 246.943626 -51.926236)
			(xy 246.398796 -51.381406) (xy 246.375611 -51.357551) (xy 246.335103 -51.304784) (xy 246.301833 -51.247179)
			(xy 246.27637 -51.185722) (xy 246.259151 -51.121466) (xy 246.25047 -51.055512) (xy 246.249952 -51.02225)
			(xy 246.249952 -46.654466) (xy 246.250454 -46.621205) (xy 246.259145 -46.555254) (xy 246.276374 -46.491002)
			(xy 246.301845 -46.42955) (xy 246.335122 -46.37195) (xy 246.375636 -46.319188) (xy 246.398796 -46.29531)
			(xy 250.260866 -42.43324) (xy 250.266962 -42.403268) (xy 250.260866 -42.389044) (xy 250.256653 -42.379914)
			(xy 250.242478 -42.365674) (xy 250.223922 -42.357969) (xy 250.213876 -42.357548) (xy 249.2248 -42.357548)
			(xy 249.214729 -42.357961) (xy 249.196131 -42.365689) (xy 249.188732 -42.372534) (xy 243.32311 -48.238156)
			(xy 243.299245 -48.26133) (xy 243.246481 -48.301841) (xy 243.188878 -48.335114) (xy 243.127423 -48.360579)
			(xy 243.063168 -48.3778) (xy 242.997215 -48.386482) (xy 242.963954 -48.387) (xy 230.251 -48.387)
			(xy 230.217741 -48.386461) (xy 230.151791 -48.377775) (xy 230.08754 -48.360553) (xy 230.026089 -48.335089)
			(xy 229.968488 -48.301818) (xy 229.915724 -48.261312) (xy 229.891844 -48.238156) (xy 229.002844 -47.349156)
			(xy 228.979692 -47.325271) (xy 228.939179 -47.272511) (xy 228.905903 -47.214912) (xy 228.880434 -47.153461)
			(xy 228.863209 -47.08921) (xy 228.854521 -47.02326) (xy 228.854 -46.99) (xy 211.4804 -46.99) (xy 211.479861 -47.023259)
			(xy 211.471175 -47.089209) (xy 211.453953 -47.15346) (xy 211.428489 -47.214911) (xy 211.395218 -47.272512)
			(xy 211.354712 -47.325276) (xy 211.331556 -47.349156) (xy 210.442556 -48.238156) (xy 210.418671 -48.261308)
			(xy 210.365911 -48.301821) (xy 210.308312 -48.335097) (xy 210.246861 -48.360566) (xy 210.18261 -48.377791)
			(xy 210.11666 -48.386479) (xy 210.0834 -48.387) (xy 197.797166 -48.387) (xy 197.763906 -48.386483)
			(xy 197.697955 -48.377793) (xy 197.633704 -48.360566) (xy 197.572252 -48.335098) (xy 197.514652 -48.301824)
			(xy 197.461889 -48.261314) (xy 197.43801 -48.238156) (xy 191.552068 -42.352214) (xy 191.544671 -42.345369)
			(xy 191.52607 -42.337652) (xy 191.516 -42.337228) (xy 190.21425 -42.337228) (xy 190.203612 -42.337748)
			(xy 190.184155 -42.346351) (xy 190.169854 -42.362101) (xy 190.16599 -42.372026) (xy 190.13551 -42.463466)
			(xy 190.132593 -42.473671) (xy 190.134551 -42.494786) (xy 190.144888 -42.513301) (xy 190.153036 -42.520108)
			(xy 190.15329 -42.520108) (xy 190.167457 -42.530955) (xy 190.194407 -42.554343) (xy 190.207138 -42.566844)
			(xy 193.935604 -46.29531) (xy 193.958748 -46.319202) (xy 193.99926 -46.371961) (xy 194.032536 -46.429559)
			(xy 194.058006 -46.491009) (xy 194.075234 -46.555258) (xy 194.083925 -46.621207) (xy 194.084448 -46.654466)
			(xy 194.084448 -51.02225) (xy 194.084038 -51.049936) (xy 207.409803 -51.049936) (xy 207.413813 -50.944033)
			(xy 207.425821 -50.838737) (xy 207.445758 -50.734651) (xy 207.47351 -50.632371) (xy 207.508918 -50.532482)
			(xy 207.551779 -50.435558) (xy 207.601847 -50.342152) (xy 207.658837 -50.252801) (xy 207.72242 -50.168015)
			(xy 207.792234 -50.088281) (xy 207.867878 -50.014056) (xy 207.948918 -49.945763) (xy 208.034892 -49.883796)
			(xy 208.125306 -49.828508) (xy 208.219642 -49.780216) (xy 208.317361 -49.739197) (xy 208.417901 -49.705686)
			(xy 208.520689 -49.679874) (xy 208.625133 -49.66191) (xy 208.730638 -49.651897) (xy 208.836597 -49.649891)
			(xy 208.942405 -49.655905) (xy 209.047455 -49.669904) (xy 209.151145 -49.691807) (xy 209.252882 -49.72149)
			(xy 209.352083 -49.758781) (xy 209.448179 -49.803469) (xy 209.54062 -49.855296) (xy 209.628877 -49.913966)
			(xy 209.712444 -49.979143) (xy 209.790843 -50.050453) (xy 209.863624 -50.127487) (xy 209.93037 -50.209806)
			(xy 209.9907 -50.296937) (xy 210.044267 -50.388381) (xy 210.090765 -50.483614) (xy 210.129927 -50.582091)
			(xy 210.16153 -50.683248) (xy 210.185391 -50.786506) (xy 210.201376 -50.891272) (xy 210.209391 -50.996947)
			(xy 210.209892 -51.049936) (xy 237.409743 -51.049936) (xy 237.413753 -50.944033) (xy 237.425761 -50.838737)
			(xy 237.445698 -50.734651) (xy 237.47345 -50.632371) (xy 237.508858 -50.532482) (xy 237.551719 -50.435558)
			(xy 237.601787 -50.342152) (xy 237.658777 -50.252801) (xy 237.72236 -50.168015) (xy 237.792174 -50.088281)
			(xy 237.867818 -50.014056) (xy 237.948858 -49.945763) (xy 238.034832 -49.883796) (xy 238.125246 -49.828508)
			(xy 238.219582 -49.780216) (xy 238.317301 -49.739197) (xy 238.417841 -49.705686) (xy 238.520629 -49.679874)
			(xy 238.625073 -49.66191) (xy 238.730578 -49.651897) (xy 238.836537 -49.649891) (xy 238.942345 -49.655905)
			(xy 239.047395 -49.669904) (xy 239.151085 -49.691807) (xy 239.252822 -49.72149) (xy 239.352023 -49.758781)
			(xy 239.448119 -49.803469) (xy 239.54056 -49.855296) (xy 239.628817 -49.913966) (xy 239.712384 -49.979143)
			(xy 239.790783 -50.050453) (xy 239.863564 -50.127487) (xy 239.93031 -50.209806) (xy 239.99064 -50.296937)
			(xy 240.044207 -50.388381) (xy 240.090705 -50.483614) (xy 240.129867 -50.582091) (xy 240.16147 -50.683248)
			(xy 240.185331 -50.786506) (xy 240.201316 -50.891272) (xy 240.209331 -50.996947) (xy 240.209832 -51.049936)
			(xy 240.209331 -51.102925) (xy 240.201316 -51.2086) (xy 240.185331 -51.313366) (xy 240.16147 -51.416624)
			(xy 240.129867 -51.517781) (xy 240.090705 -51.616258) (xy 240.044207 -51.711491) (xy 239.99064 -51.802935)
			(xy 239.93031 -51.890066) (xy 239.863564 -51.972385) (xy 239.790783 -52.049419) (xy 239.712384 -52.120729)
			(xy 239.628817 -52.185906) (xy 239.54056 -52.244576) (xy 239.448119 -52.296403) (xy 239.352023 -52.341091)
			(xy 239.252822 -52.378382) (xy 239.151085 -52.408065) (xy 239.047395 -52.429968) (xy 238.942345 -52.443967)
			(xy 238.836537 -52.449981) (xy 238.730578 -52.447975) (xy 238.625073 -52.437962) (xy 238.520629 -52.419998)
			(xy 238.417841 -52.394186) (xy 238.317301 -52.360675) (xy 238.219582 -52.319656) (xy 238.125246 -52.271364)
			(xy 238.034832 -52.216076) (xy 237.948858 -52.154109) (xy 237.867818 -52.085816) (xy 237.792174 -52.011591)
			(xy 237.72236 -51.931857) (xy 237.658777 -51.847071) (xy 237.601787 -51.75772) (xy 237.551719 -51.664314)
			(xy 237.508858 -51.56739) (xy 237.47345 -51.467501) (xy 237.445698 -51.365221) (xy 237.425761 -51.261135)
			(xy 237.413753 -51.155839) (xy 237.409743 -51.049936) (xy 210.209892 -51.049936) (xy 210.209391 -51.102925)
			(xy 210.201376 -51.2086) (xy 210.185391 -51.313366) (xy 210.16153 -51.416624) (xy 210.129927 -51.517781)
			(xy 210.090765 -51.616258) (xy 210.044267 -51.711491) (xy 209.9907 -51.802935) (xy 209.93037 -51.890066)
			(xy 209.863624 -51.972385) (xy 209.790843 -52.049419) (xy 209.712444 -52.120729) (xy 209.628877 -52.185906)
			(xy 209.54062 -52.244576) (xy 209.448179 -52.296403) (xy 209.352083 -52.341091) (xy 209.252882 -52.378382)
			(xy 209.151145 -52.408065) (xy 209.047455 -52.429968) (xy 208.942405 -52.443967) (xy 208.836597 -52.449981)
			(xy 208.730638 -52.447975) (xy 208.625133 -52.437962) (xy 208.520689 -52.419998) (xy 208.417901 -52.394186)
			(xy 208.317361 -52.360675) (xy 208.219642 -52.319656) (xy 208.125306 -52.271364) (xy 208.034892 -52.216076)
			(xy 207.948918 -52.154109) (xy 207.867878 -52.085816) (xy 207.792234 -52.011591) (xy 207.72242 -51.931857)
			(xy 207.658837 -51.847071) (xy 207.601847 -51.75772) (xy 207.551779 -51.664314) (xy 207.508918 -51.56739)
			(xy 207.47351 -51.467501) (xy 207.445758 -51.365221) (xy 207.425821 -51.261135) (xy 207.413813 -51.155839)
			(xy 207.409803 -51.049936) (xy 194.084038 -51.049936) (xy 194.083956 -51.055511) (xy 194.075263 -51.121463)
			(xy 194.058032 -51.185715) (xy 194.03256 -51.247167) (xy 193.99928 -51.304767) (xy 193.958765 -51.357528)
			(xy 193.935604 -51.381406) (xy 193.390774 -51.926236) (xy 193.366877 -51.949375) (xy 193.31412 -51.989891)
			(xy 193.256524 -52.023169) (xy 193.195075 -52.04864) (xy 193.130826 -52.065868) (xy 193.064877 -52.074557)
			(xy 193.031618 -52.07508) (xy 182.815484 -52.07508) (xy 182.782224 -52.074557) (xy 182.716274 -52.065869)
			(xy 182.652022 -52.048644) (xy 182.59057 -52.023177) (xy 182.53297 -51.989903) (xy 182.480207 -51.949394)
			(xy 182.456328 -51.926236) (xy 181.784244 -51.254152) (xy 181.76109 -51.230269) (xy 181.720577 -51.177508)
			(xy 181.687302 -51.119909) (xy 181.661833 -51.058458) (xy 181.644608 -50.994207) (xy 181.635921 -50.928256)
			(xy 181.6354 -50.894996) (xy 181.6354 -46.609) (xy 181.635939 -46.575741) (xy 181.644625 -46.509791)
			(xy 181.661847 -46.44554) (xy 181.687311 -46.384089) (xy 181.720582 -46.326488) (xy 181.761088 -46.273724)
			(xy 181.784244 -46.249844) (xy 185.467244 -42.566844) (xy 185.479973 -42.554341) (xy 185.506922 -42.530951)
			(xy 185.521092 -42.520108) (xy 185.521346 -42.520108) (xy 185.529459 -42.513289) (xy 185.539717 -42.494765)
			(xy 185.541693 -42.473684) (xy 185.538872 -42.463466) (xy 185.508392 -42.372026) (xy 185.504497 -42.362119)
			(xy 185.4902 -42.346385) (xy 185.470761 -42.337776) (xy 185.460132 -42.337228) (xy 174.147226 -42.337228)
			(xy 174.137157 -42.337659) (xy 174.118559 -42.345375) (xy 174.111158 -42.352214) (xy 172.697648 -43.765724)
			(xy 172.690812 -43.773127) (xy 172.683088 -43.791724) (xy 172.682662 -43.801792) (xy 172.682662 -47.032361)
			(xy 177.987702 -47.032361) (xy 177.987702 -46.947639) (xy 177.995755 -46.863302) (xy 178.011789 -46.780112)
			(xy 178.035657 -46.698822) (xy 178.067145 -46.62017) (xy 178.105967 -46.544867) (xy 178.15177 -46.473595)
			(xy 178.204141 -46.406999) (xy 178.262606 -46.345684) (xy 178.326634 -46.290203) (xy 178.395646 -46.24106)
			(xy 178.469016 -46.1987) (xy 178.546081 -46.163505) (xy 178.626143 -46.135796) (xy 178.708476 -46.115822)
			(xy 178.792335 -46.103765) (xy 178.87696 -46.099734) (xy 178.961585 -46.103765) (xy 179.045444 -46.115822)
			(xy 179.127777 -46.135796) (xy 179.207839 -46.163505) (xy 179.284904 -46.1987) (xy 179.358274 -46.24106)
			(xy 179.427286 -46.290203) (xy 179.491314 -46.345684) (xy 179.549779 -46.406999) (xy 179.60215 -46.473595)
			(xy 179.647953 -46.544867) (xy 179.686775 -46.62017) (xy 179.718263 -46.698822) (xy 179.742131 -46.780112)
			(xy 179.758165 -46.863302) (xy 179.766218 -46.947639) (xy 179.766722 -46.99) (xy 179.766218 -47.032361)
			(xy 179.758165 -47.116698) (xy 179.742131 -47.199888) (xy 179.718263 -47.281178) (xy 179.686775 -47.35983)
			(xy 179.647953 -47.435133) (xy 179.60215 -47.506405) (xy 179.549779 -47.573001) (xy 179.491314 -47.634316)
			(xy 179.427286 -47.689797) (xy 179.358274 -47.73894) (xy 179.284904 -47.7813) (xy 179.207839 -47.816495)
			(xy 179.127777 -47.844204) (xy 179.045444 -47.864178) (xy 178.961585 -47.876235) (xy 178.87696 -47.880267)
			(xy 178.792335 -47.876235) (xy 178.708476 -47.864178) (xy 178.626143 -47.844204) (xy 178.546081 -47.816495)
			(xy 178.469016 -47.7813) (xy 178.395646 -47.73894) (xy 178.326634 -47.689797) (xy 178.262606 -47.634316)
			(xy 178.204141 -47.573001) (xy 178.15177 -47.506405) (xy 178.105967 -47.435133) (xy 178.067145 -47.35983)
			(xy 178.035657 -47.281178) (xy 178.011789 -47.199888) (xy 177.995755 -47.116698) (xy 177.987702 -47.032361)
			(xy 172.682662 -47.032361) (xy 172.682662 -50.465228) (xy 172.683056 -50.475301) (xy 172.690797 -50.4939)
			(xy 172.697648 -50.501296) (xy 172.778674 -50.582322) (xy 172.786086 -50.589146) (xy 172.804676 -50.596875)
			(xy 172.814742 -50.597308) (xy 173.980348 -50.597308) (xy 174.013609 -50.597814) (xy 174.07956 -50.606506)
			(xy 174.143811 -50.623734) (xy 174.205263 -50.649205) (xy 174.262863 -50.682481) (xy 174.315625 -50.722993)
			(xy 174.339504 -50.746152) (xy 176.661318 -53.067966) (xy 176.684492 -53.091831) (xy 176.725 -53.144596)
			(xy 176.758272 -53.2022) (xy 176.783737 -53.263655) (xy 176.800958 -53.327908) (xy 176.809642 -53.393861)
			(xy 176.810162 -53.427122) (xy 176.810162 -54.679088) (xy 176.809626 -54.712348) (xy 176.800941 -54.778298)
			(xy 176.783719 -54.842549) (xy 176.758254 -54.904001) (xy 176.724983 -54.961602) (xy 176.684475 -55.014365)
			(xy 176.661318 -55.038244) (xy 175.970438 -55.729124) (xy 175.946572 -55.752297) (xy 175.893807 -55.792805)
			(xy 175.836204 -55.826077) (xy 175.774749 -55.851542) (xy 175.710495 -55.868764) (xy 175.644543 -55.877448)
			(xy 175.611282 -55.877968) (xy 160.844484 -55.877968) (xy 160.834411 -55.878367) (xy 160.815813 -55.886104)
			(xy 160.808416 -55.892954) (xy 158.78937 -57.912) (xy 268.756388 -57.912) (xy 268.760418 -57.827399)
			(xy 268.772471 -57.743564) (xy 268.792439 -57.661255) (xy 268.820141 -57.581216) (xy 268.855325 -57.504173)
			(xy 268.897674 -57.430823) (xy 268.946803 -57.361831) (xy 269.002268 -57.297821) (xy 269.063566 -57.239373)
			(xy 269.130142 -57.187017) (xy 269.201394 -57.141227) (xy 269.276675 -57.102416) (xy 269.355305 -57.070937)
			(xy 269.436572 -57.047076) (xy 269.519738 -57.031047) (xy 269.604052 -57.022996) (xy 269.6464 -57.022492)
			(xy 269.646908 -57.022492) (xy 269.69324 -57.023098) (xy 269.785398 -57.032769) (xy 269.876052 -57.051965)
			(xy 269.964221 -57.080477) (xy 270.006826 -57.098692) (xy 270.016768 -57.102498) (xy 270.038032 -57.102498)
			(xy 270.047974 -57.098692) (xy 270.090636 -57.080447) (xy 270.178929 -57.051903) (xy 270.269714 -57.03271)
			(xy 270.362004 -57.023077) (xy 270.4084 -57.022492) (xy 270.451753 -57.02298) (xy 270.538049 -57.031388)
			(xy 270.623118 -57.048154) (xy 270.706152 -57.073118) (xy 270.786362 -57.106044) (xy 270.862988 -57.146619)
			(xy 270.935302 -57.194458) (xy 271.002617 -57.249107) (xy 271.064295 -57.310046) (xy 271.092422 -57.34304)
			(xy 271.099534 -57.351676) (xy 271.119854 -57.361328) (xy 271.220946 -57.361328) (xy 271.241266 -57.351676)
			(xy 271.248378 -57.34304) (xy 271.276524 -57.310064) (xy 271.338205 -57.249132) (xy 271.40552 -57.194489)
			(xy 271.477833 -57.146654) (xy 271.554455 -57.106081) (xy 271.634662 -57.073155) (xy 271.717692 -57.048188)
			(xy 271.802756 -57.031418) (xy 271.889049 -57.023002) (xy 271.9324 -57.022492) (xy 271.978796 -57.023075)
			(xy 272.071084 -57.03272) (xy 272.161868 -57.051916) (xy 272.250161 -57.080454) (xy 272.292826 -57.098692)
			(xy 272.302768 -57.102498) (xy 272.324032 -57.102498) (xy 272.333974 -57.098692) (xy 272.376577 -57.08047)
			(xy 272.464744 -57.051952) (xy 272.5554 -57.03276) (xy 272.64756 -57.0231) (xy 272.693892 -57.022492)
			(xy 272.6944 -57.022492) (xy 272.736748 -57.022996) (xy 272.821062 -57.031047) (xy 272.904228 -57.047076)
			(xy 272.985495 -57.070937) (xy 273.064125 -57.102416) (xy 273.139406 -57.141227) (xy 273.210658 -57.187017)
			(xy 273.277234 -57.239373) (xy 273.338532 -57.297821) (xy 273.393997 -57.361831) (xy 273.443126 -57.430823)
			(xy 273.485475 -57.504173) (xy 273.520659 -57.581216) (xy 273.548361 -57.661255) (xy 273.568329 -57.743564)
			(xy 273.580382 -57.827399) (xy 273.584413 -57.912) (xy 273.580382 -57.996601) (xy 273.568329 -58.080436)
			(xy 273.548361 -58.162745) (xy 273.520659 -58.242784) (xy 273.485475 -58.319827) (xy 273.443126 -58.393177)
			(xy 273.393997 -58.462169) (xy 273.338532 -58.526179) (xy 273.277234 -58.584627) (xy 273.210658 -58.636983)
			(xy 273.139406 -58.682773) (xy 273.064125 -58.721584) (xy 272.985495 -58.753063) (xy 272.904228 -58.776924)
			(xy 272.821062 -58.792953) (xy 272.736748 -58.801004) (xy 272.6944 -58.801508) (xy 272.693892 -58.801508)
			(xy 272.64756 -58.800902) (xy 272.555402 -58.791231) (xy 272.464748 -58.772035) (xy 272.376579 -58.743523)
			(xy 272.333974 -58.725308) (xy 272.324032 -58.721502) (xy 272.302768 -58.721502) (xy 272.292826 -58.725308)
			(xy 272.250164 -58.743553) (xy 272.161871 -58.772097) (xy 272.071086 -58.79129) (xy 271.978796 -58.800923)
			(xy 271.9324 -58.801508) (xy 271.889047 -58.80102) (xy 271.802751 -58.792612) (xy 271.717682 -58.775846)
			(xy 271.634648 -58.750882) (xy 271.554438 -58.717956) (xy 271.477812 -58.677381) (xy 271.405498 -58.629542)
			(xy 271.338183 -58.574893) (xy 271.276505 -58.513954) (xy 271.248378 -58.48096) (xy 271.241266 -58.472324)
			(xy 271.220946 -58.462672) (xy 271.119854 -58.462672) (xy 271.099534 -58.472324) (xy 271.092422 -58.48096)
			(xy 271.064276 -58.513936) (xy 271.002595 -58.574868) (xy 270.93528 -58.629511) (xy 270.862967 -58.677346)
			(xy 270.786345 -58.717919) (xy 270.706138 -58.750845) (xy 270.623108 -58.775812) (xy 270.538044 -58.792582)
			(xy 270.451751 -58.800998) (xy 270.4084 -58.801508) (xy 270.362004 -58.800925) (xy 270.269716 -58.79128)
			(xy 270.178932 -58.772084) (xy 270.090639 -58.743546) (xy 270.047974 -58.725308) (xy 270.038032 -58.721502)
			(xy 270.016768 -58.721502) (xy 270.006826 -58.725308) (xy 269.964223 -58.74353) (xy 269.876056 -58.772048)
			(xy 269.7854 -58.79124) (xy 269.69324 -58.8009) (xy 269.646908 -58.801508) (xy 269.6464 -58.801508)
			(xy 269.604052 -58.801004) (xy 269.519738 -58.792953) (xy 269.436572 -58.776924) (xy 269.355305 -58.753063)
			(xy 269.276675 -58.721584) (xy 269.201394 -58.682773) (xy 269.130142 -58.636983) (xy 269.063566 -58.584627)
			(xy 269.002268 -58.526179) (xy 268.946803 -58.462169) (xy 268.897674 -58.393177) (xy 268.855325 -58.319827)
			(xy 268.820141 -58.242784) (xy 268.792439 -58.162745) (xy 268.772471 -58.080436) (xy 268.760418 -57.996601)
			(xy 268.756388 -57.912) (xy 158.78937 -57.912) (xy 156.32557 -60.3758) (xy 165.632388 -60.3758) (xy 165.636418 -60.291199)
			(xy 165.648471 -60.207364) (xy 165.668439 -60.125055) (xy 165.696141 -60.045016) (xy 165.731325 -59.967973)
			(xy 165.773674 -59.894623) (xy 165.822803 -59.825631) (xy 165.878268 -59.761621) (xy 165.939566 -59.703173)
			(xy 166.006142 -59.650817) (xy 166.077394 -59.605027) (xy 166.152675 -59.566216) (xy 166.231305 -59.534737)
			(xy 166.312572 -59.510876) (xy 166.395738 -59.494847) (xy 166.480052 -59.486796) (xy 166.5224 -59.486292)
			(xy 166.522908 -59.486292) (xy 166.56924 -59.486898) (xy 166.661398 -59.496569) (xy 166.752052 -59.515765)
			(xy 166.840221 -59.544277) (xy 166.882826 -59.562492) (xy 166.892768 -59.566298) (xy 166.914032 -59.566298)
			(xy 166.923974 -59.562492) (xy 166.966577 -59.54427) (xy 167.054744 -59.515752) (xy 167.1454 -59.49656)
			(xy 167.23756 -59.4869) (xy 167.283892 -59.486292) (xy 167.2844 -59.486292) (xy 167.326748 -59.486796)
			(xy 167.411062 -59.494847) (xy 167.494228 -59.510876) (xy 167.575495 -59.534737) (xy 167.654125 -59.566216)
			(xy 167.729406 -59.605027) (xy 167.800658 -59.650817) (xy 167.867234 -59.703173) (xy 167.928532 -59.761621)
			(xy 167.983997 -59.825631) (xy 168.033126 -59.894623) (xy 168.075475 -59.967973) (xy 168.110659 -60.045016)
			(xy 168.138361 -60.125055) (xy 168.158329 -60.207364) (xy 168.170382 -60.291199) (xy 168.174413 -60.3758)
			(xy 168.170382 -60.460401) (xy 168.158329 -60.544236) (xy 168.138361 -60.626545) (xy 168.110659 -60.706584)
			(xy 168.075475 -60.783627) (xy 168.033126 -60.856977) (xy 167.983997 -60.925969) (xy 167.928532 -60.989979)
			(xy 167.867234 -61.048427) (xy 167.800658 -61.100783) (xy 167.729406 -61.146573) (xy 167.654125 -61.185384)
			(xy 167.575495 -61.216863) (xy 167.494228 -61.240724) (xy 167.411062 -61.256753) (xy 167.326748 -61.264804)
			(xy 167.2844 -61.265308) (xy 167.283892 -61.265308) (xy 167.23756 -61.264702) (xy 167.145402 -61.255031)
			(xy 167.054748 -61.235835) (xy 166.966579 -61.207323) (xy 166.923974 -61.189108) (xy 166.914032 -61.185302)
			(xy 166.892768 -61.185302) (xy 166.882826 -61.189108) (xy 166.840223 -61.20733) (xy 166.752056 -61.235848)
			(xy 166.6614 -61.25504) (xy 166.56924 -61.2647) (xy 166.522908 -61.265308) (xy 166.5224 -61.265308)
			(xy 166.480052 -61.264804) (xy 166.395738 -61.256753) (xy 166.312572 -61.240724) (xy 166.231305 -61.216863)
			(xy 166.152675 -61.185384) (xy 166.077394 -61.146573) (xy 166.006142 -61.100783) (xy 165.939566 -61.048427)
			(xy 165.878268 -60.989979) (xy 165.822803 -60.925969) (xy 165.773674 -60.856977) (xy 165.731325 -60.783627)
			(xy 165.696141 -60.706584) (xy 165.668439 -60.626545) (xy 165.648471 -60.544236) (xy 165.636418 -60.460401)
			(xy 165.632388 -60.3758) (xy 156.32557 -60.3758) (xy 152.143009 -64.558361) (xy 261.838182 -64.558361)
			(xy 261.838182 -64.473639) (xy 261.846235 -64.389302) (xy 261.862269 -64.306112) (xy 261.886137 -64.224822)
			(xy 261.917625 -64.14617) (xy 261.956447 -64.070867) (xy 262.00225 -63.999595) (xy 262.054621 -63.932999)
			(xy 262.113086 -63.871684) (xy 262.177114 -63.816203) (xy 262.246126 -63.76706) (xy 262.319496 -63.7247)
			(xy 262.396561 -63.689505) (xy 262.476623 -63.661796) (xy 262.558956 -63.641822) (xy 262.642815 -63.629765)
			(xy 262.72744 -63.625734) (xy 262.812065 -63.629765) (xy 262.895924 -63.641822) (xy 262.978257 -63.661796)
			(xy 263.058319 -63.689505) (xy 263.135384 -63.7247) (xy 263.208754 -63.76706) (xy 263.277766 -63.816203)
			(xy 263.341794 -63.871684) (xy 263.400259 -63.932999) (xy 263.45263 -63.999595) (xy 263.498433 -64.070867)
			(xy 263.537255 -64.14617) (xy 263.568743 -64.224822) (xy 263.592611 -64.306112) (xy 263.608645 -64.389302)
			(xy 263.616698 -64.473639) (xy 263.617202 -64.516) (xy 263.616698 -64.558361) (xy 263.608645 -64.642698)
			(xy 263.592611 -64.725888) (xy 263.568743 -64.807178) (xy 263.537255 -64.88583) (xy 263.498433 -64.961133)
			(xy 263.45263 -65.032405) (xy 263.400259 -65.099001) (xy 263.341794 -65.160316) (xy 263.277766 -65.215797)
			(xy 263.208754 -65.26494) (xy 263.135384 -65.3073) (xy 263.058319 -65.342495) (xy 262.978257 -65.370204)
			(xy 262.895924 -65.390178) (xy 262.812065 -65.402235) (xy 262.72744 -65.406267) (xy 262.642815 -65.402235)
			(xy 262.558956 -65.390178) (xy 262.476623 -65.370204) (xy 262.396561 -65.342495) (xy 262.319496 -65.3073)
			(xy 262.246126 -65.26494) (xy 262.177114 -65.215797) (xy 262.113086 -65.160316) (xy 262.054621 -65.099001)
			(xy 262.00225 -65.032405) (xy 261.956447 -64.961133) (xy 261.917625 -64.88583) (xy 261.886137 -64.807178)
			(xy 261.862269 -64.725888) (xy 261.846235 -64.642698) (xy 261.838182 -64.558361) (xy 152.143009 -64.558361)
			(xy 150.38197 -66.3194) (xy 178.683872 -66.3194) (xy 178.687902 -66.234795) (xy 178.699957 -66.150957)
			(xy 178.719926 -66.068644) (xy 178.74763 -65.988602) (xy 178.782817 -65.911556) (xy 178.825168 -65.838204)
			(xy 178.8743 -65.769209) (xy 178.929768 -65.705198) (xy 178.99107 -65.646749) (xy 179.057651 -65.594392)
			(xy 179.128907 -65.548601) (xy 179.204193 -65.509791) (xy 179.282827 -65.478314) (xy 179.364098 -65.454453)
			(xy 179.447268 -65.438427) (xy 179.531586 -65.430378) (xy 179.573936 -65.429892) (xy 179.574698 -65.429892)
			(xy 179.613046 -65.430288) (xy 179.689453 -65.436923) (xy 179.765005 -65.450117) (xy 179.839139 -65.469774)
			(xy 179.911302 -65.495746) (xy 179.9463 -65.511426) (xy 179.956573 -65.515566) (xy 179.978699 -65.515566)
			(xy 179.988972 -65.511426) (xy 180.023978 -65.49577) (xy 180.096146 -65.469818) (xy 180.170278 -65.45017)
			(xy 180.245826 -65.436971) (xy 180.322228 -65.430321) (xy 180.360574 -65.429892) (xy 180.361336 -65.429892)
			(xy 180.403683 -65.430397) (xy 180.487994 -65.438451) (xy 180.571158 -65.454483) (xy 180.652421 -65.478347)
			(xy 180.731048 -65.509827) (xy 180.806327 -65.548639) (xy 180.877576 -65.59443) (xy 180.944149 -65.646786)
			(xy 181.005444 -65.705234) (xy 181.060907 -65.769243) (xy 181.110033 -65.838234) (xy 181.15238 -65.911582)
			(xy 181.187562 -65.988624) (xy 181.215263 -66.068661) (xy 181.23523 -66.150968) (xy 181.247283 -66.234801)
			(xy 181.251313 -66.3194) (xy 181.247283 -66.403999) (xy 181.23523 -66.487832) (xy 181.215263 -66.570139)
			(xy 181.187562 -66.650176) (xy 181.15238 -66.727218) (xy 181.110033 -66.800566) (xy 181.060907 -66.869557)
			(xy 181.005444 -66.933566) (xy 180.944149 -66.992014) (xy 180.877576 -67.04437) (xy 180.806327 -67.090161)
			(xy 180.731048 -67.128973) (xy 180.652421 -67.160453) (xy 180.571158 -67.184317) (xy 180.487994 -67.200349)
			(xy 180.403683 -67.208403) (xy 180.361336 -67.208908) (xy 180.360574 -67.208908) (xy 180.322227 -67.208485)
			(xy 180.24582 -67.201857) (xy 180.170269 -67.188668) (xy 180.096135 -67.169018) (xy 180.02397 -67.143051)
			(xy 179.988972 -67.127374) (xy 179.978699 -67.123234) (xy 179.956573 -67.123234) (xy 179.9463 -67.127374)
			(xy 179.911298 -67.14304) (xy 179.839129 -67.16899) (xy 179.764996 -67.188636) (xy 179.689447 -67.201832)
			(xy 179.613044 -67.20848) (xy 179.574698 -67.208908) (xy 179.573936 -67.208908) (xy 179.531586 -67.208422)
			(xy 179.447268 -67.200373) (xy 179.364098 -67.184347) (xy 179.282827 -67.160486) (xy 179.204193 -67.129009)
			(xy 179.128907 -67.090199) (xy 179.057651 -67.044408) (xy 178.99107 -66.992051) (xy 178.929768 -66.933602)
			(xy 178.8743 -66.869591) (xy 178.825168 -66.800596) (xy 178.782817 -66.727244) (xy 178.74763 -66.650198)
			(xy 178.719926 -66.570156) (xy 178.699957 -66.487843) (xy 178.687902 -66.404005) (xy 178.683872 -66.3194)
			(xy 150.38197 -66.3194) (xy 149.027388 -67.673982) (xy 149.003493 -67.697123) (xy 148.950735 -67.737636)
			(xy 148.893138 -67.770913) (xy 148.831689 -67.796384) (xy 148.76744 -67.813612) (xy 148.701491 -67.822303)
			(xy 148.668232 -67.822826) (xy 147.268438 -67.822826) (xy 147.258918 -67.823235) (xy 147.241193 -67.830193)
			(xy 147.22722 -67.84313) (xy 147.222718 -67.851528) (xy 147.20415 -67.888594) (xy 147.161092 -67.959444)
			(xy 147.111631 -68.025982) (xy 147.056195 -68.08763) (xy 146.995265 -68.143854) (xy 146.929368 -68.194166)
			(xy 146.859078 -68.238131) (xy 146.785002 -68.275367) (xy 146.707784 -68.30555) (xy 146.628093 -68.32842)
			(xy 146.54662 -68.343777) (xy 146.464072 -68.351489) (xy 146.381164 -68.351489) (xy 146.298616 -68.343777)
			(xy 146.217143 -68.32842) (xy 146.137452 -68.30555) (xy 146.060234 -68.275367) (xy 145.986158 -68.238131)
			(xy 145.915868 -68.194166) (xy 145.849971 -68.143854) (xy 145.789041 -68.08763) (xy 145.733605 -68.025982)
			(xy 145.684144 -67.959444) (xy 145.641086 -67.888594) (xy 145.622518 -67.851528) (xy 145.618028 -67.84312)
			(xy 145.604056 -67.830173) (xy 145.586322 -67.82322) (xy 145.576798 -67.822826) (xy 143.862806 -67.822826)
			(xy 143.834866 -67.845686) (xy 143.83131 -67.86372) (xy 143.822279 -67.9067) (xy 143.796815 -67.99076)
			(xy 143.763184 -68.071898) (xy 143.742918 -68.110862) (xy 143.737504 -68.12233) (xy 143.737501 -68.147656)
			(xy 143.742918 -68.159122) (xy 143.763197 -68.198006) (xy 143.796886 -68.27898) (xy 143.822451 -68.362874)
			(xy 143.839643 -68.448874) (xy 143.848295 -68.536149) (xy 143.848836 -68.58) (xy 143.848317 -68.623763)
			(xy 143.839718 -68.710864) (xy 143.822612 -68.796702) (xy 143.797165 -68.880446) (xy 143.763623 -68.961289)
			(xy 143.743426 -69.000116) (xy 143.738194 -69.011509) (xy 143.738307 -69.036544) (xy 143.74368 -69.047868)
			(xy 143.763943 -69.086781) (xy 143.797578 -69.167817) (xy 143.804198 -69.1896) (xy 177.667872 -69.1896)
			(xy 177.671902 -69.104995) (xy 177.683957 -69.021157) (xy 177.703926 -68.938844) (xy 177.73163 -68.858802)
			(xy 177.766817 -68.781756) (xy 177.809168 -68.708404) (xy 177.8583 -68.639409) (xy 177.913768 -68.575398)
			(xy 177.97507 -68.516949) (xy 178.041651 -68.464592) (xy 178.112907 -68.418801) (xy 178.188193 -68.379991)
			(xy 178.266827 -68.348514) (xy 178.348098 -68.324653) (xy 178.431268 -68.308627) (xy 178.515586 -68.300578)
			(xy 178.557936 -68.300092) (xy 178.558444 -68.300092) (xy 178.597192 -68.300509) (xy 178.674394 -68.307273)
			(xy 178.750714 -68.320729) (xy 178.825573 -68.340774) (xy 178.898405 -68.367256) (xy 178.968657 -68.399975)
			(xy 179.002436 -68.418964) (xy 179.01031 -68.423123) (xy 179.027836 -68.426217) (xy 179.045362 -68.423123)
			(xy 179.053236 -68.418964) (xy 179.087017 -68.399978) (xy 179.157269 -68.367265) (xy 179.230101 -68.340786)
			(xy 179.304961 -68.320743) (xy 179.38128 -68.307289) (xy 179.45848 -68.300524) (xy 179.497228 -68.300092)
			(xy 179.497736 -68.300092) (xy 179.540083 -68.300597) (xy 179.624394 -68.308651) (xy 179.707558 -68.324683)
			(xy 179.788821 -68.348547) (xy 179.867448 -68.380027) (xy 179.942727 -68.418839) (xy 180.013976 -68.46463)
			(xy 180.080549 -68.516986) (xy 180.141844 -68.575434) (xy 180.197307 -68.639443) (xy 180.246433 -68.708434)
			(xy 180.28878 -68.781782) (xy 180.323962 -68.858824) (xy 180.351663 -68.938861) (xy 180.37163 -69.021168)
			(xy 180.383683 -69.105001) (xy 180.387713 -69.1896) (xy 180.383683 -69.274199) (xy 180.37163 -69.358032)
			(xy 180.351663 -69.440339) (xy 180.350534 -69.4436) (xy 181.326028 -69.4436) (xy 181.326532 -69.401252)
			(xy 181.334583 -69.316938) (xy 181.350612 -69.233772) (xy 181.374473 -69.152505) (xy 181.405952 -69.073875)
			(xy 181.444763 -68.998594) (xy 181.490553 -68.927342) (xy 181.542909 -68.860766) (xy 181.601357 -68.799468)
			(xy 181.665367 -68.744003) (xy 181.734359 -68.694874) (xy 181.807709 -68.652525) (xy 181.884752 -68.617341)
			(xy 181.964791 -68.589639) (xy 182.0471 -68.569671) (xy 182.130935 -68.557618) (xy 182.215536 -68.553588)
			(xy 182.300137 -68.557618) (xy 182.383972 -68.569671) (xy 182.426549 -68.58) (xy 183.920388 -68.58)
			(xy 183.924418 -68.495399) (xy 183.936471 -68.411564) (xy 183.956439 -68.329255) (xy 183.984141 -68.249216)
			(xy 184.019325 -68.172173) (xy 184.061674 -68.098823) (xy 184.110803 -68.029831) (xy 184.166268 -67.965821)
			(xy 184.227566 -67.907373) (xy 184.294142 -67.855017) (xy 184.365394 -67.809227) (xy 184.440675 -67.770416)
			(xy 184.519305 -67.738937) (xy 184.600572 -67.715076) (xy 184.683738 -67.699047) (xy 184.768052 -67.690996)
			(xy 184.8104 -67.690492) (xy 184.810908 -67.690492) (xy 184.85724 -67.691098) (xy 184.949398 -67.700769)
			(xy 185.040052 -67.719965) (xy 185.128221 -67.748477) (xy 185.170826 -67.766692) (xy 185.180768 -67.770498)
			(xy 185.202032 -67.770498) (xy 185.211974 -67.766692) (xy 185.254577 -67.74847) (xy 185.342744 -67.719952)
			(xy 185.4334 -67.70076) (xy 185.52556 -67.6911) (xy 185.571892 -67.690492) (xy 185.5724 -67.690492)
			(xy 185.614748 -67.690996) (xy 185.699062 -67.699047) (xy 185.782228 -67.715076) (xy 185.863495 -67.738937)
			(xy 185.942125 -67.770416) (xy 186.017406 -67.809227) (xy 186.088658 -67.855017) (xy 186.155234 -67.907373)
			(xy 186.216532 -67.965821) (xy 186.271997 -68.029831) (xy 186.321126 -68.098823) (xy 186.363475 -68.172173)
			(xy 186.375726 -68.199) (xy 267.232388 -68.199) (xy 267.236418 -68.114399) (xy 267.248471 -68.030564)
			(xy 267.268439 -67.948255) (xy 267.296141 -67.868216) (xy 267.331325 -67.791173) (xy 267.373674 -67.717823)
			(xy 267.422803 -67.648831) (xy 267.478268 -67.584821) (xy 267.539566 -67.526373) (xy 267.606142 -67.474017)
			(xy 267.677394 -67.428227) (xy 267.752675 -67.389416) (xy 267.831305 -67.357937) (xy 267.912572 -67.334076)
			(xy 267.995738 -67.318047) (xy 268.080052 -67.309996) (xy 268.1224 -67.309492) (xy 268.122908 -67.309492)
			(xy 268.161656 -67.309926) (xy 268.238857 -67.316687) (xy 268.315177 -67.330139) (xy 268.390036 -67.350181)
			(xy 268.462869 -67.37666) (xy 268.53312 -67.409376) (xy 268.5669 -67.428364) (xy 268.574774 -67.432523)
			(xy 268.5923 -67.435617) (xy 268.609826 -67.432523) (xy 268.6177 -67.428364) (xy 268.651489 -67.409393)
			(xy 268.721739 -67.376677) (xy 268.79457 -67.350196) (xy 268.869428 -67.330151) (xy 268.945745 -67.316693)
			(xy 269.022945 -67.309925) (xy 269.061692 -67.309492) (xy 269.0622 -67.309492) (xy 269.104548 -67.309996)
			(xy 269.188862 -67.318047) (xy 269.272028 -67.334076) (xy 269.353295 -67.357937) (xy 269.431925 -67.389416)
			(xy 269.507206 -67.428227) (xy 269.578458 -67.474017) (xy 269.645034 -67.526373) (xy 269.706332 -67.584821)
			(xy 269.761797 -67.648831) (xy 269.810926 -67.717823) (xy 269.853275 -67.791173) (xy 269.888459 -67.868216)
			(xy 269.916161 -67.948255) (xy 269.936129 -68.030564) (xy 269.948182 -68.114399) (xy 269.952213 -68.199)
			(xy 269.948182 -68.283601) (xy 269.936129 -68.367436) (xy 269.916161 -68.449745) (xy 269.888459 -68.529784)
			(xy 269.853275 -68.606827) (xy 269.810926 -68.680177) (xy 269.761797 -68.749169) (xy 269.706332 -68.813179)
			(xy 269.645034 -68.871627) (xy 269.578458 -68.923983) (xy 269.507206 -68.969773) (xy 269.431925 -69.008584)
			(xy 269.353295 -69.040063) (xy 269.272028 -69.063924) (xy 269.188862 -69.079953) (xy 269.104548 -69.088004)
			(xy 269.0622 -69.088508) (xy 269.061692 -69.088508) (xy 269.022944 -69.088074) (xy 268.945743 -69.081313)
			(xy 268.869423 -69.067861) (xy 268.794564 -69.047819) (xy 268.721731 -69.02134) (xy 268.65148 -68.988624)
			(xy 268.6177 -68.969636) (xy 268.609826 -68.965477) (xy 268.5923 -68.962383) (xy 268.574774 -68.965477)
			(xy 268.5669 -68.969636) (xy 268.533111 -68.988607) (xy 268.462861 -69.021323) (xy 268.39003 -69.047804)
			(xy 268.315172 -69.067849) (xy 268.238855 -69.081307) (xy 268.161655 -69.088075) (xy 268.122908 -69.088508)
			(xy 268.1224 -69.088508) (xy 268.080052 -69.088004) (xy 267.995738 -69.079953) (xy 267.912572 -69.063924)
			(xy 267.831305 -69.040063) (xy 267.752675 -69.008584) (xy 267.677394 -68.969773) (xy 267.606142 -68.923983)
			(xy 267.539566 -68.871627) (xy 267.478268 -68.813179) (xy 267.422803 -68.749169) (xy 267.373674 -68.680177)
			(xy 267.331325 -68.606827) (xy 267.296141 -68.529784) (xy 267.268439 -68.449745) (xy 267.248471 -68.367436)
			(xy 267.236418 -68.283601) (xy 267.232388 -68.199) (xy 186.375726 -68.199) (xy 186.398659 -68.249216)
			(xy 186.426361 -68.329255) (xy 186.446329 -68.411564) (xy 186.458382 -68.495399) (xy 186.462413 -68.58)
			(xy 186.458382 -68.664601) (xy 186.446329 -68.748436) (xy 186.426361 -68.830745) (xy 186.398659 -68.910784)
			(xy 186.363475 -68.987827) (xy 186.321126 -69.061177) (xy 186.271997 -69.130169) (xy 186.216532 -69.194179)
			(xy 186.155234 -69.252627) (xy 186.088658 -69.304983) (xy 186.023153 -69.34708) (xy 263.981692 -69.34708)
			(xy 263.982196 -69.304732) (xy 263.990247 -69.220418) (xy 264.006276 -69.137252) (xy 264.030137 -69.055985)
			(xy 264.061616 -68.977355) (xy 264.100427 -68.902074) (xy 264.146217 -68.830822) (xy 264.198573 -68.764246)
			(xy 264.257021 -68.702948) (xy 264.321031 -68.647483) (xy 264.390023 -68.598354) (xy 264.463373 -68.556005)
			(xy 264.540416 -68.520821) (xy 264.620455 -68.493119) (xy 264.702764 -68.473151) (xy 264.786599 -68.461098)
			(xy 264.8712 -68.457068) (xy 264.955801 -68.461098) (xy 265.039636 -68.473151) (xy 265.121945 -68.493119)
			(xy 265.201984 -68.520821) (xy 265.279027 -68.556005) (xy 265.352377 -68.598354) (xy 265.421369 -68.647483)
			(xy 265.485379 -68.702948) (xy 265.543827 -68.764246) (xy 265.596183 -68.830822) (xy 265.641973 -68.902074)
			(xy 265.680784 -68.977355) (xy 265.712263 -69.055985) (xy 265.736124 -69.137252) (xy 265.752153 -69.220418)
			(xy 265.760204 -69.304732) (xy 265.760708 -69.34708) (xy 265.760708 -69.347842) (xy 265.760124 -69.39309)
			(xy 265.750905 -69.483115) (xy 265.732585 -69.571738) (xy 265.705356 -69.658041) (xy 265.669499 -69.74113)
			(xy 265.647932 -69.780912) (xy 265.643026 -69.790878) (xy 265.641461 -69.813015) (xy 265.644884 -69.823584)
			(xy 265.676126 -69.906896) (xy 265.691874 -69.92239) (xy 265.702542 -69.9262) (xy 265.741999 -69.940786)
			(xy 265.818247 -69.976332) (xy 265.8908 -70.018917) (xy 265.959008 -70.068161) (xy 266.022264 -70.123623)
			(xy 266.080001 -70.184809) (xy 266.131705 -70.251172) (xy 266.176914 -70.322119) (xy 266.215223 -70.397017)
			(xy 266.246292 -70.475197) (xy 266.269842 -70.55596) (xy 266.285663 -70.638586) (xy 266.293613 -70.722337)
			(xy 266.294108 -70.7644) (xy 266.293604 -70.806748) (xy 266.285553 -70.891062) (xy 266.269524 -70.974228)
			(xy 266.256555 -71.0184) (xy 267.232388 -71.0184) (xy 267.236418 -70.933799) (xy 267.248471 -70.849964)
			(xy 267.268439 -70.767655) (xy 267.296141 -70.687616) (xy 267.331325 -70.610573) (xy 267.373674 -70.537223)
			(xy 267.422803 -70.468231) (xy 267.478268 -70.404221) (xy 267.539566 -70.345773) (xy 267.606142 -70.293417)
			(xy 267.677394 -70.247627) (xy 267.752675 -70.208816) (xy 267.831305 -70.177337) (xy 267.912572 -70.153476)
			(xy 267.995738 -70.137447) (xy 268.080052 -70.129396) (xy 268.1224 -70.128892) (xy 268.122908 -70.128892)
			(xy 268.161656 -70.129326) (xy 268.238857 -70.136087) (xy 268.315177 -70.149539) (xy 268.390036 -70.169581)
			(xy 268.462869 -70.19606) (xy 268.53312 -70.228776) (xy 268.5669 -70.247764) (xy 268.574774 -70.251923)
			(xy 268.5923 -70.255017) (xy 268.609826 -70.251923) (xy 268.6177 -70.247764) (xy 268.651489 -70.228793)
			(xy 268.721739 -70.196077) (xy 268.79457 -70.169596) (xy 268.869428 -70.149551) (xy 268.945745 -70.136093)
			(xy 269.022945 -70.129325) (xy 269.061692 -70.128892) (xy 269.0622 -70.128892) (xy 269.104548 -70.129396)
			(xy 269.188862 -70.137447) (xy 269.272028 -70.153476) (xy 269.353295 -70.177337) (xy 269.431925 -70.208816)
			(xy 269.507206 -70.247627) (xy 269.578458 -70.293417) (xy 269.645034 -70.345773) (xy 269.706332 -70.404221)
			(xy 269.761797 -70.468231) (xy 269.810926 -70.537223) (xy 269.853275 -70.610573) (xy 269.888459 -70.687616)
			(xy 269.916161 -70.767655) (xy 269.936129 -70.849964) (xy 269.948182 -70.933799) (xy 269.952213 -71.0184)
			(xy 269.948182 -71.103001) (xy 269.936129 -71.186836) (xy 269.916161 -71.269145) (xy 269.888459 -71.349184)
			(xy 269.853275 -71.426227) (xy 269.810926 -71.499577) (xy 269.761797 -71.568569) (xy 269.706332 -71.632579)
			(xy 269.645034 -71.691027) (xy 269.578458 -71.743383) (xy 269.507206 -71.789173) (xy 269.431925 -71.827984)
			(xy 269.353295 -71.859463) (xy 269.272028 -71.883324) (xy 269.188862 -71.899353) (xy 269.104548 -71.907404)
			(xy 269.0622 -71.907908) (xy 269.061692 -71.907908) (xy 269.022944 -71.907474) (xy 268.945743 -71.900713)
			(xy 268.869423 -71.887261) (xy 268.794564 -71.867219) (xy 268.721731 -71.84074) (xy 268.65148 -71.808024)
			(xy 268.6177 -71.789036) (xy 268.609826 -71.784877) (xy 268.5923 -71.781783) (xy 268.574774 -71.784877)
			(xy 268.5669 -71.789036) (xy 268.533111 -71.808007) (xy 268.462861 -71.840723) (xy 268.39003 -71.867204)
			(xy 268.315172 -71.887249) (xy 268.238855 -71.900707) (xy 268.161655 -71.907475) (xy 268.122908 -71.907908)
			(xy 268.1224 -71.907908) (xy 268.080052 -71.907404) (xy 267.995738 -71.899353) (xy 267.912572 -71.883324)
			(xy 267.831305 -71.859463) (xy 267.752675 -71.827984) (xy 267.677394 -71.789173) (xy 267.606142 -71.743383)
			(xy 267.539566 -71.691027) (xy 267.478268 -71.632579) (xy 267.422803 -71.568569) (xy 267.373674 -71.499577)
			(xy 267.331325 -71.426227) (xy 267.296141 -71.349184) (xy 267.268439 -71.269145) (xy 267.248471 -71.186836)
			(xy 267.236418 -71.103001) (xy 267.232388 -71.0184) (xy 266.256555 -71.0184) (xy 266.245663 -71.055495)
			(xy 266.214184 -71.134125) (xy 266.175373 -71.209406) (xy 266.129583 -71.280658) (xy 266.077227 -71.347234)
			(xy 266.018779 -71.408532) (xy 265.954769 -71.463997) (xy 265.885777 -71.513126) (xy 265.812427 -71.555475)
			(xy 265.735384 -71.590659) (xy 265.655345 -71.618361) (xy 265.573036 -71.638329) (xy 265.489201 -71.650382)
			(xy 265.4046 -71.654413) (xy 265.319999 -71.650382) (xy 265.236164 -71.638329) (xy 265.153855 -71.618361)
			(xy 265.073816 -71.590659) (xy 264.996773 -71.555475) (xy 264.923423 -71.513126) (xy 264.854431 -71.463997)
			(xy 264.790421 -71.408532) (xy 264.731973 -71.347234) (xy 264.679617 -71.280658) (xy 264.633827 -71.209406)
			(xy 264.595016 -71.134125) (xy 264.563537 -71.055495) (xy 264.539676 -70.974228) (xy 264.523647 -70.891062)
			(xy 264.515596 -70.806748) (xy 264.515092 -70.7644) (xy 264.515092 -70.763638) (xy 264.515667 -70.71839)
			(xy 264.524889 -70.628364) (xy 264.54321 -70.539741) (xy 264.570441 -70.453439) (xy 264.6063 -70.37035)
			(xy 264.627868 -70.330568) (xy 264.632726 -70.320583) (xy 264.634321 -70.298463) (xy 264.630916 -70.287896)
			(xy 264.599674 -70.204584) (xy 264.583926 -70.18909) (xy 264.573258 -70.18528) (xy 264.533794 -70.170712)
			(xy 264.457545 -70.135164) (xy 264.384993 -70.092578) (xy 264.316784 -70.043333) (xy 264.253528 -69.987869)
			(xy 264.195791 -69.926681) (xy 264.144087 -69.860317) (xy 264.098879 -69.789368) (xy 264.06057 -69.714469)
			(xy 264.029503 -69.636288) (xy 264.005954 -69.555523) (xy 263.990135 -69.472895) (xy 263.982186 -69.389144)
			(xy 263.981692 -69.34708) (xy 186.023153 -69.34708) (xy 186.017406 -69.350773) (xy 185.942125 -69.389584)
			(xy 185.863495 -69.421063) (xy 185.782228 -69.444924) (xy 185.699062 -69.460953) (xy 185.614748 -69.469004)
			(xy 185.5724 -69.469508) (xy 185.571892 -69.469508) (xy 185.52556 -69.468902) (xy 185.433402 -69.459231)
			(xy 185.342748 -69.440035) (xy 185.254579 -69.411523) (xy 185.211974 -69.393308) (xy 185.202032 -69.389502)
			(xy 185.180768 -69.389502) (xy 185.170826 -69.393308) (xy 185.128223 -69.41153) (xy 185.040056 -69.440048)
			(xy 184.9494 -69.45924) (xy 184.85724 -69.4689) (xy 184.810908 -69.469508) (xy 184.8104 -69.469508)
			(xy 184.768052 -69.469004) (xy 184.683738 -69.460953) (xy 184.600572 -69.444924) (xy 184.519305 -69.421063)
			(xy 184.440675 -69.389584) (xy 184.365394 -69.350773) (xy 184.294142 -69.304983) (xy 184.227566 -69.252627)
			(xy 184.166268 -69.194179) (xy 184.110803 -69.130169) (xy 184.061674 -69.061177) (xy 184.019325 -68.987827)
			(xy 183.984141 -68.910784) (xy 183.956439 -68.830745) (xy 183.936471 -68.748436) (xy 183.924418 -68.664601)
			(xy 183.920388 -68.58) (xy 182.426549 -68.58) (xy 182.466281 -68.589639) (xy 182.54632 -68.617341)
			(xy 182.623363 -68.652525) (xy 182.696713 -68.694874) (xy 182.765705 -68.744003) (xy 182.829715 -68.799468)
			(xy 182.888163 -68.860766) (xy 182.940519 -68.927342) (xy 182.986309 -68.998594) (xy 183.02512 -69.073875)
			(xy 183.056599 -69.152505) (xy 183.08046 -69.233772) (xy 183.096489 -69.316938) (xy 183.10454 -69.401252)
			(xy 183.105044 -69.4436) (xy 183.105044 -69.444362) (xy 183.104477 -69.489611) (xy 183.095255 -69.579637)
			(xy 183.076932 -69.66826) (xy 183.049699 -69.754562) (xy 183.013837 -69.837651) (xy 182.992268 -69.877432)
			(xy 182.98741 -69.887417) (xy 182.985813 -69.909537) (xy 182.98922 -69.920104) (xy 183.020462 -70.003416)
			(xy 183.03621 -70.01891) (xy 183.046878 -70.02272) (xy 183.08635 -70.037268) (xy 183.162598 -70.072818)
			(xy 183.23515 -70.115407) (xy 183.303358 -70.164655) (xy 183.366613 -70.220121) (xy 183.424349 -70.28131)
			(xy 183.476052 -70.347676) (xy 183.521259 -70.418626) (xy 183.559567 -70.493527) (xy 183.590634 -70.571709)
			(xy 183.614182 -70.652475) (xy 183.630002 -70.735103) (xy 183.63795 -70.818856) (xy 183.638444 -70.86092)
			(xy 183.63794 -70.903268) (xy 183.629889 -70.987582) (xy 183.61386 -71.070748) (xy 183.589999 -71.152015)
			(xy 183.55852 -71.230645) (xy 183.519709 -71.305926) (xy 183.473919 -71.377178) (xy 183.421563 -71.443754)
			(xy 183.363115 -71.505052) (xy 183.299105 -71.560517) (xy 183.275677 -71.5772) (xy 260.602988 -71.5772)
			(xy 260.607018 -71.492599) (xy 260.619071 -71.408764) (xy 260.639039 -71.326455) (xy 260.666741 -71.246416)
			(xy 260.701925 -71.169373) (xy 260.744274 -71.096023) (xy 260.793403 -71.027031) (xy 260.848868 -70.963021)
			(xy 260.910166 -70.904573) (xy 260.976742 -70.852217) (xy 261.047994 -70.806427) (xy 261.123275 -70.767616)
			(xy 261.201905 -70.736137) (xy 261.283172 -70.712276) (xy 261.366338 -70.696247) (xy 261.450652 -70.688196)
			(xy 261.493 -70.687692) (xy 261.493508 -70.687692) (xy 261.53984 -70.688298) (xy 261.631998 -70.697969)
			(xy 261.722652 -70.717165) (xy 261.810821 -70.745677) (xy 261.853426 -70.763892) (xy 261.863368 -70.767698)
			(xy 261.884632 -70.767698) (xy 261.894574 -70.763892) (xy 261.937177 -70.74567) (xy 262.025344 -70.717152)
			(xy 262.116 -70.69796) (xy 262.20816 -70.6883) (xy 262.254492 -70.687692) (xy 262.255 -70.687692)
			(xy 262.297348 -70.688196) (xy 262.381662 -70.696247) (xy 262.464828 -70.712276) (xy 262.546095 -70.736137)
			(xy 262.624725 -70.767616) (xy 262.700006 -70.806427) (xy 262.771258 -70.852217) (xy 262.837834 -70.904573)
			(xy 262.899132 -70.963021) (xy 262.954597 -71.027031) (xy 263.003726 -71.096023) (xy 263.046075 -71.169373)
			(xy 263.081259 -71.246416) (xy 263.108961 -71.326455) (xy 263.128929 -71.408764) (xy 263.140982 -71.492599)
			(xy 263.145013 -71.5772) (xy 263.140982 -71.661801) (xy 263.128929 -71.745636) (xy 263.108961 -71.827945)
			(xy 263.081259 -71.907984) (xy 263.046075 -71.985027) (xy 263.003726 -72.058377) (xy 262.954597 -72.127369)
			(xy 262.899132 -72.191379) (xy 262.837834 -72.249827) (xy 262.771258 -72.302183) (xy 262.700006 -72.347973)
			(xy 262.624725 -72.386784) (xy 262.546095 -72.418263) (xy 262.464828 -72.442124) (xy 262.381662 -72.458153)
			(xy 262.297348 -72.466204) (xy 262.255 -72.466708) (xy 262.254492 -72.466708) (xy 262.20816 -72.466102)
			(xy 262.116002 -72.456431) (xy 262.025348 -72.437235) (xy 261.937179 -72.408723) (xy 261.894574 -72.390508)
			(xy 261.884632 -72.386702) (xy 261.863368 -72.386702) (xy 261.853426 -72.390508) (xy 261.810823 -72.40873)
			(xy 261.722656 -72.437248) (xy 261.632 -72.45644) (xy 261.53984 -72.4661) (xy 261.493508 -72.466708)
			(xy 261.493 -72.466708) (xy 261.450652 -72.466204) (xy 261.366338 -72.458153) (xy 261.283172 -72.442124)
			(xy 261.201905 -72.418263) (xy 261.123275 -72.386784) (xy 261.047994 -72.347973) (xy 260.976742 -72.302183)
			(xy 260.910166 -72.249827) (xy 260.848868 -72.191379) (xy 260.793403 -72.127369) (xy 260.744274 -72.058377)
			(xy 260.701925 -71.985027) (xy 260.666741 -71.907984) (xy 260.639039 -71.827945) (xy 260.619071 -71.745636)
			(xy 260.607018 -71.661801) (xy 260.602988 -71.5772) (xy 183.275677 -71.5772) (xy 183.230113 -71.609646)
			(xy 183.156763 -71.651995) (xy 183.07972 -71.687179) (xy 182.999681 -71.714881) (xy 182.917372 -71.734849)
			(xy 182.833537 -71.746902) (xy 182.748936 -71.750933) (xy 182.664335 -71.746902) (xy 182.5805 -71.734849)
			(xy 182.498191 -71.714881) (xy 182.418152 -71.687179) (xy 182.341109 -71.651995) (xy 182.267759 -71.609646)
			(xy 182.198767 -71.560517) (xy 182.134757 -71.505052) (xy 182.076309 -71.443754) (xy 182.023953 -71.377178)
			(xy 181.978163 -71.305926) (xy 181.939352 -71.230645) (xy 181.907873 -71.152015) (xy 181.884012 -71.070748)
			(xy 181.867983 -70.987582) (xy 181.859932 -70.903268) (xy 181.859428 -70.86092) (xy 181.859428 -70.860158)
			(xy 181.860007 -70.81491) (xy 181.869227 -70.724884) (xy 181.887547 -70.636261) (xy 181.914778 -70.549959)
			(xy 181.950636 -70.466869) (xy 181.972204 -70.427088) (xy 181.977111 -70.417122) (xy 181.978678 -70.394985)
			(xy 181.975252 -70.384416) (xy 181.94401 -70.301104) (xy 181.928262 -70.28561) (xy 181.917594 -70.2818)
			(xy 181.878145 -70.267193) (xy 181.801896 -70.23165) (xy 181.729343 -70.189068) (xy 181.661134 -70.139826)
			(xy 181.597877 -70.084366) (xy 181.540139 -70.023182) (xy 181.488434 -69.956821) (xy 181.443225 -69.885875)
			(xy 181.404914 -69.810979) (xy 181.373845 -69.7328) (xy 181.350295 -69.652037) (xy 181.334473 -69.569413)
			(xy 181.326523 -69.485663) (xy 181.326028 -69.4436) (xy 180.350534 -69.4436) (xy 180.323962 -69.520376)
			(xy 180.28878 -69.597418) (xy 180.246433 -69.670766) (xy 180.197307 -69.739757) (xy 180.141844 -69.803766)
			(xy 180.080549 -69.862214) (xy 180.013976 -69.91457) (xy 179.942727 -69.960361) (xy 179.867448 -69.999173)
			(xy 179.788821 -70.030653) (xy 179.707558 -70.054517) (xy 179.624394 -70.070549) (xy 179.540083 -70.078603)
			(xy 179.497736 -70.079108) (xy 179.497228 -70.079108) (xy 179.45848 -70.078658) (xy 179.38128 -70.0719)
			(xy 179.304961 -70.058451) (xy 179.230101 -70.038412) (xy 179.157268 -70.011936) (xy 179.087016 -69.979222)
			(xy 179.053236 -69.960236) (xy 179.045362 -69.956077) (xy 179.027836 -69.952983) (xy 179.01031 -69.956077)
			(xy 179.002436 -69.960236) (xy 178.968662 -69.979233) (xy 178.898407 -70.011945) (xy 178.825574 -70.038422)
			(xy 178.750713 -70.058462) (xy 178.674393 -70.071915) (xy 178.597192 -70.078678) (xy 178.558444 -70.079108)
			(xy 178.557936 -70.079108) (xy 178.515586 -70.078622) (xy 178.431268 -70.070573) (xy 178.348098 -70.054547)
			(xy 178.266827 -70.030686) (xy 178.188193 -69.999209) (xy 178.112907 -69.960399) (xy 178.041651 -69.914608)
			(xy 177.97507 -69.862251) (xy 177.913768 -69.803802) (xy 177.8583 -69.739791) (xy 177.809168 -69.670796)
			(xy 177.766817 -69.597444) (xy 177.73163 -69.520398) (xy 177.703926 -69.440356) (xy 177.683957 -69.358043)
			(xy 177.671902 -69.274205) (xy 177.667872 -69.1896) (xy 143.804198 -69.1896) (xy 143.823089 -69.251765)
			(xy 143.840228 -69.337814) (xy 143.848829 -69.42513) (xy 143.849344 -69.469) (xy 143.848824 -69.512819)
			(xy 143.840185 -69.60003) (xy 143.82303 -69.685972) (xy 143.797525 -69.769817) (xy 143.763915 -69.850753)
			(xy 143.74368 -69.889624) (xy 143.738368 -69.90098) (xy 143.738368 -69.92602) (xy 143.74368 -69.937376)
			(xy 143.763922 -69.976244) (xy 143.797557 -70.057173) (xy 143.82307 -70.141017) (xy 143.840214 -70.226964)
			(xy 143.848823 -70.31418) (xy 143.849344 -70.358) (xy 143.84884 -70.400397) (xy 143.84078 -70.484807)
			(xy 143.824732 -70.568068) (xy 143.800843 -70.649427) (xy 143.769328 -70.728147) (xy 143.730474 -70.803515)
			(xy 143.684631 -70.874848) (xy 143.632215 -70.9415) (xy 143.5737 -71.002868) (xy 143.509618 -71.058396)
			(xy 143.440547 -71.107581) (xy 143.367113 -71.149978) (xy 143.289982 -71.185203) (xy 143.209852 -71.212936)
			(xy 143.127448 -71.232927) (xy 143.043518 -71.244994) (xy 142.95882 -71.249029) (xy 142.874122 -71.244994)
			(xy 142.790192 -71.232927) (xy 142.707788 -71.212936) (xy 142.627658 -71.185203) (xy 142.550527 -71.149978)
			(xy 142.477093 -71.107581) (xy 142.408022 -71.058396) (xy 142.34394 -71.002868) (xy 142.285425 -70.9415)
			(xy 142.233009 -70.874848) (xy 142.187166 -70.803515) (xy 142.148312 -70.728147) (xy 142.116797 -70.649427)
			(xy 142.092908 -70.568068) (xy 142.07686 -70.484807) (xy 142.0688 -70.400397) (xy 142.068296 -70.358)
			(xy 142.068812 -70.314181) (xy 142.077451 -70.22697) (xy 142.094607 -70.141027) (xy 142.120113 -70.057183)
			(xy 142.153725 -69.976247) (xy 142.17396 -69.937376) (xy 142.179269 -69.92602) (xy 142.179269 -69.90098)
			(xy 142.17396 -69.889624) (xy 142.153713 -69.850758) (xy 142.12008 -69.769829) (xy 142.094568 -69.685984)
			(xy 142.077425 -69.600037) (xy 142.068817 -69.51282) (xy 142.068296 -69.469) (xy 142.068784 -69.425129)
			(xy 142.077376 -69.337809) (xy 142.094516 -69.251758) (xy 142.120037 -69.16781) (xy 142.153693 -69.08678)
			(xy 142.17396 -69.047868) (xy 142.179366 -69.036553) (xy 142.179479 -69.0115) (xy 142.174214 -69.000116)
			(xy 142.154023 -68.961286) (xy 142.120474 -68.880446) (xy 142.095025 -68.796702) (xy 142.07792 -68.710865)
			(xy 142.069327 -68.623763) (xy 142.068804 -68.58) (xy 142.069352 -68.536149) (xy 142.077992 -68.448872)
			(xy 142.095177 -68.362869) (xy 142.120741 -68.278975) (xy 142.154437 -68.198003) (xy 142.174722 -68.159122)
			(xy 142.180144 -68.147657) (xy 142.18014 -68.122329) (xy 142.174722 -68.110862) (xy 142.154472 -68.071891)
			(xy 142.120849 -67.990752) (xy 142.095381 -67.906695) (xy 142.08633 -67.86372) (xy 142.082774 -67.845686)
			(xy 142.054834 -67.822826) (xy 140.90904 -67.822826) (xy 140.89952 -67.823236) (xy 140.881795 -67.830194)
			(xy 140.867822 -67.84313) (xy 140.86332 -67.851528) (xy 140.844752 -67.888594) (xy 140.801694 -67.959444)
			(xy 140.752233 -68.025982) (xy 140.696797 -68.08763) (xy 140.635867 -68.143854) (xy 140.56997 -68.194166)
			(xy 140.49968 -68.238131) (xy 140.425604 -68.275367) (xy 140.348386 -68.30555) (xy 140.268695 -68.32842)
			(xy 140.187222 -68.343777) (xy 140.104674 -68.351489) (xy 140.021766 -68.351489) (xy 139.939218 -68.343777)
			(xy 139.857745 -68.32842) (xy 139.778054 -68.30555) (xy 139.700836 -68.275367) (xy 139.62676 -68.238131)
			(xy 139.55647 -68.194166) (xy 139.490573 -68.143854) (xy 139.429643 -68.08763) (xy 139.374207 -68.025982)
			(xy 139.324746 -67.959444) (xy 139.281688 -67.888594) (xy 139.26312 -67.851528) (xy 139.258628 -67.843121)
			(xy 139.244657 -67.830174) (xy 139.226924 -67.823221) (xy 139.2174 -67.822826) (xy 138.0871 -67.822826)
			(xy 138.07703 -67.823245) (xy 138.058432 -67.830969) (xy 138.051032 -67.837812) (xy 137.389616 -68.499228)
			(xy 137.382773 -68.506626) (xy 137.375054 -68.525227) (xy 137.37463 -68.535296) (xy 137.37463 -71.85406)
			(xy 149.046184 -71.85406) (xy 149.046695 -71.811643) (xy 149.054765 -71.727194) (xy 149.070836 -71.643896)
			(xy 149.094764 -71.562507) (xy 149.12633 -71.483764) (xy 149.165248 -71.408384) (xy 149.211164 -71.33705)
			(xy 149.263662 -71.270412) (xy 149.322265 -71.209073) (xy 149.354032 -71.18096) (xy 149.361938 -71.173399)
			(xy 149.371032 -71.153531) (xy 149.371558 -71.142606) (xy 149.371558 -71.06539) (xy 149.371056 -71.054461)
			(xy 149.361953 -71.034585) (xy 149.354032 -71.027036) (xy 149.322275 -70.998912) (xy 149.263673 -70.937573)
			(xy 149.211174 -70.870935) (xy 149.165256 -70.799603) (xy 149.126335 -70.724225) (xy 149.094765 -70.645485)
			(xy 149.070832 -70.564097) (xy 149.054754 -70.480801) (xy 149.046677 -70.396353) (xy 149.046184 -70.353936)
			(xy 149.046688 -70.311588) (xy 149.054739 -70.227274) (xy 149.070768 -70.144108) (xy 149.094629 -70.062841)
			(xy 149.126108 -69.984211) (xy 149.164919 -69.90893) (xy 149.210709 -69.837678) (xy 149.263065 -69.771102)
			(xy 149.321513 -69.709804) (xy 149.385523 -69.654339) (xy 149.454515 -69.60521) (xy 149.527865 -69.562861)
			(xy 149.604908 -69.527677) (xy 149.684947 -69.499975) (xy 149.767256 -69.480007) (xy 149.851091 -69.467954)
			(xy 149.935692 -69.463924) (xy 150.020293 -69.467954) (xy 150.104128 -69.480007) (xy 150.186437 -69.499975)
			(xy 150.266476 -69.527677) (xy 150.343519 -69.562861) (xy 150.416869 -69.60521) (xy 150.485861 -69.654339)
			(xy 150.549871 -69.709804) (xy 150.608319 -69.771102) (xy 150.660675 -69.837678) (xy 150.706465 -69.90893)
			(xy 150.745276 -69.984211) (xy 150.776755 -70.062841) (xy 150.800616 -70.144108) (xy 150.816645 -70.227274)
			(xy 150.824696 -70.311588) (xy 150.8252 -70.353936) (xy 150.824691 -70.396353) (xy 150.816622 -70.480803)
			(xy 150.800551 -70.5641) (xy 150.776623 -70.64549) (xy 150.745057 -70.724233) (xy 150.706139 -70.799613)
			(xy 150.660221 -70.870946) (xy 150.607723 -70.937585) (xy 150.549119 -70.998924) (xy 150.517352 -71.027036)
			(xy 150.509446 -71.034596) (xy 150.500353 -71.054465) (xy 150.499826 -71.06539) (xy 150.499826 -71.142606)
			(xy 150.500336 -71.153534) (xy 150.509433 -71.173409) (xy 150.517352 -71.18096) (xy 150.549103 -71.20909)
			(xy 150.607707 -71.270428) (xy 150.660206 -71.337064) (xy 150.706125 -71.408396) (xy 150.745047 -71.483773)
			(xy 150.776617 -71.562513) (xy 150.800551 -71.6439) (xy 150.816629 -71.727196) (xy 150.824707 -71.811643)
			(xy 150.8252 -71.85406) (xy 150.824696 -71.896408) (xy 150.816645 -71.980722) (xy 150.811195 -72.009)
			(xy 177.667872 -72.009) (xy 177.671902 -71.924395) (xy 177.683957 -71.840557) (xy 177.703926 -71.758244)
			(xy 177.73163 -71.678202) (xy 177.766817 -71.601156) (xy 177.809168 -71.527804) (xy 177.8583 -71.458809)
			(xy 177.913768 -71.394798) (xy 177.97507 -71.336349) (xy 178.041651 -71.283992) (xy 178.112907 -71.238201)
			(xy 178.188193 -71.199391) (xy 178.266827 -71.167914) (xy 178.348098 -71.144053) (xy 178.431268 -71.128027)
			(xy 178.515586 -71.119978) (xy 178.557936 -71.119492) (xy 178.596727 -71.119889) (xy 178.674016 -71.126624)
			(xy 178.750424 -71.140065) (xy 178.825371 -71.16011) (xy 178.898288 -71.186607) (xy 178.968619 -71.219355)
			(xy 179.002436 -71.238364) (xy 179.01031 -71.242523) (xy 179.027836 -71.245617) (xy 179.045362 -71.242523)
			(xy 179.053236 -71.238364) (xy 179.087054 -71.219359) (xy 179.157387 -71.186616) (xy 179.230303 -71.160122)
			(xy 179.30525 -71.140079) (xy 179.381658 -71.126639) (xy 179.458946 -71.119903) (xy 179.497736 -71.119492)
			(xy 179.540083 -71.119997) (xy 179.624394 -71.128051) (xy 179.707558 -71.144083) (xy 179.788821 -71.167947)
			(xy 179.867448 -71.199427) (xy 179.942727 -71.238239) (xy 180.013976 -71.28403) (xy 180.080549 -71.336386)
			(xy 180.141844 -71.394834) (xy 180.197307 -71.458843) (xy 180.246433 -71.527834) (xy 180.28878 -71.601182)
			(xy 180.323962 -71.678224) (xy 180.351663 -71.758261) (xy 180.37163 -71.840568) (xy 180.383683 -71.924401)
			(xy 180.387713 -72.009) (xy 180.383683 -72.093599) (xy 180.37163 -72.177432) (xy 180.351663 -72.259739)
			(xy 180.323962 -72.339776) (xy 180.28878 -72.416818) (xy 180.246433 -72.490166) (xy 180.197307 -72.559157)
			(xy 180.141844 -72.623166) (xy 180.080549 -72.681614) (xy 180.013976 -72.73397) (xy 179.942727 -72.779761)
			(xy 179.867448 -72.818573) (xy 179.788821 -72.850053) (xy 179.707558 -72.873917) (xy 179.624394 -72.889949)
			(xy 179.540083 -72.898003) (xy 179.497736 -72.898508) (xy 179.458945 -72.898124) (xy 179.381656 -72.891387)
			(xy 179.305247 -72.877943) (xy 179.2303 -72.857895) (xy 179.157383 -72.831396) (xy 179.087053 -72.798646)
			(xy 179.053236 -72.779636) (xy 179.045362 -72.775477) (xy 179.027836 -72.772383) (xy 179.01031 -72.775477)
			(xy 179.002436 -72.779636) (xy 178.968624 -72.798653) (xy 178.89829 -72.831394) (xy 178.825372 -72.857885)
			(xy 178.750424 -72.877926) (xy 178.674015 -72.891365) (xy 178.596727 -72.898098) (xy 178.557936 -72.898508)
			(xy 178.515586 -72.898022) (xy 178.431268 -72.889973) (xy 178.348098 -72.873947) (xy 178.266827 -72.850086)
			(xy 178.188193 -72.818609) (xy 178.112907 -72.779799) (xy 178.041651 -72.734008) (xy 177.97507 -72.681651)
			(xy 177.913768 -72.623202) (xy 177.8583 -72.559191) (xy 177.809168 -72.490196) (xy 177.766817 -72.416844)
			(xy 177.73163 -72.339798) (xy 177.703926 -72.259756) (xy 177.683957 -72.177443) (xy 177.671902 -72.093605)
			(xy 177.667872 -72.009) (xy 150.811195 -72.009) (xy 150.800616 -72.063888) (xy 150.776755 -72.145155)
			(xy 150.745276 -72.223785) (xy 150.706465 -72.299066) (xy 150.660675 -72.370318) (xy 150.608319 -72.436894)
			(xy 150.549871 -72.498192) (xy 150.485861 -72.553657) (xy 150.416869 -72.602786) (xy 150.343519 -72.645135)
			(xy 150.266476 -72.680319) (xy 150.186437 -72.708021) (xy 150.104128 -72.727989) (xy 150.020293 -72.740042)
			(xy 149.935692 -72.744073) (xy 149.851091 -72.740042) (xy 149.767256 -72.727989) (xy 149.684947 -72.708021)
			(xy 149.604908 -72.680319) (xy 149.527865 -72.645135) (xy 149.454515 -72.602786) (xy 149.385523 -72.553657)
			(xy 149.321513 -72.498192) (xy 149.263065 -72.436894) (xy 149.210709 -72.370318) (xy 149.164919 -72.299066)
			(xy 149.126108 -72.223785) (xy 149.094629 -72.145155) (xy 149.070768 -72.063888) (xy 149.054739 -71.980722)
			(xy 149.046688 -71.896408) (xy 149.046184 -71.85406) (xy 137.37463 -71.85406) (xy 137.37463 -74.360278)
			(xy 144.226788 -74.360278) (xy 144.227274 -74.317132) (xy 144.23562 -74.231244) (xy 144.252241 -74.146568)
			(xy 144.276981 -74.063898) (xy 144.309607 -73.984012) (xy 144.349813 -73.907659) (xy 144.373092 -73.871328)
			(xy 144.377639 -73.863717) (xy 144.381747 -73.846485) (xy 144.37974 -73.828884) (xy 144.37614 -73.820782)
			(xy 144.358096 -73.78366) (xy 144.328174 -73.706728) (xy 144.305503 -73.627357) (xy 144.290279 -73.546227)
			(xy 144.28263 -73.464037) (xy 144.28216 -73.422764) (xy 144.28216 -73.42251) (xy 144.282664 -73.380162)
			(xy 144.290715 -73.295848) (xy 144.306744 -73.212682) (xy 144.330605 -73.131415) (xy 144.362084 -73.052785)
			(xy 144.400895 -72.977504) (xy 144.446685 -72.906252) (xy 144.499041 -72.839676) (xy 144.557489 -72.778378)
			(xy 144.621499 -72.722913) (xy 144.690491 -72.673784) (xy 144.763841 -72.631435) (xy 144.840884 -72.596251)
			(xy 144.920923 -72.568549) (xy 145.003232 -72.548581) (xy 145.087067 -72.536528) (xy 145.171668 -72.532498)
			(xy 145.256269 -72.536528) (xy 145.340104 -72.548581) (xy 145.422413 -72.568549) (xy 145.502452 -72.596251)
			(xy 145.579495 -72.631435) (xy 145.652845 -72.673784) (xy 145.721837 -72.722913) (xy 145.785847 -72.778378)
			(xy 145.844295 -72.839676) (xy 145.896651 -72.906252) (xy 145.942441 -72.977504) (xy 145.981252 -73.052785)
			(xy 146.012731 -73.131415) (xy 146.036592 -73.212682) (xy 146.052621 -73.295848) (xy 146.060672 -73.380162)
			(xy 146.061176 -73.42251) (xy 146.061176 -73.423272) (xy 146.060668 -73.466348) (xy 146.052315 -73.552094)
			(xy 146.035714 -73.636632) (xy 146.011019 -73.719169) (xy 145.978463 -73.798933) (xy 145.93835 -73.875177)
			(xy 145.915126 -73.91146) (xy 145.910587 -73.919075) (xy 145.906476 -73.936305) (xy 145.908479 -73.953905)
			(xy 145.912078 -73.962006) (xy 145.930176 -73.999137) (xy 145.960164 -74.076112) (xy 145.982889 -74.155534)
			(xy 145.998156 -74.236721) (xy 146.005833 -74.318973) (xy 146.006046 -74.337361) (xy 183.260742 -74.337361)
			(xy 183.260742 -74.252639) (xy 183.268795 -74.168302) (xy 183.284829 -74.085112) (xy 183.308697 -74.003822)
			(xy 183.340185 -73.92517) (xy 183.379007 -73.849867) (xy 183.42481 -73.778595) (xy 183.477181 -73.711999)
			(xy 183.535646 -73.650684) (xy 183.599674 -73.595203) (xy 183.668686 -73.54606) (xy 183.742056 -73.5037)
			(xy 183.819121 -73.468505) (xy 183.899183 -73.440796) (xy 183.981516 -73.420822) (xy 184.065375 -73.408765)
			(xy 184.15 -73.404734) (xy 184.234625 -73.408765) (xy 184.318484 -73.420822) (xy 184.400817 -73.440796)
			(xy 184.480879 -73.468505) (xy 184.557944 -73.5037) (xy 184.631314 -73.54606) (xy 184.700326 -73.595203)
			(xy 184.764354 -73.650684) (xy 184.822819 -73.711999) (xy 184.87519 -73.778595) (xy 184.920993 -73.849867)
			(xy 184.940962 -73.8886) (xy 266.368788 -73.8886) (xy 266.372818 -73.803999) (xy 266.384871 -73.720164)
			(xy 266.404839 -73.637855) (xy 266.432541 -73.557816) (xy 266.467725 -73.480773) (xy 266.510074 -73.407423)
			(xy 266.559203 -73.338431) (xy 266.614668 -73.274421) (xy 266.675966 -73.215973) (xy 266.742542 -73.163617)
			(xy 266.813794 -73.117827) (xy 266.889075 -73.079016) (xy 266.967705 -73.047537) (xy 267.048972 -73.023676)
			(xy 267.132138 -73.007647) (xy 267.216452 -72.999596) (xy 267.2588 -72.999092) (xy 267.259562 -72.999092)
			(xy 267.297909 -72.999501) (xy 267.374317 -73.006133) (xy 267.449868 -73.019325) (xy 267.524002 -73.038978)
			(xy 267.596166 -73.064947) (xy 267.631164 -73.080626) (xy 267.641437 -73.084766) (xy 267.663563 -73.084766)
			(xy 267.673836 -73.080626) (xy 267.708833 -73.064947) (xy 267.781003 -73.039) (xy 267.855138 -73.019357)
			(xy 267.930687 -73.006163) (xy 268.007092 -72.999518) (xy 268.045438 -72.999092) (xy 268.0462 -72.999092)
			(xy 268.088548 -72.999596) (xy 268.172862 -73.007647) (xy 268.256028 -73.023676) (xy 268.337295 -73.047537)
			(xy 268.415925 -73.079016) (xy 268.491206 -73.117827) (xy 268.562458 -73.163617) (xy 268.629034 -73.215973)
			(xy 268.690332 -73.274421) (xy 268.745797 -73.338431) (xy 268.794926 -73.407423) (xy 268.837275 -73.480773)
			(xy 268.872459 -73.557816) (xy 268.900161 -73.637855) (xy 268.920129 -73.720164) (xy 268.932182 -73.803999)
			(xy 268.936213 -73.8886) (xy 268.932182 -73.973201) (xy 268.920129 -74.057036) (xy 268.900161 -74.139345)
			(xy 268.872459 -74.219384) (xy 268.837275 -74.296427) (xy 268.794926 -74.369777) (xy 268.745797 -74.438769)
			(xy 268.697852 -74.4941) (xy 303.021024 -74.4941) (xy 303.025053 -74.409502) (xy 303.037107 -74.325671)
			(xy 303.057074 -74.243365) (xy 303.084774 -74.163329) (xy 303.119957 -74.086289) (xy 303.162304 -74.012942)
			(xy 303.211431 -73.943953) (xy 303.266894 -73.879946) (xy 303.328189 -73.821501) (xy 303.394763 -73.769147)
			(xy 303.466012 -73.723358) (xy 303.54129 -73.684549) (xy 303.619917 -73.653071) (xy 303.70118 -73.629211)
			(xy 303.784343 -73.613182) (xy 303.868653 -73.605132) (xy 303.911 -73.604628) (xy 303.951046 -73.605059)
			(xy 304.030815 -73.612254) (xy 304.109614 -73.626586) (xy 304.186807 -73.647939) (xy 304.26177 -73.67614)
			(xy 304.333897 -73.710962) (xy 304.402603 -73.752123) (xy 304.467334 -73.799289) (xy 304.49774 -73.825354)
			(xy 304.504826 -73.831124) (xy 304.521886 -73.837632) (xy 304.531014 -73.838054) (xy 304.560986 -73.838054)
			(xy 304.570108 -73.837612) (xy 304.587158 -73.831097) (xy 304.59426 -73.825354) (xy 304.624664 -73.799286)
			(xy 304.689385 -73.752101) (xy 304.758087 -73.710928) (xy 304.830213 -73.676099) (xy 304.905178 -73.647896)
			(xy 304.982375 -73.626549) (xy 305.06118 -73.61223) (xy 305.140952 -73.605055) (xy 305.181 -73.604628)
			(xy 305.22335 -73.60506) (xy 305.307667 -73.613111) (xy 305.390837 -73.629141) (xy 305.472106 -73.653003)
			(xy 305.55074 -73.684483) (xy 305.626024 -73.723295) (xy 305.697279 -73.769088) (xy 305.763858 -73.821446)
			(xy 305.825158 -73.879896) (xy 305.880625 -73.943909) (xy 305.929756 -74.012903) (xy 305.972107 -74.086256)
			(xy 306.007292 -74.163302) (xy 306.034995 -74.243344) (xy 306.054964 -74.325657) (xy 306.067018 -74.409496)
			(xy 306.071049 -74.4941) (xy 306.067018 -74.578704) (xy 306.054964 -74.662543) (xy 306.034995 -74.744856)
			(xy 306.007292 -74.824898) (xy 305.972107 -74.901944) (xy 305.929756 -74.975297) (xy 305.880625 -75.044291)
			(xy 305.825158 -75.108304) (xy 305.763858 -75.166754) (xy 305.697279 -75.219112) (xy 305.626024 -75.264905)
			(xy 305.55074 -75.303717) (xy 305.472106 -75.335197) (xy 305.390837 -75.359059) (xy 305.307667 -75.375089)
			(xy 305.22335 -75.38314) (xy 305.181 -75.383644) (xy 305.140954 -75.38322) (xy 305.061185 -75.376025)
			(xy 304.982385 -75.361692) (xy 304.905191 -75.340339) (xy 304.830228 -75.312136) (xy 304.758102 -75.277313)
			(xy 304.689396 -75.236152) (xy 304.624665 -75.188984) (xy 304.59426 -75.162918) (xy 304.587168 -75.157157)
			(xy 304.570113 -75.150642) (xy 304.560986 -75.150218) (xy 304.531014 -75.150218) (xy 304.521893 -75.150666)
			(xy 304.504843 -75.157178) (xy 304.49774 -75.162918) (xy 304.467332 -75.188982) (xy 304.402612 -75.236167)
			(xy 304.333911 -75.277342) (xy 304.261786 -75.312171) (xy 304.186821 -75.340374) (xy 304.109624 -75.361722)
			(xy 304.03082 -75.376042) (xy 303.951047 -75.383217) (xy 303.911 -75.383644) (xy 303.868653 -75.383068)
			(xy 303.784343 -75.375018) (xy 303.70118 -75.358989) (xy 303.619917 -75.335129) (xy 303.54129 -75.303651)
			(xy 303.466012 -75.264842) (xy 303.394763 -75.219053) (xy 303.328189 -75.166699) (xy 303.266894 -75.108254)
			(xy 303.211431 -75.044247) (xy 303.162304 -74.975258) (xy 303.119957 -74.901911) (xy 303.084774 -74.824871)
			(xy 303.057074 -74.744835) (xy 303.037107 -74.662529) (xy 303.025053 -74.578698) (xy 303.021024 -74.4941)
			(xy 268.697852 -74.4941) (xy 268.690332 -74.502779) (xy 268.629034 -74.561227) (xy 268.562458 -74.613583)
			(xy 268.491206 -74.659373) (xy 268.415925 -74.698184) (xy 268.337295 -74.729663) (xy 268.256028 -74.753524)
			(xy 268.172862 -74.769553) (xy 268.088548 -74.777604) (xy 268.0462 -74.778108) (xy 268.045438 -74.778108)
			(xy 268.007091 -74.777699) (xy 267.930683 -74.771067) (xy 267.855132 -74.757875) (xy 267.780998 -74.738222)
			(xy 267.708834 -74.712253) (xy 267.673836 -74.696574) (xy 267.663563 -74.692434) (xy 267.641437 -74.692434)
			(xy 267.631164 -74.696574) (xy 267.596167 -74.712253) (xy 267.523997 -74.7382) (xy 267.449862 -74.757843)
			(xy 267.374313 -74.771037) (xy 267.297908 -74.777682) (xy 267.259562 -74.778108) (xy 267.2588 -74.778108)
			(xy 267.216452 -74.777604) (xy 267.132138 -74.769553) (xy 267.048972 -74.753524) (xy 266.967705 -74.729663)
			(xy 266.889075 -74.698184) (xy 266.813794 -74.659373) (xy 266.742542 -74.613583) (xy 266.675966 -74.561227)
			(xy 266.614668 -74.502779) (xy 266.559203 -74.438769) (xy 266.510074 -74.369777) (xy 266.467725 -74.296427)
			(xy 266.432541 -74.219384) (xy 266.404839 -74.139345) (xy 266.384871 -74.057036) (xy 266.372818 -73.973201)
			(xy 266.368788 -73.8886) (xy 184.940962 -73.8886) (xy 184.959815 -73.92517) (xy 184.991303 -74.003822)
			(xy 185.015171 -74.085112) (xy 185.031205 -74.168302) (xy 185.039258 -74.252639) (xy 185.039762 -74.295)
			(xy 185.039258 -74.337361) (xy 185.031205 -74.421698) (xy 185.015171 -74.504888) (xy 184.991303 -74.586178)
			(xy 184.959815 -74.66483) (xy 184.920993 -74.740133) (xy 184.87519 -74.811405) (xy 184.822819 -74.878001)
			(xy 184.764354 -74.939316) (xy 184.700326 -74.994797) (xy 184.631314 -75.04394) (xy 184.557944 -75.0863)
			(xy 184.480879 -75.121495) (xy 184.400817 -75.149204) (xy 184.318484 -75.169178) (xy 184.234625 -75.181235)
			(xy 184.15 -75.185267) (xy 184.065375 -75.181235) (xy 183.981516 -75.169178) (xy 183.899183 -75.149204)
			(xy 183.819121 -75.121495) (xy 183.742056 -75.0863) (xy 183.668686 -75.04394) (xy 183.599674 -74.994797)
			(xy 183.535646 -74.939316) (xy 183.477181 -74.878001) (xy 183.42481 -74.811405) (xy 183.379007 -74.740133)
			(xy 183.340185 -74.66483) (xy 183.308697 -74.586178) (xy 183.284829 -74.504888) (xy 183.268795 -74.421698)
			(xy 183.260742 -74.337361) (xy 146.006046 -74.337361) (xy 146.006312 -74.360278) (xy 146.005808 -74.402639)
			(xy 145.997755 -74.486976) (xy 145.981721 -74.570166) (xy 145.957853 -74.651456) (xy 145.926365 -74.730108)
			(xy 145.887543 -74.805411) (xy 145.84174 -74.876683) (xy 145.789369 -74.943279) (xy 145.730904 -75.004594)
			(xy 145.666876 -75.060075) (xy 145.597864 -75.109218) (xy 145.524494 -75.151578) (xy 145.447429 -75.186773)
			(xy 145.367367 -75.214482) (xy 145.285034 -75.234456) (xy 145.201175 -75.246513) (xy 145.11655 -75.250545)
			(xy 145.031925 -75.246513) (xy 144.948066 -75.234456) (xy 144.865733 -75.214482) (xy 144.785671 -75.186773)
			(xy 144.708606 -75.151578) (xy 144.635236 -75.109218) (xy 144.566224 -75.060075) (xy 144.502196 -75.004594)
			(xy 144.443731 -74.943279) (xy 144.39136 -74.876683) (xy 144.345557 -74.805411) (xy 144.306735 -74.730108)
			(xy 144.275247 -74.651456) (xy 144.251379 -74.570166) (xy 144.235345 -74.486976) (xy 144.227292 -74.402639)
			(xy 144.226788 -74.360278) (xy 137.37463 -74.360278) (xy 137.37463 -75.861361) (xy 297.179742 -75.861361)
			(xy 297.179742 -75.776639) (xy 297.187795 -75.692302) (xy 297.203829 -75.609112) (xy 297.227697 -75.527822)
			(xy 297.259185 -75.44917) (xy 297.298007 -75.373867) (xy 297.34381 -75.302595) (xy 297.396181 -75.235999)
			(xy 297.454646 -75.174684) (xy 297.518674 -75.119203) (xy 297.587686 -75.07006) (xy 297.661056 -75.0277)
			(xy 297.738121 -74.992505) (xy 297.818183 -74.964796) (xy 297.900516 -74.944822) (xy 297.984375 -74.932765)
			(xy 298.069 -74.928734) (xy 298.153625 -74.932765) (xy 298.237484 -74.944822) (xy 298.319817 -74.964796)
			(xy 298.399879 -74.992505) (xy 298.476944 -75.0277) (xy 298.550314 -75.07006) (xy 298.619326 -75.119203)
			(xy 298.683354 -75.174684) (xy 298.741819 -75.235999) (xy 298.79419 -75.302595) (xy 298.839993 -75.373867)
			(xy 298.878815 -75.44917) (xy 298.910303 -75.527822) (xy 298.934171 -75.609112) (xy 298.950205 -75.692302)
			(xy 298.958258 -75.776639) (xy 298.958762 -75.819) (xy 298.958258 -75.861361) (xy 298.950205 -75.945698)
			(xy 298.934171 -76.028888) (xy 298.910303 -76.110178) (xy 298.878815 -76.18883) (xy 298.839993 -76.264133)
			(xy 298.810167 -76.310544) (xy 305.873647 -76.310544) (xy 305.873647 -76.181404) (xy 305.881597 -76.052509)
			(xy 305.897467 -75.924349) (xy 305.921196 -75.797408) (xy 305.952695 -75.672169) (xy 305.991844 -75.549106)
			(xy 306.038495 -75.428687) (xy 306.09247 -75.311368) (xy 306.153565 -75.197594) (xy 306.221548 -75.087797)
			(xy 306.296162 -74.982394) (xy 306.377123 -74.881784) (xy 306.464123 -74.786349) (xy 306.556834 -74.69645)
			(xy 306.654904 -74.612429) (xy 306.757959 -74.534605) (xy 306.86561 -74.463273) (xy 306.977449 -74.398703)
			(xy 307.09305 -74.341141) (xy 307.211975 -74.290804) (xy 307.333774 -74.247884) (xy 307.457984 -74.212543)
			(xy 307.584133 -74.184916) (xy 307.711745 -74.165107) (xy 307.840334 -74.153191) (xy 307.969412 -74.149215)
			(xy 308.09849 -74.153191) (xy 308.227079 -74.165107) (xy 308.354691 -74.184916) (xy 308.48084 -74.212543)
			(xy 308.60505 -74.247884) (xy 308.726849 -74.290804) (xy 308.845774 -74.341141) (xy 308.961375 -74.398703)
			(xy 309.073214 -74.463273) (xy 309.180865 -74.534605) (xy 309.28392 -74.612429) (xy 309.38199 -74.69645)
			(xy 309.474701 -74.786349) (xy 309.561701 -74.881784) (xy 309.642662 -74.982394) (xy 309.717276 -75.087797)
			(xy 309.785259 -75.197594) (xy 309.846354 -75.311368) (xy 309.900329 -75.428687) (xy 309.94698 -75.549106)
			(xy 309.986129 -75.672169) (xy 310.017628 -75.797408) (xy 310.041357 -75.924349) (xy 310.057227 -76.052509)
			(xy 310.065177 -76.181404) (xy 310.065674 -76.245974) (xy 310.065177 -76.310544) (xy 310.057227 -76.439439)
			(xy 310.041357 -76.567599) (xy 310.017628 -76.69454) (xy 309.986129 -76.819779) (xy 309.94698 -76.942842)
			(xy 309.900329 -77.063261) (xy 309.846354 -77.18058) (xy 309.785259 -77.294354) (xy 309.717276 -77.404151)
			(xy 309.642662 -77.509554) (xy 309.561701 -77.610164) (xy 309.474701 -77.705599) (xy 309.38199 -77.795498)
			(xy 309.28392 -77.879519) (xy 309.180865 -77.957343) (xy 309.073214 -78.028675) (xy 308.961375 -78.093245)
			(xy 308.845774 -78.150807) (xy 308.726849 -78.201144) (xy 308.60505 -78.244064) (xy 308.48084 -78.279405)
			(xy 308.354691 -78.307032) (xy 308.227079 -78.326841) (xy 308.09849 -78.338757) (xy 307.969412 -78.342734)
			(xy 307.840334 -78.338757) (xy 307.711745 -78.326841) (xy 307.584133 -78.307032) (xy 307.457984 -78.279405)
			(xy 307.333774 -78.244064) (xy 307.211975 -78.201144) (xy 307.09305 -78.150807) (xy 306.977449 -78.093245)
			(xy 306.86561 -78.028675) (xy 306.757959 -77.957343) (xy 306.654904 -77.879519) (xy 306.556834 -77.795498)
			(xy 306.464123 -77.705599) (xy 306.377123 -77.610164) (xy 306.296162 -77.509554) (xy 306.221548 -77.404151)
			(xy 306.153565 -77.294354) (xy 306.09247 -77.18058) (xy 306.038495 -77.063261) (xy 305.991844 -76.942842)
			(xy 305.952695 -76.819779) (xy 305.921196 -76.69454) (xy 305.897467 -76.567599) (xy 305.881597 -76.439439)
			(xy 305.873647 -76.310544) (xy 298.810167 -76.310544) (xy 298.79419 -76.335405) (xy 298.741819 -76.402001)
			(xy 298.683354 -76.463316) (xy 298.619326 -76.518797) (xy 298.550314 -76.56794) (xy 298.476944 -76.6103)
			(xy 298.399879 -76.645495) (xy 298.319817 -76.673204) (xy 298.237484 -76.693178) (xy 298.153625 -76.705235)
			(xy 298.069 -76.709267) (xy 297.984375 -76.705235) (xy 297.900516 -76.693178) (xy 297.818183 -76.673204)
			(xy 297.738121 -76.645495) (xy 297.661056 -76.6103) (xy 297.587686 -76.56794) (xy 297.518674 -76.518797)
			(xy 297.454646 -76.463316) (xy 297.396181 -76.402001) (xy 297.34381 -76.335405) (xy 297.298007 -76.264133)
			(xy 297.259185 -76.18883) (xy 297.227697 -76.110178) (xy 297.203829 -76.028888) (xy 297.187795 -75.945698)
			(xy 297.179742 -75.861361) (xy 137.37463 -75.861361) (xy 137.37463 -76.8584) (xy 142.64304 -76.8584)
			(xy 142.64707 -76.773794) (xy 142.659125 -76.689953) (xy 142.679094 -76.607639) (xy 142.706798 -76.527595)
			(xy 142.741985 -76.450547) (xy 142.784337 -76.377193) (xy 142.833469 -76.308197) (xy 142.888938 -76.244183)
			(xy 142.95024 -76.185733) (xy 143.016821 -76.133374) (xy 143.088078 -76.087581) (xy 143.163365 -76.048769)
			(xy 143.242 -76.017289) (xy 143.323272 -75.993427) (xy 143.406444 -75.977398) (xy 143.490763 -75.969347)
			(xy 143.533114 -75.96886) (xy 143.533368 -75.96886) (xy 143.576522 -75.969355) (xy 143.662423 -75.977737)
			(xy 143.747109 -75.994397) (xy 143.829784 -76.019177) (xy 143.909671 -76.051846) (xy 143.98602 -76.092095)
			(xy 144.058114 -76.139548) (xy 144.125275 -76.193757) (xy 144.15643 -76.223622) (xy 144.163594 -76.230101)
			(xy 144.181339 -76.237687) (xy 144.190974 -76.238354) (xy 144.270476 -76.239878) (xy 144.28851 -76.23302)
			(xy 144.295876 -76.226416) (xy 144.32649 -76.199346) (xy 144.391887 -76.150331) (xy 144.461506 -76.107524)
			(xy 144.534759 -76.071287) (xy 144.611029 -76.041924) (xy 144.689671 -76.019684) (xy 144.770022 -76.004754)
			(xy 144.851405 -75.997261) (xy 144.892268 -75.9968) (xy 144.892522 -75.9968) (xy 144.93487 -75.997289)
			(xy 145.019183 -76.005341) (xy 145.102348 -76.021372) (xy 145.183614 -76.045236) (xy 145.262242 -76.076716)
			(xy 145.337523 -76.115527) (xy 145.408773 -76.161318) (xy 145.475349 -76.213675) (xy 145.536645 -76.272123)
			(xy 145.592109 -76.336133) (xy 145.641237 -76.405125) (xy 145.683585 -76.478475) (xy 145.718768 -76.555518)
			(xy 145.74647 -76.635556) (xy 145.766437 -76.717865) (xy 145.778491 -76.8017) (xy 145.782521 -76.8863)
			(xy 145.778491 -76.9709) (xy 145.766437 -77.054735) (xy 145.74647 -77.137044) (xy 145.718768 -77.217082)
			(xy 145.683585 -77.294125) (xy 145.641237 -77.367475) (xy 145.592109 -77.436467) (xy 145.536645 -77.500477)
			(xy 145.475349 -77.558925) (xy 145.408773 -77.611282) (xy 145.337523 -77.657073) (xy 145.262242 -77.695884)
			(xy 145.183614 -77.727364) (xy 145.102348 -77.751228) (xy 145.019183 -77.767259) (xy 144.93487 -77.775311)
			(xy 144.892522 -77.775816) (xy 144.892268 -77.775816) (xy 144.849115 -77.775276) (xy 144.763216 -77.766898)
			(xy 144.678532 -77.750243) (xy 144.595858 -77.725468) (xy 144.515971 -77.692806) (xy 144.439621 -77.652563)
			(xy 144.367526 -77.605117) (xy 144.300363 -77.550915) (xy 144.269206 -77.521054) (xy 144.262065 -77.514545)
			(xy 144.244303 -77.506978) (xy 144.234662 -77.506322) (xy 144.15516 -77.504798) (xy 144.137126 -77.511656)
			(xy 144.12976 -77.51826) (xy 144.099127 -77.545309) (xy 144.033734 -77.594326) (xy 143.964118 -77.637135)
			(xy 143.890867 -77.673375) (xy 143.8146 -77.702741) (xy 143.73596 -77.724984) (xy 143.655611 -77.739917)
			(xy 143.574231 -77.747414) (xy 143.533368 -77.747876) (xy 143.533114 -77.747876) (xy 143.490763 -77.747453)
			(xy 143.406444 -77.739402) (xy 143.323272 -77.723373) (xy 143.242 -77.699511) (xy 143.163365 -77.668031)
			(xy 143.088078 -77.629219) (xy 143.016821 -77.583426) (xy 142.95024 -77.531067) (xy 142.888938 -77.472617)
			(xy 142.833469 -77.408603) (xy 142.784337 -77.339607) (xy 142.741985 -77.266253) (xy 142.706798 -77.189205)
			(xy 142.679094 -77.109161) (xy 142.659125 -77.026847) (xy 142.64707 -76.943006) (xy 142.64304 -76.8584)
			(xy 137.37463 -76.8584) (xy 137.37463 -79.7052) (xy 149.144228 -79.7052) (xy 149.144228 -79.704692)
			(xy 149.144831 -79.65836) (xy 149.154503 -79.566202) (xy 149.173699 -79.475548) (xy 149.202212 -79.387379)
			(xy 149.220428 -79.344774) (xy 149.224232 -79.334831) (xy 149.224232 -79.313569) (xy 149.220428 -79.303626)
			(xy 149.202202 -79.261025) (xy 149.173686 -79.172856) (xy 149.154495 -79.082201) (xy 149.144836 -78.99004)
			(xy 149.144228 -78.943708) (xy 149.144228 -78.9432) (xy 149.144732 -78.900852) (xy 149.152783 -78.816538)
			(xy 149.168812 -78.733372) (xy 149.192673 -78.652105) (xy 149.224152 -78.573475) (xy 149.262963 -78.498194)
			(xy 149.308753 -78.426942) (xy 149.361109 -78.360366) (xy 149.419557 -78.299068) (xy 149.483567 -78.243603)
			(xy 149.552559 -78.194474) (xy 149.625909 -78.152125) (xy 149.702952 -78.116941) (xy 149.782991 -78.089239)
			(xy 149.8653 -78.069271) (xy 149.949135 -78.057218) (xy 150.033736 -78.053188) (xy 150.118337 -78.057218)
			(xy 150.202172 -78.069271) (xy 150.284481 -78.089239) (xy 150.36452 -78.116941) (xy 150.441563 -78.152125)
			(xy 150.514913 -78.194474) (xy 150.583905 -78.243603) (xy 150.647915 -78.299068) (xy 150.706363 -78.360366)
			(xy 150.758719 -78.426942) (xy 150.804509 -78.498194) (xy 150.84332 -78.573475) (xy 150.874799 -78.652105)
			(xy 150.89866 -78.733372) (xy 150.914689 -78.816538) (xy 150.92274 -78.900852) (xy 150.923244 -78.9432)
			(xy 150.923244 -78.943708) (xy 150.922635 -78.99004) (xy 150.912964 -79.082198) (xy 150.893769 -79.172852)
			(xy 150.865258 -79.26102) (xy 150.847044 -79.303626) (xy 150.843237 -79.313568) (xy 150.843237 -79.334832)
			(xy 150.847044 -79.344774) (xy 150.865268 -79.387376) (xy 150.893785 -79.475544) (xy 150.912977 -79.5662)
			(xy 150.922636 -79.65836) (xy 150.923244 -79.704692) (xy 150.923244 -79.7052) (xy 150.923186 -79.710114)
			(xy 205.177635 -79.710114) (xy 205.177635 -79.539758) (xy 205.18562 -79.36959) (xy 205.201572 -79.199983)
			(xy 205.225457 -79.031311) (xy 205.257221 -78.863943) (xy 205.296796 -78.698248) (xy 205.344093 -78.53459)
			(xy 205.39901 -78.373329) (xy 205.461425 -78.214819) (xy 205.531201 -78.059409) (xy 205.608184 -77.907441)
			(xy 205.692206 -77.759247) (xy 205.783082 -77.615155) (xy 205.880612 -77.475481) (xy 205.984582 -77.340532)
			(xy 206.094763 -77.210604) (xy 206.210912 -77.085984) (xy 206.332776 -76.966945) (xy 206.460084 -76.853749)
			(xy 206.592559 -76.746644) (xy 206.729909 -76.645867) (xy 206.871831 -76.551638) (xy 207.018013 -76.464165)
			(xy 207.168136 -76.38364) (xy 207.321867 -76.31024) (xy 207.47887 -76.244126) (xy 207.6388 -76.185444)
			(xy 207.801304 -76.134323) (xy 207.966025 -76.090875) (xy 208.132603 -76.055196) (xy 208.300669 -76.027364)
			(xy 208.469855 -76.00744) (xy 208.639789 -75.995468) (xy 208.810098 -75.991475) (xy 208.980407 -75.995468)
			(xy 209.150341 -76.00744) (xy 209.319527 -76.027364) (xy 209.487593 -76.055196) (xy 209.654171 -76.090875)
			(xy 209.818892 -76.134323) (xy 209.981396 -76.185444) (xy 210.141326 -76.244126) (xy 210.298329 -76.31024)
			(xy 210.45206 -76.38364) (xy 210.602183 -76.464165) (xy 210.748365 -76.551638) (xy 210.890287 -76.645867)
			(xy 211.027637 -76.746644) (xy 211.160112 -76.853749) (xy 211.28742 -76.966945) (xy 211.409284 -77.085984)
			(xy 211.525433 -77.210604) (xy 211.635614 -77.340532) (xy 211.739584 -77.475481) (xy 211.837114 -77.615155)
			(xy 211.92799 -77.759247) (xy 212.012012 -77.907441) (xy 212.088995 -78.059409) (xy 212.158771 -78.214819)
			(xy 212.221186 -78.373329) (xy 212.276103 -78.53459) (xy 212.3234 -78.698248) (xy 212.362975 -78.863943)
			(xy 212.394739 -79.031311) (xy 212.418624 -79.199983) (xy 212.434576 -79.36959) (xy 212.442561 -79.539758)
			(xy 212.44306 -79.624936) (xy 212.442561 -79.710114) (xy 235.177575 -79.710114) (xy 235.177575 -79.539758)
			(xy 235.18556 -79.36959) (xy 235.201512 -79.199983) (xy 235.225397 -79.031311) (xy 235.257161 -78.863943)
			(xy 235.296736 -78.698248) (xy 235.344033 -78.53459) (xy 235.39895 -78.373329) (xy 235.461365 -78.214819)
			(xy 235.531141 -78.059409) (xy 235.608124 -77.907441) (xy 235.692146 -77.759247) (xy 235.783022 -77.615155)
			(xy 235.880552 -77.475481) (xy 235.984522 -77.340532) (xy 236.094703 -77.210604) (xy 236.210852 -77.085984)
			(xy 236.332716 -76.966945) (xy 236.460024 -76.853749) (xy 236.592499 -76.746644) (xy 236.729849 -76.645867)
			(xy 236.871771 -76.551638) (xy 237.017953 -76.464165) (xy 237.168076 -76.38364) (xy 237.321807 -76.31024)
			(xy 237.47881 -76.244126) (xy 237.63874 -76.185444) (xy 237.801244 -76.134323) (xy 237.965965 -76.090875)
			(xy 238.132543 -76.055196) (xy 238.300609 -76.027364) (xy 238.469795 -76.00744) (xy 238.639729 -75.995468)
			(xy 238.810038 -75.991475) (xy 238.980347 -75.995468) (xy 239.150281 -76.00744) (xy 239.319467 -76.027364)
			(xy 239.487533 -76.055196) (xy 239.654111 -76.090875) (xy 239.818832 -76.134323) (xy 239.981336 -76.185444)
			(xy 240.141266 -76.244126) (xy 240.298269 -76.31024) (xy 240.452 -76.38364) (xy 240.602123 -76.464165)
			(xy 240.748305 -76.551638) (xy 240.890227 -76.645867) (xy 241.027577 -76.746644) (xy 241.160052 -76.853749)
			(xy 241.28736 -76.966945) (xy 241.409224 -77.085984) (xy 241.525373 -77.210604) (xy 241.635554 -77.340532)
			(xy 241.739524 -77.475481) (xy 241.837054 -77.615155) (xy 241.92793 -77.759247) (xy 242.011952 -77.907441)
			(xy 242.088935 -78.059409) (xy 242.132213 -78.1558) (xy 279.439887 -78.1558) (xy 279.443918 -78.071199)
			(xy 279.455971 -77.987365) (xy 279.475939 -77.905056) (xy 279.50364 -77.825017) (xy 279.538825 -77.747974)
			(xy 279.581173 -77.674625) (xy 279.630301 -77.605633) (xy 279.685766 -77.541623) (xy 279.747063 -77.483176)
			(xy 279.813639 -77.430819) (xy 279.88489 -77.385029) (xy 279.960171 -77.346218) (xy 280.038801 -77.314739)
			(xy 280.120067 -77.290877) (xy 280.203233 -77.274847) (xy 280.287546 -77.266796) (xy 280.329894 -77.266292)
			(xy 280.330402 -77.266292) (xy 280.376734 -77.2669) (xy 280.468892 -77.276571) (xy 280.559546 -77.295766)
			(xy 280.647715 -77.324277) (xy 280.69032 -77.342492) (xy 280.700262 -77.346298) (xy 280.721526 -77.346298)
			(xy 280.731468 -77.342492) (xy 280.774072 -77.324272) (xy 280.862239 -77.295754) (xy 280.952894 -77.276561)
			(xy 281.045054 -77.2669) (xy 281.091386 -77.266292) (xy 281.091894 -77.266292) (xy 281.134243 -77.26678)
			(xy 281.218559 -77.27483) (xy 281.301727 -77.290859) (xy 281.382995 -77.314721) (xy 281.461627 -77.3462)
			(xy 281.536911 -77.385011) (xy 281.608164 -77.430802) (xy 281.674742 -77.48316) (xy 281.736042 -77.541608)
			(xy 281.791508 -77.605619) (xy 281.840638 -77.674613) (xy 281.882988 -77.747964) (xy 281.918173 -77.825009)
			(xy 281.945875 -77.905049) (xy 281.965844 -77.98736) (xy 281.977898 -78.071197) (xy 281.981928 -78.1558)
			(xy 281.977898 -78.240403) (xy 281.965844 -78.32424) (xy 281.945875 -78.406551) (xy 281.918173 -78.486591)
			(xy 281.882988 -78.563636) (xy 281.840638 -78.636987) (xy 281.791508 -78.705981) (xy 281.736042 -78.769992)
			(xy 281.674742 -78.82844) (xy 281.608164 -78.880798) (xy 281.536911 -78.926589) (xy 281.461627 -78.9654)
			(xy 281.382995 -78.996879) (xy 281.301727 -79.020741) (xy 281.218559 -79.03677) (xy 281.134243 -79.04482)
			(xy 281.091894 -79.045308) (xy 281.091386 -79.045308) (xy 281.045054 -79.044704) (xy 280.952896 -79.035032)
			(xy 280.862242 -79.015836) (xy 280.774073 -78.987323) (xy 280.731468 -78.969108) (xy 280.721526 -78.965302)
			(xy 280.700262 -78.965302) (xy 280.69032 -78.969108) (xy 280.647718 -78.987332) (xy 280.55955 -79.015849)
			(xy 280.468894 -79.035041) (xy 280.376734 -79.0447) (xy 280.330402 -79.045308) (xy 280.329894 -79.045308)
			(xy 280.287546 -79.044804) (xy 280.203233 -79.036753) (xy 280.120067 -79.020723) (xy 280.038801 -78.996861)
			(xy 279.960171 -78.965382) (xy 279.88489 -78.926571) (xy 279.813639 -78.880781) (xy 279.747063 -78.828424)
			(xy 279.685766 -78.769977) (xy 279.630301 -78.705967) (xy 279.581173 -78.636975) (xy 279.538825 -78.563626)
			(xy 279.50364 -78.486583) (xy 279.475939 -78.406544) (xy 279.455971 -78.324235) (xy 279.443918 -78.240401)
			(xy 279.439887 -78.1558) (xy 242.132213 -78.1558) (xy 242.158711 -78.214819) (xy 242.221126 -78.373329)
			(xy 242.276043 -78.53459) (xy 242.32334 -78.698248) (xy 242.362915 -78.863943) (xy 242.394679 -79.031311)
			(xy 242.418564 -79.199983) (xy 242.434516 -79.36959) (xy 242.442501 -79.539758) (xy 242.443 -79.624936)
			(xy 242.442501 -79.710114) (xy 242.434516 -79.880282) (xy 242.418564 -80.049889) (xy 242.394679 -80.218561)
			(xy 242.362915 -80.385929) (xy 242.361704 -80.391) (xy 297.102788 -80.391) (xy 297.106818 -80.306399)
			(xy 297.118871 -80.222564) (xy 297.138839 -80.140255) (xy 297.166541 -80.060216) (xy 297.201725 -79.983173)
			(xy 297.244074 -79.909823) (xy 297.293203 -79.840831) (xy 297.348668 -79.776821) (xy 297.409966 -79.718373)
			(xy 297.476542 -79.666017) (xy 297.547794 -79.620227) (xy 297.623075 -79.581416) (xy 297.701705 -79.549937)
			(xy 297.782972 -79.526076) (xy 297.866138 -79.510047) (xy 297.950452 -79.501996) (xy 297.9928 -79.501492)
			(xy 297.993308 -79.501492) (xy 298.03964 -79.502098) (xy 298.131798 -79.511769) (xy 298.222452 -79.530965)
			(xy 298.310621 -79.559477) (xy 298.353226 -79.577692) (xy 298.363168 -79.581498) (xy 298.384432 -79.581498)
			(xy 298.394374 -79.577692) (xy 298.436977 -79.55947) (xy 298.525144 -79.530952) (xy 298.6158 -79.51176)
			(xy 298.70796 -79.5021) (xy 298.754292 -79.501492) (xy 298.7548 -79.501492) (xy 298.797148 -79.501996)
			(xy 298.881462 -79.510047) (xy 298.964628 -79.526076) (xy 299.045895 -79.549937) (xy 299.124525 -79.581416)
			(xy 299.199806 -79.620227) (xy 299.271058 -79.666017) (xy 299.337634 -79.718373) (xy 299.398932 -79.776821)
			(xy 299.450937 -79.836838) (xy 303.180186 -79.836838) (xy 303.182815 -79.753015) (xy 303.19332 -79.66981)
			(xy 303.211608 -79.587964) (xy 303.237517 -79.508202) (xy 303.270817 -79.431231) (xy 303.311212 -79.357736)
			(xy 303.358343 -79.288368) (xy 303.411794 -79.223743) (xy 303.471088 -79.164435) (xy 303.5357 -79.110969)
			(xy 303.605057 -79.063821) (xy 303.678543 -79.023409) (xy 303.755505 -78.990091) (xy 303.835261 -78.964164)
			(xy 303.917103 -78.945856) (xy 304.000305 -78.935331) (xy 304.084128 -78.932683) (xy 304.167828 -78.937934)
			(xy 304.250663 -78.951038) (xy 304.331897 -78.971879) (xy 304.410809 -79.000271) (xy 304.4867 -79.035964)
			(xy 304.558894 -79.078639) (xy 304.626753 -79.127919) (xy 304.689673 -79.183366) (xy 304.747097 -79.244487)
			(xy 304.798514 -79.310741) (xy 304.843468 -79.38154) (xy 304.881561 -79.456254) (xy 304.912453 -79.534222)
			(xy 304.935872 -79.61475) (xy 304.951609 -79.697125) (xy 304.959525 -79.780616) (xy 304.96002 -79.822548)
			(xy 304.96002 -79.823056) (xy 304.959492 -79.865875) (xy 304.951224 -79.951114) (xy 304.94351 -79.993236)
			(xy 304.941789 -80.004521) (xy 304.94747 -80.026607) (xy 304.954432 -80.035654) (xy 305.012852 -80.104996)
			(xy 305.03368 -80.114394) (xy 305.044856 -80.11414) (xy 305.045872 -80.11414) (xy 305.063398 -80.11414)
			(xy 305.105333 -80.11462) (xy 305.18883 -80.122512) (xy 305.271215 -80.138226) (xy 305.351755 -80.161624)
			(xy 305.429736 -80.192496) (xy 305.504465 -80.23057) (xy 305.57528 -80.275507) (xy 305.641553 -80.326908)
			(xy 305.702694 -80.384318) (xy 305.758161 -80.447227) (xy 305.807463 -80.515076) (xy 305.85016 -80.587263)
			(xy 305.885876 -80.663148) (xy 305.914292 -80.742058) (xy 305.935156 -80.823291) (xy 305.948283 -80.906127)
			(xy 305.953557 -80.98983) (xy 305.950931 -81.073659) (xy 305.940428 -81.156868) (xy 305.922142 -81.23872)
			(xy 305.896234 -81.318488) (xy 305.862935 -81.395464) (xy 305.82254 -81.468965) (xy 305.775407 -81.538338)
			(xy 305.721955 -81.602968) (xy 305.662659 -81.662282) (xy 305.598045 -81.715752) (xy 305.528685 -81.762905)
			(xy 305.455196 -81.803321) (xy 305.37823 -81.836643) (xy 305.298469 -81.862574) (xy 305.216623 -81.880884)
			(xy 305.133416 -81.891411) (xy 305.049589 -81.894061) (xy 304.965883 -81.888812) (xy 304.883044 -81.875708)
			(xy 304.801804 -81.854868) (xy 304.722887 -81.826475) (xy 304.646992 -81.790781) (xy 304.574792 -81.748104)
			(xy 304.506928 -81.698823) (xy 304.444004 -81.643373) (xy 304.386576 -81.582249) (xy 304.335155 -81.515992)
			(xy 304.290198 -81.445189) (xy 304.252102 -81.370471) (xy 304.221207 -81.292499) (xy 304.197787 -81.211966)
			(xy 304.182048 -81.129586) (xy 304.174132 -81.046091) (xy 304.173636 -81.004156) (xy 304.173636 -81.003648)
			(xy 304.174164 -80.960829) (xy 304.182432 -80.87559) (xy 304.190146 -80.833468) (xy 304.191851 -80.822182)
			(xy 304.186179 -80.800099) (xy 304.179224 -80.79105) (xy 304.120804 -80.721708) (xy 304.099976 -80.71231)
			(xy 304.0888 -80.712564) (xy 304.087784 -80.712564) (xy 304.070258 -80.712564) (xy 304.028326 -80.712034)
			(xy 303.944833 -80.704139) (xy 303.862455 -80.688421) (xy 303.78192 -80.665021) (xy 303.703946 -80.634147)
			(xy 303.629222 -80.596072) (xy 303.558413 -80.551135) (xy 303.492147 -80.499733) (xy 303.431012 -80.442324)
			(xy 303.37555 -80.379417) (xy 303.326255 -80.31157) (xy 303.283562 -80.239385) (xy 303.247852 -80.163503)
			(xy 303.219441 -80.084598) (xy 303.198581 -80.003369) (xy 303.185457 -79.920537) (xy 303.180186 -79.836838)
			(xy 299.450937 -79.836838) (xy 299.454397 -79.840831) (xy 299.503526 -79.909823) (xy 299.545875 -79.983173)
			(xy 299.581059 -80.060216) (xy 299.608761 -80.140255) (xy 299.628729 -80.222564) (xy 299.640782 -80.306399)
			(xy 299.644813 -80.391) (xy 299.640782 -80.475601) (xy 299.628729 -80.559436) (xy 299.608761 -80.641745)
			(xy 299.581059 -80.721784) (xy 299.545875 -80.798827) (xy 299.503526 -80.872177) (xy 299.454397 -80.941169)
			(xy 299.398932 -81.005179) (xy 299.337634 -81.063627) (xy 299.271058 -81.115983) (xy 299.199806 -81.161773)
			(xy 299.124525 -81.200584) (xy 299.045895 -81.232063) (xy 298.964628 -81.255924) (xy 298.881462 -81.271953)
			(xy 298.797148 -81.280004) (xy 298.7548 -81.280508) (xy 298.754292 -81.280508) (xy 298.70796 -81.279902)
			(xy 298.615802 -81.270231) (xy 298.525148 -81.251035) (xy 298.436979 -81.222523) (xy 298.394374 -81.204308)
			(xy 298.384432 -81.200502) (xy 298.363168 -81.200502) (xy 298.353226 -81.204308) (xy 298.310623 -81.22253)
			(xy 298.222456 -81.251048) (xy 298.1318 -81.27024) (xy 298.03964 -81.2799) (xy 297.993308 -81.280508)
			(xy 297.9928 -81.280508) (xy 297.950452 -81.280004) (xy 297.866138 -81.271953) (xy 297.782972 -81.255924)
			(xy 297.701705 -81.232063) (xy 297.623075 -81.200584) (xy 297.547794 -81.161773) (xy 297.476542 -81.115983)
			(xy 297.409966 -81.063627) (xy 297.348668 -81.005179) (xy 297.293203 -80.941169) (xy 297.244074 -80.872177)
			(xy 297.201725 -80.798827) (xy 297.166541 -80.721784) (xy 297.138839 -80.641745) (xy 297.118871 -80.559436)
			(xy 297.106818 -80.475601) (xy 297.102788 -80.391) (xy 242.361704 -80.391) (xy 242.32334 -80.551624)
			(xy 242.276043 -80.715282) (xy 242.221126 -80.876543) (xy 242.158711 -81.035053) (xy 242.088935 -81.190463)
			(xy 242.011952 -81.342431) (xy 241.92793 -81.490625) (xy 241.837054 -81.634717) (xy 241.739524 -81.774391)
			(xy 241.635554 -81.90934) (xy 241.525373 -82.039268) (xy 241.409224 -82.163888) (xy 241.28736 -82.282927)
			(xy 241.160052 -82.396123) (xy 241.027577 -82.503228) (xy 240.890227 -82.604005) (xy 240.748305 -82.698234)
			(xy 240.602123 -82.785707) (xy 240.452 -82.866232) (xy 240.298269 -82.939632) (xy 240.141266 -83.005746)
			(xy 239.981336 -83.064428) (xy 239.818832 -83.115549) (xy 239.654111 -83.158997) (xy 239.487533 -83.194676)
			(xy 239.319467 -83.222508) (xy 239.150281 -83.242432) (xy 238.980347 -83.254404) (xy 238.810038 -83.258398)
			(xy 238.639729 -83.254404) (xy 238.469795 -83.242432) (xy 238.300609 -83.222508) (xy 238.132543 -83.194676)
			(xy 237.965965 -83.158997) (xy 237.801244 -83.115549) (xy 237.63874 -83.064428) (xy 237.47881 -83.005746)
			(xy 237.321807 -82.939632) (xy 237.168076 -82.866232) (xy 237.017953 -82.785707) (xy 236.871771 -82.698234)
			(xy 236.729849 -82.604005) (xy 236.592499 -82.503228) (xy 236.460024 -82.396123) (xy 236.332716 -82.282927)
			(xy 236.210852 -82.163888) (xy 236.094703 -82.039268) (xy 235.984522 -81.90934) (xy 235.880552 -81.774391)
			(xy 235.783022 -81.634717) (xy 235.692146 -81.490625) (xy 235.608124 -81.342431) (xy 235.531141 -81.190463)
			(xy 235.461365 -81.035053) (xy 235.39895 -80.876543) (xy 235.344033 -80.715282) (xy 235.296736 -80.551624)
			(xy 235.257161 -80.385929) (xy 235.225397 -80.218561) (xy 235.201512 -80.049889) (xy 235.18556 -79.880282)
			(xy 235.177575 -79.710114) (xy 212.442561 -79.710114) (xy 212.434576 -79.880282) (xy 212.418624 -80.049889)
			(xy 212.394739 -80.218561) (xy 212.362975 -80.385929) (xy 212.3234 -80.551624) (xy 212.276103 -80.715282)
			(xy 212.221186 -80.876543) (xy 212.158771 -81.035053) (xy 212.088995 -81.190463) (xy 212.012012 -81.342431)
			(xy 211.92799 -81.490625) (xy 211.837114 -81.634717) (xy 211.739584 -81.774391) (xy 211.635614 -81.90934)
			(xy 211.525433 -82.039268) (xy 211.409284 -82.163888) (xy 211.28742 -82.282927) (xy 211.160112 -82.396123)
			(xy 211.027637 -82.503228) (xy 210.890287 -82.604005) (xy 210.748365 -82.698234) (xy 210.602183 -82.785707)
			(xy 210.45206 -82.866232) (xy 210.298329 -82.939632) (xy 210.141326 -83.005746) (xy 209.981396 -83.064428)
			(xy 209.818892 -83.115549) (xy 209.654171 -83.158997) (xy 209.487593 -83.194676) (xy 209.319527 -83.222508)
			(xy 209.150341 -83.242432) (xy 208.980407 -83.254404) (xy 208.810098 -83.258398) (xy 208.639789 -83.254404)
			(xy 208.469855 -83.242432) (xy 208.300669 -83.222508) (xy 208.132603 -83.194676) (xy 207.966025 -83.158997)
			(xy 207.801304 -83.115549) (xy 207.6388 -83.064428) (xy 207.47887 -83.005746) (xy 207.321867 -82.939632)
			(xy 207.168136 -82.866232) (xy 207.018013 -82.785707) (xy 206.871831 -82.698234) (xy 206.729909 -82.604005)
			(xy 206.592559 -82.503228) (xy 206.460084 -82.396123) (xy 206.332776 -82.282927) (xy 206.210912 -82.163888)
			(xy 206.094763 -82.039268) (xy 205.984582 -81.90934) (xy 205.880612 -81.774391) (xy 205.783082 -81.634717)
			(xy 205.692206 -81.490625) (xy 205.608184 -81.342431) (xy 205.531201 -81.190463) (xy 205.461425 -81.035053)
			(xy 205.39901 -80.876543) (xy 205.344093 -80.715282) (xy 205.296796 -80.551624) (xy 205.257221 -80.385929)
			(xy 205.225457 -80.218561) (xy 205.201572 -80.049889) (xy 205.18562 -79.880282) (xy 205.177635 -79.710114)
			(xy 150.923186 -79.710114) (xy 150.92274 -79.747548) (xy 150.914689 -79.831862) (xy 150.89866 -79.915028)
			(xy 150.874799 -79.996295) (xy 150.84332 -80.074925) (xy 150.804509 -80.150206) (xy 150.758719 -80.221458)
			(xy 150.706363 -80.288034) (xy 150.647915 -80.349332) (xy 150.583905 -80.404797) (xy 150.514913 -80.453926)
			(xy 150.441563 -80.496275) (xy 150.36452 -80.531459) (xy 150.284481 -80.559161) (xy 150.202172 -80.579129)
			(xy 150.118337 -80.591182) (xy 150.033736 -80.595213) (xy 149.949135 -80.591182) (xy 149.8653 -80.579129)
			(xy 149.782991 -80.559161) (xy 149.702952 -80.531459) (xy 149.625909 -80.496275) (xy 149.552559 -80.453926)
			(xy 149.483567 -80.404797) (xy 149.419557 -80.349332) (xy 149.361109 -80.288034) (xy 149.308753 -80.221458)
			(xy 149.262963 -80.150206) (xy 149.224152 -80.074925) (xy 149.192673 -79.996295) (xy 149.168812 -79.915028)
			(xy 149.152783 -79.831862) (xy 149.144732 -79.747548) (xy 149.144228 -79.7052) (xy 137.37463 -79.7052)
			(xy 137.37463 -79.89062) (xy 137.374124 -79.923881) (xy 137.365434 -79.989832) (xy 137.348207 -80.054084)
			(xy 137.322737 -80.115537) (xy 137.28946 -80.173137) (xy 137.248946 -80.225898) (xy 137.225786 -80.249776)
			(xy 136.598406 -80.877156) (xy 136.574543 -80.900332) (xy 136.521779 -80.940843) (xy 136.464175 -80.974115)
			(xy 136.40272 -80.99958) (xy 136.338465 -81.0168) (xy 136.272511 -81.025482) (xy 136.23925 -81.026)
			(xy 123.4694 -81.026) (xy 123.436141 -81.025461) (xy 123.370191 -81.016775) (xy 123.30594 -80.999553)
			(xy 123.244489 -80.974089) (xy 123.186888 -80.940818) (xy 123.134124 -80.900312) (xy 123.110244 -80.877156)
			(xy 122.475244 -80.242156) (xy 122.452092 -80.218271) (xy 122.411579 -80.165511) (xy 122.378303 -80.107912)
			(xy 122.352834 -80.046461) (xy 122.335609 -79.98221) (xy 122.326921 -79.91626) (xy 122.3264 -79.883)
			(xy 62.930237 -79.883) (xy 62.866209 -79.937386) (xy 62.777346 -80.002441) (xy 62.68402 -80.060913)
			(xy 62.586718 -80.1125) (xy 62.485947 -80.156931) (xy 62.382233 -80.193974) (xy 62.276116 -80.223437)
			(xy 62.16815 -80.245167) (xy 62.058897 -80.259049) (xy 61.948927 -80.265011) (xy 61.838814 -80.263023)
			(xy 61.729131 -80.253094) (xy 61.620451 -80.235277) (xy 61.51334 -80.209664) (xy 61.408356 -80.176389)
			(xy 61.306047 -80.135625) (xy 61.206946 -80.087585) (xy 61.111569 -80.03252) (xy 61.020415 -79.970715)
			(xy 60.933958 -79.902495) (xy 60.852649 -79.828214) (xy 60.776912 -79.748259) (xy 60.707141 -79.663048)
			(xy 60.643702 -79.573024) (xy 60.586923 -79.478657) (xy 60.537102 -79.38044) (xy 60.494498 -79.278883)
			(xy 60.459333 -79.174517) (xy 60.43179 -79.067886) (xy 60.412014 -78.959545) (xy 60.400106 -78.850059)
			(xy 60.396131 -78.74) (xy 43.888152 -78.74) (xy 43.887655 -78.795066) (xy 43.879708 -78.90491) (xy 43.863856 -79.013894)
			(xy 43.840181 -79.12145) (xy 43.808807 -79.227018) (xy 43.769897 -79.330046) (xy 43.723654 -79.429998)
			(xy 43.67032 -79.526353) (xy 43.610171 -79.618609) (xy 43.543523 -79.706283) (xy 43.470722 -79.78892)
			(xy 43.392147 -79.866088) (xy 43.308209 -79.937386) (xy 43.219346 -80.002441) (xy 43.12602 -80.060913)
			(xy 43.028718 -80.1125) (xy 42.927947 -80.156931) (xy 42.824233 -80.193974) (xy 42.718116 -80.223437)
			(xy 42.61015 -80.245167) (xy 42.500897 -80.259049) (xy 42.390927 -80.265011) (xy 42.280814 -80.263023)
			(xy 42.171131 -80.253094) (xy 42.062451 -80.235277) (xy 41.95534 -80.209664) (xy 41.850356 -80.176389)
			(xy 41.748047 -80.135625) (xy 41.648946 -80.087585) (xy 41.553569 -80.03252) (xy 41.462415 -79.970715)
			(xy 41.375958 -79.902495) (xy 41.294649 -79.828214) (xy 41.218912 -79.748259) (xy 41.149141 -79.663048)
			(xy 41.085702 -79.573024) (xy 41.028923 -79.478657) (xy 40.979102 -79.38044) (xy 40.936498 -79.278883)
			(xy 40.901333 -79.174517) (xy 40.87379 -79.067886) (xy 40.854014 -78.959545) (xy 40.842106 -78.850059)
			(xy 40.838131 -78.74) (xy 0.509016 -78.74) (xy 0.509016 -82.296) (xy 174.014896 -82.296) (xy 174.018924 -82.211447)
			(xy 174.03097 -82.12766) (xy 174.050927 -82.045398) (xy 174.078613 -81.965405) (xy 174.113777 -81.888406)
			(xy 174.156102 -81.815098) (xy 174.205203 -81.746145) (xy 174.260636 -81.682172) (xy 174.321899 -81.623758)
			(xy 174.388437 -81.571431) (xy 174.459648 -81.525667) (xy 174.534887 -81.486879) (xy 174.613472 -81.455418)
			(xy 174.694691 -81.43157) (xy 174.77781 -81.41555) (xy 174.862076 -81.407504) (xy 174.9044 -81.407)
			(xy 174.950803 -81.407598) (xy 175.043101 -81.417298) (xy 175.133886 -81.43656) (xy 175.222171 -81.465175)
			(xy 175.264826 -81.483454) (xy 175.266604 -81.484216) (xy 175.275737 -81.487398) (xy 175.295063 -81.487398)
			(xy 175.304196 -81.484216) (xy 175.305974 -81.483454) (xy 175.348636 -81.465192) (xy 175.436919 -81.436578)
			(xy 175.527702 -81.417316) (xy 175.619998 -81.407617) (xy 175.6664 -81.407) (xy 175.666654 -81.407)
			(xy 175.715422 -81.407677) (xy 175.812372 -81.418361) (xy 175.907567 -81.439606) (xy 175.953928 -81.454752)
			(xy 175.960648 -81.456851) (xy 175.974701 -81.457612) (xy 175.981614 -81.456276) (xy 175.985678 -81.45526)
			(xy 176.028801 -81.442312) (xy 176.117009 -81.424222) (xy 176.206594 -81.415151) (xy 176.251616 -81.41462)
			(xy 176.293257 -81.415101) (xy 176.376178 -81.422845) (xy 176.458014 -81.438302) (xy 176.538047 -81.461335)
			(xy 176.57699 -81.476088) (xy 176.586068 -81.479207) (xy 176.60525 -81.479207) (xy 176.614328 -81.476088)
			(xy 176.653265 -81.461315) (xy 176.733297 -81.43827) (xy 176.815135 -81.422813) (xy 176.898059 -81.415078)
			(xy 176.939702 -81.41462) (xy 176.962729 -81.414716) (xy 177.008727 -81.417002) (xy 177.03165 -81.419192)
			(xy 177.032158 -81.419192) (xy 177.04562 -81.418938) (xy 177.081557 -81.413372) (xy 177.154037 -81.407395)
			(xy 177.1904 -81.407) (xy 177.236803 -81.407598) (xy 177.329101 -81.417298) (xy 177.419886 -81.43656)
			(xy 177.508171 -81.465175) (xy 177.550826 -81.483454) (xy 177.552604 -81.484216) (xy 177.561737 -81.487398)
			(xy 177.581063 -81.487398) (xy 177.590196 -81.484216) (xy 177.591974 -81.483454) (xy 177.634636 -81.465192)
			(xy 177.722919 -81.436578) (xy 177.813702 -81.417316) (xy 177.905998 -81.407617) (xy 177.9524 -81.407)
			(xy 177.994724 -81.407504) (xy 178.07899 -81.41555) (xy 178.162109 -81.43157) (xy 178.243328 -81.455418)
			(xy 178.321913 -81.486879) (xy 178.397152 -81.525667) (xy 178.468363 -81.571431) (xy 178.534901 -81.623758)
			(xy 178.596164 -81.682172) (xy 178.651597 -81.746145) (xy 178.700698 -81.815098) (xy 178.743023 -81.888406)
			(xy 178.778187 -81.965405) (xy 178.805873 -82.045398) (xy 178.82583 -82.12766) (xy 178.837876 -82.211447)
			(xy 178.841904 -82.296) (xy 178.837876 -82.380553) (xy 178.82583 -82.46434) (xy 178.805873 -82.546602)
			(xy 178.778187 -82.626595) (xy 178.743023 -82.703594) (xy 178.700698 -82.776902) (xy 178.651597 -82.845855)
			(xy 178.596164 -82.909828) (xy 178.534901 -82.968242) (xy 178.468363 -83.020569) (xy 178.397152 -83.066333)
			(xy 178.321913 -83.105121) (xy 178.243328 -83.136582) (xy 178.162109 -83.16043) (xy 178.07899 -83.17645)
			(xy 177.994724 -83.184496) (xy 177.9524 -83.185) (xy 177.905997 -83.184402) (xy 177.813699 -83.174702)
			(xy 177.722914 -83.15544) (xy 177.634629 -83.126825) (xy 177.591974 -83.108546) (xy 177.590196 -83.107784)
			(xy 177.581063 -83.104602) (xy 177.561737 -83.104602) (xy 177.552604 -83.107784) (xy 177.550826 -83.108546)
			(xy 177.508164 -83.126808) (xy 177.419881 -83.155422) (xy 177.329098 -83.174684) (xy 177.236802 -83.184383)
			(xy 177.1904 -83.185) (xy 177.189638 -83.185) (xy 177.167821 -83.184863) (xy 177.12424 -83.182703)
			(xy 177.102516 -83.180682) (xy 177.089054 -83.18119) (xy 177.051996 -83.18706) (xy 176.97722 -83.193289)
			(xy 176.939702 -83.193636) (xy 176.89806 -83.193184) (xy 176.815138 -83.185432) (xy 176.733303 -83.169967)
			(xy 176.65327 -83.146926) (xy 176.614328 -83.132168) (xy 176.605259 -83.128992) (xy 176.586059 -83.128992)
			(xy 176.57699 -83.132168) (xy 176.538052 -83.146938) (xy 176.45802 -83.169983) (xy 176.376183 -83.185441)
			(xy 176.293258 -83.193177) (xy 176.251616 -83.193636) (xy 176.202451 -83.193015) (xy 176.104715 -83.182233)
			(xy 176.008766 -83.160732) (xy 175.962056 -83.145376) (xy 175.954369 -83.143042) (xy 175.938315 -83.142774)
			(xy 175.93056 -83.144868) (xy 175.8877 -83.157609) (xy 175.80008 -83.175465) (xy 175.71111 -83.184444)
			(xy 175.6664 -83.185) (xy 175.619997 -83.184402) (xy 175.527699 -83.174702) (xy 175.436914 -83.15544)
			(xy 175.348629 -83.126825) (xy 175.305974 -83.108546) (xy 175.304196 -83.107784) (xy 175.295063 -83.104602)
			(xy 175.275737 -83.104602) (xy 175.266604 -83.107784) (xy 175.264826 -83.108546) (xy 175.222164 -83.126808)
			(xy 175.133881 -83.155422) (xy 175.043098 -83.174684) (xy 174.950802 -83.184383) (xy 174.9044 -83.185)
			(xy 174.862076 -83.184496) (xy 174.77781 -83.17645) (xy 174.694691 -83.16043) (xy 174.613472 -83.136582)
			(xy 174.534887 -83.105121) (xy 174.459648 -83.066333) (xy 174.388437 -83.020569) (xy 174.321899 -82.968242)
			(xy 174.260636 -82.909828) (xy 174.205203 -82.845855) (xy 174.156102 -82.776902) (xy 174.113777 -82.703594)
			(xy 174.078613 -82.626595) (xy 174.050927 -82.546602) (xy 174.03097 -82.46434) (xy 174.018924 -82.380553)
			(xy 174.014896 -82.296) (xy 0.509016 -82.296) (xy 0.509016 -86.127279) (xy 159.685986 -86.127279)
			(xy 159.685986 -86.042557) (xy 159.694039 -85.95822) (xy 159.710073 -85.87503) (xy 159.733941 -85.79374)
			(xy 159.765429 -85.715088) (xy 159.804251 -85.639785) (xy 159.850054 -85.568513) (xy 159.902425 -85.501917)
			(xy 159.96089 -85.440602) (xy 160.024918 -85.385121) (xy 160.09393 -85.335978) (xy 160.1673 -85.293618)
			(xy 160.244365 -85.258423) (xy 160.324427 -85.230714) (xy 160.40676 -85.21074) (xy 160.490619 -85.198683)
			(xy 160.575244 -85.194652) (xy 160.659869 -85.198683) (xy 160.743728 -85.21074) (xy 160.826061 -85.230714)
			(xy 160.906123 -85.258423) (xy 160.983188 -85.293618) (xy 161.056558 -85.335978) (xy 161.12557 -85.385121)
			(xy 161.189598 -85.440602) (xy 161.248063 -85.501917) (xy 161.300434 -85.568513) (xy 161.346237 -85.639785)
			(xy 161.385059 -85.715088) (xy 161.416547 -85.79374) (xy 161.440415 -85.87503) (xy 161.456449 -85.95822)
			(xy 161.464502 -86.042557) (xy 161.465006 -86.084918) (xy 161.464502 -86.127279) (xy 161.456449 -86.211616)
			(xy 161.452327 -86.233) (xy 269.188188 -86.233) (xy 269.192218 -86.148399) (xy 269.204271 -86.064564)
			(xy 269.224239 -85.982255) (xy 269.251941 -85.902216) (xy 269.287125 -85.825173) (xy 269.329474 -85.751823)
			(xy 269.378603 -85.682831) (xy 269.434068 -85.618821) (xy 269.495366 -85.560373) (xy 269.561942 -85.508017)
			(xy 269.633194 -85.462227) (xy 269.708475 -85.423416) (xy 269.787105 -85.391937) (xy 269.868372 -85.368076)
			(xy 269.951538 -85.352047) (xy 270.035852 -85.343996) (xy 270.0782 -85.343492) (xy 270.078962 -85.343492)
			(xy 270.117182 -85.3439) (xy 270.193341 -85.350465) (xy 270.268653 -85.363549) (xy 270.342563 -85.383056)
			(xy 270.378682 -85.395562) (xy 270.386998 -85.398148) (xy 270.404402 -85.398148) (xy 270.412718 -85.395562)
			(xy 270.448841 -85.383071) (xy 270.522753 -85.363581) (xy 270.598064 -85.350497) (xy 270.674219 -85.343915)
			(xy 270.712438 -85.343492) (xy 270.7132 -85.343492) (xy 270.756684 -85.343995) (xy 270.843237 -85.35248)
			(xy 270.928548 -85.36937) (xy 271.011805 -85.394503) (xy 271.092212 -85.42764) (xy 271.169003 -85.468464)
			(xy 271.241444 -85.516586) (xy 271.308843 -85.571546) (xy 271.340072 -85.60181) (xy 271.340326 -85.602064)
			(xy 271.347704 -85.608646) (xy 271.366008 -85.616084) (xy 271.375886 -85.616542) (xy 271.447514 -85.616542)
			(xy 271.457395 -85.616108) (xy 271.475694 -85.608649) (xy 271.483074 -85.602064) (xy 271.483328 -85.60181)
			(xy 271.514554 -85.571545) (xy 271.581957 -85.51659) (xy 271.6544 -85.468474) (xy 271.731191 -85.427654)
			(xy 271.811598 -85.394521) (xy 271.894855 -85.36939) (xy 271.980165 -85.352502) (xy 272.066717 -85.344018)
			(xy 272.1102 -85.343492) (xy 272.110962 -85.343492) (xy 272.149182 -85.3439) (xy 272.225341 -85.350465)
			(xy 272.300653 -85.363549) (xy 272.374563 -85.383056) (xy 272.410682 -85.395562) (xy 272.418998 -85.398148)
			(xy 272.436402 -85.398148) (xy 272.444718 -85.395562) (xy 272.480841 -85.383071) (xy 272.554753 -85.363581)
			(xy 272.630064 -85.350497) (xy 272.706219 -85.343915) (xy 272.744438 -85.343492) (xy 272.7452 -85.343492)
			(xy 272.788684 -85.343995) (xy 272.875237 -85.35248) (xy 272.960548 -85.36937) (xy 273.043805 -85.394503)
			(xy 273.124212 -85.42764) (xy 273.201003 -85.468464) (xy 273.273444 -85.516586) (xy 273.340843 -85.571546)
			(xy 273.372072 -85.60181) (xy 273.372326 -85.602064) (xy 273.379704 -85.608646) (xy 273.398008 -85.616084)
			(xy 273.407886 -85.616542) (xy 273.479514 -85.616542) (xy 273.489395 -85.616108) (xy 273.507694 -85.608649)
			(xy 273.515074 -85.602064) (xy 273.515328 -85.60181) (xy 273.546554 -85.571545) (xy 273.613957 -85.51659)
			(xy 273.6864 -85.468474) (xy 273.763191 -85.427654) (xy 273.843598 -85.394521) (xy 273.926855 -85.36939)
			(xy 274.012165 -85.352502) (xy 274.098717 -85.344018) (xy 274.1422 -85.343492) (xy 274.142962 -85.343492)
			(xy 274.181182 -85.3439) (xy 274.257341 -85.350465) (xy 274.332653 -85.363549) (xy 274.406563 -85.383056)
			(xy 274.442682 -85.395562) (xy 274.450998 -85.398148) (xy 274.468402 -85.398148) (xy 274.476718 -85.395562)
			(xy 274.512841 -85.383071) (xy 274.586753 -85.363581) (xy 274.662064 -85.350497) (xy 274.738219 -85.343915)
			(xy 274.776438 -85.343492) (xy 274.7772 -85.343492) (xy 274.817247 -85.343907) (xy 274.897016 -85.351102)
			(xy 274.975816 -85.365436) (xy 275.05301 -85.38679) (xy 275.127973 -85.414994) (xy 275.2001 -85.449818)
			(xy 275.268805 -85.490982) (xy 275.333535 -85.538151) (xy 275.36394 -85.564218) (xy 275.371029 -85.569983)
			(xy 275.388086 -85.576495) (xy 275.397214 -85.576918) (xy 275.427186 -85.576918) (xy 275.436309 -85.576484)
			(xy 275.453359 -85.569964) (xy 275.46046 -85.564218) (xy 275.490874 -85.53816) (xy 275.555592 -85.490974)
			(xy 275.624292 -85.449798) (xy 275.696416 -85.414967) (xy 275.77138 -85.386763) (xy 275.848577 -85.365414)
			(xy 275.927381 -85.351094) (xy 276.007153 -85.343919) (xy 276.0472 -85.343492) (xy 276.047962 -85.343492)
			(xy 276.086182 -85.3439) (xy 276.162341 -85.350465) (xy 276.237653 -85.363549) (xy 276.311563 -85.383056)
			(xy 276.347682 -85.395562) (xy 276.355998 -85.398148) (xy 276.373402 -85.398148) (xy 276.381718 -85.395562)
			(xy 276.417841 -85.383071) (xy 276.491753 -85.363581) (xy 276.567064 -85.350497) (xy 276.643219 -85.343915)
			(xy 276.681438 -85.343492) (xy 276.6822 -85.343492) (xy 276.724548 -85.343996) (xy 276.808862 -85.352047)
			(xy 276.892028 -85.368076) (xy 276.973295 -85.391937) (xy 277.051925 -85.423416) (xy 277.127206 -85.462227)
			(xy 277.198458 -85.508017) (xy 277.265034 -85.560373) (xy 277.326332 -85.618821) (xy 277.381797 -85.682831)
			(xy 277.430926 -85.751823) (xy 277.473275 -85.825173) (xy 277.508459 -85.902216) (xy 277.536161 -85.982255)
			(xy 277.556129 -86.064564) (xy 277.568182 -86.148399) (xy 277.572213 -86.233) (xy 277.568182 -86.317601)
			(xy 277.556129 -86.401436) (xy 277.536161 -86.483745) (xy 277.508459 -86.563784) (xy 277.473275 -86.640827)
			(xy 277.430926 -86.714177) (xy 277.381797 -86.783169) (xy 277.326332 -86.847179) (xy 277.265034 -86.905627)
			(xy 277.198458 -86.957983) (xy 277.127206 -87.003773) (xy 277.051925 -87.042584) (xy 276.973295 -87.074063)
			(xy 276.892028 -87.097924) (xy 276.808862 -87.113953) (xy 276.724548 -87.122004) (xy 276.6822 -87.122508)
			(xy 276.681438 -87.122508) (xy 276.643218 -87.1221) (xy 276.567059 -87.115535) (xy 276.491747 -87.102451)
			(xy 276.417837 -87.082944) (xy 276.381718 -87.070438) (xy 276.373402 -87.067852) (xy 276.355998 -87.067852)
			(xy 276.347682 -87.070438) (xy 276.311559 -87.082929) (xy 276.237647 -87.102419) (xy 276.162336 -87.115503)
			(xy 276.086181 -87.122085) (xy 276.047962 -87.122508) (xy 276.0472 -87.122508) (xy 276.007153 -87.122093)
			(xy 275.927384 -87.114898) (xy 275.848584 -87.100564) (xy 275.77139 -87.07921) (xy 275.696427 -87.051006)
			(xy 275.6243 -87.016182) (xy 275.555595 -86.975018) (xy 275.490865 -86.927849) (xy 275.46046 -86.901782)
			(xy 275.453371 -86.896017) (xy 275.436314 -86.889505) (xy 275.427186 -86.889082) (xy 275.397214 -86.889082)
			(xy 275.388091 -86.889516) (xy 275.371041 -86.896036) (xy 275.36394 -86.901782) (xy 275.333526 -86.92784)
			(xy 275.268808 -86.975026) (xy 275.200108 -87.016202) (xy 275.127984 -87.051033) (xy 275.05302 -87.079237)
			(xy 274.975823 -87.100586) (xy 274.897019 -87.114906) (xy 274.817247 -87.122081) (xy 274.7772 -87.122508)
			(xy 274.776438 -87.122508) (xy 274.738218 -87.1221) (xy 274.662059 -87.115535) (xy 274.586747 -87.102451)
			(xy 274.512837 -87.082944) (xy 274.476718 -87.070438) (xy 274.468402 -87.067852) (xy 274.450998 -87.067852)
			(xy 274.442682 -87.070438) (xy 274.406559 -87.082929) (xy 274.332647 -87.102419) (xy 274.257336 -87.115503)
			(xy 274.181181 -87.122085) (xy 274.142962 -87.122508) (xy 274.1422 -87.122508) (xy 274.098716 -87.122005)
			(xy 274.012163 -87.11352) (xy 273.926852 -87.09663) (xy 273.843595 -87.071497) (xy 273.763188 -87.03836)
			(xy 273.686397 -86.997536) (xy 273.613956 -86.949414) (xy 273.546557 -86.894454) (xy 273.515328 -86.86419)
			(xy 273.515074 -86.863936) (xy 273.507696 -86.857354) (xy 273.489392 -86.849916) (xy 273.479514 -86.849458)
			(xy 273.407886 -86.849458) (xy 273.398005 -86.849892) (xy 273.379706 -86.857351) (xy 273.372326 -86.863936)
			(xy 273.372072 -86.86419) (xy 273.340846 -86.894455) (xy 273.273443 -86.94941) (xy 273.201 -86.997526)
			(xy 273.124209 -87.038346) (xy 273.043802 -87.071479) (xy 272.960545 -87.09661) (xy 272.875235 -87.113498)
			(xy 272.788683 -87.121982) (xy 272.7452 -87.122508) (xy 272.744438 -87.122508) (xy 272.706218 -87.1221)
			(xy 272.630059 -87.115535) (xy 272.554747 -87.102451) (xy 272.480837 -87.082944) (xy 272.444718 -87.070438)
			(xy 272.436402 -87.067852) (xy 272.418998 -87.067852) (xy 272.410682 -87.070438) (xy 272.374559 -87.082929)
			(xy 272.300647 -87.102419) (xy 272.225336 -87.115503) (xy 272.149181 -87.122085) (xy 272.110962 -87.122508)
			(xy 272.1102 -87.122508) (xy 272.066716 -87.122005) (xy 271.980163 -87.11352) (xy 271.894852 -87.09663)
			(xy 271.811595 -87.071497) (xy 271.731188 -87.03836) (xy 271.654397 -86.997536) (xy 271.581956 -86.949414)
			(xy 271.514557 -86.894454) (xy 271.483328 -86.86419) (xy 271.483074 -86.863936) (xy 271.475696 -86.857354)
			(xy 271.457392 -86.849916) (xy 271.447514 -86.849458) (xy 271.375886 -86.849458) (xy 271.366005 -86.849892)
			(xy 271.347706 -86.857351) (xy 271.340326 -86.863936) (xy 271.340072 -86.86419) (xy 271.308846 -86.894455)
			(xy 271.241443 -86.94941) (xy 271.169 -86.997526) (xy 271.092209 -87.038346) (xy 271.011802 -87.071479)
			(xy 270.928545 -87.09661) (xy 270.843235 -87.113498) (xy 270.756683 -87.121982) (xy 270.7132 -87.122508)
			(xy 270.712438 -87.122508) (xy 270.674218 -87.1221) (xy 270.598059 -87.115535) (xy 270.522747 -87.102451)
			(xy 270.448837 -87.082944) (xy 270.412718 -87.070438) (xy 270.404402 -87.067852) (xy 270.386998 -87.067852)
			(xy 270.378682 -87.070438) (xy 270.342559 -87.082929) (xy 270.268647 -87.102419) (xy 270.193336 -87.115503)
			(xy 270.117181 -87.122085) (xy 270.078962 -87.122508) (xy 270.0782 -87.122508) (xy 270.035852 -87.122004)
			(xy 269.951538 -87.113953) (xy 269.868372 -87.097924) (xy 269.787105 -87.074063) (xy 269.708475 -87.042584)
			(xy 269.633194 -87.003773) (xy 269.561942 -86.957983) (xy 269.495366 -86.905627) (xy 269.434068 -86.847179)
			(xy 269.378603 -86.783169) (xy 269.329474 -86.714177) (xy 269.287125 -86.640827) (xy 269.251941 -86.563784)
			(xy 269.224239 -86.483745) (xy 269.204271 -86.401436) (xy 269.192218 -86.317601) (xy 269.188188 -86.233)
			(xy 161.452327 -86.233) (xy 161.440415 -86.294806) (xy 161.416547 -86.376096) (xy 161.385059 -86.454748)
			(xy 161.346237 -86.530051) (xy 161.300434 -86.601323) (xy 161.248063 -86.667919) (xy 161.189598 -86.729234)
			(xy 161.12557 -86.784715) (xy 161.056558 -86.833858) (xy 160.983188 -86.876218) (xy 160.906123 -86.911413)
			(xy 160.826061 -86.939122) (xy 160.743728 -86.959096) (xy 160.659869 -86.971153) (xy 160.575244 -86.975185)
			(xy 160.490619 -86.971153) (xy 160.40676 -86.959096) (xy 160.324427 -86.939122) (xy 160.244365 -86.911413)
			(xy 160.1673 -86.876218) (xy 160.09393 -86.833858) (xy 160.024918 -86.784715) (xy 159.96089 -86.729234)
			(xy 159.902425 -86.667919) (xy 159.850054 -86.601323) (xy 159.804251 -86.530051) (xy 159.765429 -86.454748)
			(xy 159.733941 -86.376096) (xy 159.710073 -86.294806) (xy 159.694039 -86.211616) (xy 159.685986 -86.127279)
			(xy 0.509016 -86.127279) (xy 0.509016 -91.559888) (xy 41.345622 -91.559888) (xy 41.349604 -91.469938)
			(xy 41.361521 -91.380691) (xy 41.381279 -91.292847) (xy 41.408723 -91.207093) (xy 41.443639 -91.1241)
			(xy 41.485753 -91.044518) (xy 41.534736 -90.968969) (xy 41.590204 -90.898045) (xy 41.651724 -90.8323)
			(xy 41.718813 -90.77225) (xy 41.790947 -90.718365) (xy 41.867561 -90.671065) (xy 41.948055 -90.630722)
			(xy 42.0318 -90.59765) (xy 42.118141 -90.57211) (xy 42.2064 -90.5543) (xy 42.295889 -90.54436) (xy 42.385905 -90.542369)
			(xy 42.475746 -90.54834) (xy 42.564707 -90.562229) (xy 42.652092 -90.583925) (xy 42.737218 -90.61326)
			(xy 42.819418 -90.650003) (xy 42.898049 -90.693867) (xy 42.972496 -90.744509) (xy 43.042176 -90.801533)
			(xy 43.106543 -90.864492) (xy 43.165094 -90.932893) (xy 43.217371 -91.006201) (xy 43.262964 -91.083843)
			(xy 43.301517 -91.16521) (xy 43.332728 -91.249666) (xy 43.356352 -91.33655) (xy 43.372205 -91.425182)
			(xy 43.380162 -91.514869) (xy 43.38066 -91.559888) (xy 60.903622 -91.559888) (xy 60.907604 -91.469938)
			(xy 60.919521 -91.380691) (xy 60.939279 -91.292847) (xy 60.966723 -91.207093) (xy 61.001639 -91.1241)
			(xy 61.043753 -91.044518) (xy 61.092736 -90.968969) (xy 61.148204 -90.898045) (xy 61.209724 -90.8323)
			(xy 61.276813 -90.77225) (xy 61.348947 -90.718365) (xy 61.425561 -90.671065) (xy 61.506055 -90.630722)
			(xy 61.5898 -90.59765) (xy 61.676141 -90.57211) (xy 61.7644 -90.5543) (xy 61.853889 -90.54436) (xy 61.943905 -90.542369)
			(xy 62.033746 -90.54834) (xy 62.122707 -90.562229) (xy 62.210092 -90.583925) (xy 62.295218 -90.61326)
			(xy 62.377418 -90.650003) (xy 62.456049 -90.693867) (xy 62.530496 -90.744509) (xy 62.600176 -90.801533)
			(xy 62.664543 -90.864492) (xy 62.723094 -90.932893) (xy 62.775371 -91.006201) (xy 62.820964 -91.083843)
			(xy 62.859517 -91.16521) (xy 62.890728 -91.249666) (xy 62.914352 -91.33655) (xy 62.930205 -91.425182)
			(xy 62.938162 -91.514869) (xy 62.93866 -91.559888) (xy 377.061232 -91.559888) (xy 377.065214 -91.469938)
			(xy 377.077131 -91.380691) (xy 377.096889 -91.292847) (xy 377.124333 -91.207093) (xy 377.159249 -91.1241)
			(xy 377.201363 -91.044518) (xy 377.250346 -90.968969) (xy 377.305814 -90.898045) (xy 377.367334 -90.8323)
			(xy 377.434423 -90.77225) (xy 377.506557 -90.718365) (xy 377.583171 -90.671065) (xy 377.663665 -90.630722)
			(xy 377.74741 -90.59765) (xy 377.833751 -90.57211) (xy 377.92201 -90.5543) (xy 378.011499 -90.54436)
			(xy 378.101515 -90.542369) (xy 378.191356 -90.54834) (xy 378.280317 -90.562229) (xy 378.367702 -90.583925)
			(xy 378.452828 -90.61326) (xy 378.535028 -90.650003) (xy 378.613659 -90.693867) (xy 378.688106 -90.744509)
			(xy 378.757786 -90.801533) (xy 378.822153 -90.864492) (xy 378.880704 -90.932893) (xy 378.932981 -91.006201)
			(xy 378.978574 -91.083843) (xy 379.017127 -91.16521) (xy 379.048338 -91.249666) (xy 379.071962 -91.33655)
			(xy 379.087815 -91.425182) (xy 379.095772 -91.514869) (xy 379.09627 -91.559888) (xy 396.619232 -91.559888)
			(xy 396.623214 -91.469938) (xy 396.635131 -91.380691) (xy 396.654889 -91.292847) (xy 396.682333 -91.207093)
			(xy 396.717249 -91.1241) (xy 396.759363 -91.044518) (xy 396.808346 -90.968969) (xy 396.863814 -90.898045)
			(xy 396.925334 -90.8323) (xy 396.992423 -90.77225) (xy 397.064557 -90.718365) (xy 397.141171 -90.671065)
			(xy 397.221665 -90.630722) (xy 397.30541 -90.59765) (xy 397.391751 -90.57211) (xy 397.48001 -90.5543)
			(xy 397.569499 -90.54436) (xy 397.659515 -90.542369) (xy 397.749356 -90.54834) (xy 397.838317 -90.562229)
			(xy 397.925702 -90.583925) (xy 398.010828 -90.61326) (xy 398.093028 -90.650003) (xy 398.171659 -90.693867)
			(xy 398.246106 -90.744509) (xy 398.315786 -90.801533) (xy 398.380153 -90.864492) (xy 398.438704 -90.932893)
			(xy 398.490981 -91.006201) (xy 398.536574 -91.083843) (xy 398.575127 -91.16521) (xy 398.606338 -91.249666)
			(xy 398.629962 -91.33655) (xy 398.645815 -91.425182) (xy 398.653772 -91.514869) (xy 398.65416 -91.549982)
			(xy 470.018373 -91.549982) (xy 470.022363 -91.436999) (xy 470.034312 -91.324578) (xy 470.054162 -91.213281)
			(xy 470.081814 -91.103661) (xy 470.117128 -90.996264) (xy 470.159931 -90.891626) (xy 470.210008 -90.790268)
			(xy 470.26711 -90.692695) (xy 470.330952 -90.599393) (xy 470.401217 -90.510827) (xy 470.477554 -90.427437)
			(xy 470.559583 -90.34964) (xy 470.646896 -90.277823) (xy 470.739057 -90.212344) (xy 470.835607 -90.153529)
			(xy 470.936065 -90.101671) (xy 471.039932 -90.057029) (xy 471.146688 -90.019824) (xy 471.255803 -89.990242)
			(xy 471.366733 -89.968431) (xy 471.478925 -89.9545) (xy 471.59182 -89.948516) (xy 471.704856 -89.950512)
			(xy 471.81747 -89.960475) (xy 471.929101 -89.978358) (xy 472.039192 -90.00407) (xy 472.147195 -90.037484)
			(xy 472.252572 -90.078433) (xy 472.354798 -90.126714) (xy 472.453363 -90.182085) (xy 472.547778 -90.24427)
			(xy 472.63757 -90.312961) (xy 472.722294 -90.387815) (xy 472.801527 -90.468458) (xy 472.874873 -90.55449)
			(xy 472.941969 -90.645481) (xy 473.002478 -90.740978) (xy 473.056101 -90.840505) (xy 473.10257 -90.943568)
			(xy 473.141653 -91.049651) (xy 473.173156 -91.158227) (xy 473.196921 -91.268754) (xy 473.212831 -91.380683)
			(xy 473.220805 -91.493455) (xy 473.221304 -91.549982) (xy 473.220805 -91.606509) (xy 473.212831 -91.719281)
			(xy 473.196921 -91.83121) (xy 473.173156 -91.941737) (xy 473.141653 -92.050313) (xy 473.10257 -92.156396)
			(xy 473.056101 -92.259459) (xy 473.002478 -92.358986) (xy 472.941969 -92.454483) (xy 472.874873 -92.545474)
			(xy 472.801527 -92.631506) (xy 472.722294 -92.712149) (xy 472.63757 -92.787003) (xy 472.547778 -92.855694)
			(xy 472.453363 -92.917879) (xy 472.354798 -92.97325) (xy 472.252572 -93.021531) (xy 472.147195 -93.06248)
			(xy 472.039192 -93.095894) (xy 471.929101 -93.121606) (xy 471.81747 -93.139489) (xy 471.704856 -93.149452)
			(xy 471.59182 -93.151448) (xy 471.478925 -93.145464) (xy 471.366733 -93.131533) (xy 471.255803 -93.109722)
			(xy 471.146688 -93.08014) (xy 471.039932 -93.042935) (xy 470.936065 -92.998293) (xy 470.835607 -92.946435)
			(xy 470.739057 -92.88762) (xy 470.646896 -92.822141) (xy 470.559583 -92.750324) (xy 470.477554 -92.672527)
			(xy 470.401217 -92.589137) (xy 470.330952 -92.500571) (xy 470.26711 -92.407269) (xy 470.210008 -92.309696)
			(xy 470.159931 -92.208338) (xy 470.117128 -92.1037) (xy 470.081814 -91.996303) (xy 470.054162 -91.886683)
			(xy 470.034312 -91.775386) (xy 470.022363 -91.662965) (xy 470.018373 -91.549982) (xy 398.65416 -91.549982)
			(xy 398.65427 -91.559888) (xy 398.653772 -91.604907) (xy 398.645815 -91.694594) (xy 398.629962 -91.783226)
			(xy 398.606338 -91.87011) (xy 398.575127 -91.954566) (xy 398.536574 -92.035933) (xy 398.490981 -92.113575)
			(xy 398.438704 -92.186883) (xy 398.380153 -92.255284) (xy 398.315786 -92.318243) (xy 398.246106 -92.375267)
			(xy 398.171659 -92.425909) (xy 398.093028 -92.469773) (xy 398.010828 -92.506516) (xy 397.925702 -92.535851)
			(xy 397.838317 -92.557547) (xy 397.749356 -92.571436) (xy 397.659515 -92.577407) (xy 397.569499 -92.575416)
			(xy 397.48001 -92.565476) (xy 397.391751 -92.547666) (xy 397.30541 -92.522126) (xy 397.221665 -92.489054)
			(xy 397.141171 -92.448711) (xy 397.064557 -92.401411) (xy 396.992423 -92.347526) (xy 396.925334 -92.287476)
			(xy 396.863814 -92.221731) (xy 396.808346 -92.150807) (xy 396.759363 -92.075258) (xy 396.717249 -91.995676)
			(xy 396.682333 -91.912683) (xy 396.654889 -91.826929) (xy 396.635131 -91.739085) (xy 396.623214 -91.649838)
			(xy 396.619232 -91.559888) (xy 379.09627 -91.559888) (xy 379.095772 -91.604907) (xy 379.087815 -91.694594)
			(xy 379.071962 -91.783226) (xy 379.048338 -91.87011) (xy 379.017127 -91.954566) (xy 378.978574 -92.035933)
			(xy 378.932981 -92.113575) (xy 378.880704 -92.186883) (xy 378.822153 -92.255284) (xy 378.757786 -92.318243)
			(xy 378.688106 -92.375267) (xy 378.613659 -92.425909) (xy 378.535028 -92.469773) (xy 378.452828 -92.506516)
			(xy 378.367702 -92.535851) (xy 378.280317 -92.557547) (xy 378.191356 -92.571436) (xy 378.101515 -92.577407)
			(xy 378.011499 -92.575416) (xy 377.92201 -92.565476) (xy 377.833751 -92.547666) (xy 377.74741 -92.522126)
			(xy 377.663665 -92.489054) (xy 377.583171 -92.448711) (xy 377.506557 -92.401411) (xy 377.434423 -92.347526)
			(xy 377.367334 -92.287476) (xy 377.305814 -92.221731) (xy 377.250346 -92.150807) (xy 377.201363 -92.075258)
			(xy 377.159249 -91.995676) (xy 377.124333 -91.912683) (xy 377.096889 -91.826929) (xy 377.077131 -91.739085)
			(xy 377.065214 -91.649838) (xy 377.061232 -91.559888) (xy 62.93866 -91.559888) (xy 62.938162 -91.604907)
			(xy 62.930205 -91.694594) (xy 62.914352 -91.783226) (xy 62.890728 -91.87011) (xy 62.859517 -91.954566)
			(xy 62.820964 -92.035933) (xy 62.775371 -92.113575) (xy 62.723094 -92.186883) (xy 62.664543 -92.255284)
			(xy 62.600176 -92.318243) (xy 62.530496 -92.375267) (xy 62.456049 -92.425909) (xy 62.377418 -92.469773)
			(xy 62.295218 -92.506516) (xy 62.210092 -92.535851) (xy 62.122707 -92.557547) (xy 62.033746 -92.571436)
			(xy 61.943905 -92.577407) (xy 61.853889 -92.575416) (xy 61.7644 -92.565476) (xy 61.676141 -92.547666)
			(xy 61.5898 -92.522126) (xy 61.506055 -92.489054) (xy 61.425561 -92.448711) (xy 61.348947 -92.401411)
			(xy 61.276813 -92.347526) (xy 61.209724 -92.287476) (xy 61.148204 -92.221731) (xy 61.092736 -92.150807)
			(xy 61.043753 -92.075258) (xy 61.001639 -91.995676) (xy 60.966723 -91.912683) (xy 60.939279 -91.826929)
			(xy 60.919521 -91.739085) (xy 60.907604 -91.649838) (xy 60.903622 -91.559888) (xy 43.38066 -91.559888)
			(xy 43.380162 -91.604907) (xy 43.372205 -91.694594) (xy 43.356352 -91.783226) (xy 43.332728 -91.87011)
			(xy 43.301517 -91.954566) (xy 43.262964 -92.035933) (xy 43.217371 -92.113575) (xy 43.165094 -92.186883)
			(xy 43.106543 -92.255284) (xy 43.042176 -92.318243) (xy 42.972496 -92.375267) (xy 42.898049 -92.425909)
			(xy 42.819418 -92.469773) (xy 42.737218 -92.506516) (xy 42.652092 -92.535851) (xy 42.564707 -92.557547)
			(xy 42.475746 -92.571436) (xy 42.385905 -92.577407) (xy 42.295889 -92.575416) (xy 42.2064 -92.565476)
			(xy 42.118141 -92.547666) (xy 42.0318 -92.522126) (xy 41.948055 -92.489054) (xy 41.867561 -92.448711)
			(xy 41.790947 -92.401411) (xy 41.718813 -92.347526) (xy 41.651724 -92.287476) (xy 41.590204 -92.221731)
			(xy 41.534736 -92.150807) (xy 41.485753 -92.075258) (xy 41.443639 -91.995676) (xy 41.408723 -91.912683)
			(xy 41.381279 -91.826929) (xy 41.361521 -91.739085) (xy 41.349604 -91.649838) (xy 41.345622 -91.559888)
			(xy 0.509016 -91.559888) (xy 0.509016 -96.308361) (xy 157.479742 -96.308361) (xy 157.479742 -96.223639)
			(xy 157.487795 -96.139302) (xy 157.503829 -96.056112) (xy 157.527697 -95.974822) (xy 157.559185 -95.89617)
			(xy 157.598007 -95.820867) (xy 157.64381 -95.749595) (xy 157.696181 -95.682999) (xy 157.754646 -95.621684)
			(xy 157.818674 -95.566203) (xy 157.887686 -95.51706) (xy 157.961056 -95.4747) (xy 158.038121 -95.439505)
			(xy 158.118183 -95.411796) (xy 158.200516 -95.391822) (xy 158.284375 -95.379765) (xy 158.369 -95.375734)
			(xy 158.453625 -95.379765) (xy 158.537484 -95.391822) (xy 158.619817 -95.411796) (xy 158.699879 -95.439505)
			(xy 158.776944 -95.4747) (xy 158.850314 -95.51706) (xy 158.919326 -95.566203) (xy 158.983354 -95.621684)
			(xy 159.041819 -95.682999) (xy 159.09419 -95.749595) (xy 159.139993 -95.820867) (xy 159.178815 -95.89617)
			(xy 159.210303 -95.974822) (xy 159.234171 -96.056112) (xy 159.250205 -96.139302) (xy 159.258258 -96.223639)
			(xy 159.258762 -96.266) (xy 159.258258 -96.308361) (xy 159.250205 -96.392698) (xy 159.234171 -96.475888)
			(xy 159.210303 -96.557178) (xy 159.178815 -96.63583) (xy 159.139993 -96.711133) (xy 159.09419 -96.782405)
			(xy 159.041819 -96.849001) (xy 158.983354 -96.910316) (xy 158.919326 -96.965797) (xy 158.850314 -97.01494)
			(xy 158.776944 -97.0573) (xy 158.699879 -97.092495) (xy 158.619817 -97.120204) (xy 158.537484 -97.140178)
			(xy 158.453625 -97.152235) (xy 158.369 -97.156267) (xy 158.284375 -97.152235) (xy 158.200516 -97.140178)
			(xy 158.118183 -97.120204) (xy 158.038121 -97.092495) (xy 157.961056 -97.0573) (xy 157.887686 -97.01494)
			(xy 157.818674 -96.965797) (xy 157.754646 -96.910316) (xy 157.696181 -96.849001) (xy 157.64381 -96.782405)
			(xy 157.598007 -96.711133) (xy 157.559185 -96.63583) (xy 157.527697 -96.557178) (xy 157.503829 -96.475888)
			(xy 157.487795 -96.392698) (xy 157.479742 -96.308361) (xy 0.509016 -96.308361) (xy 0.509016 -99.06)
			(xy 40.838131 -99.06) (xy 40.842106 -98.949941) (xy 40.854014 -98.840455) (xy 40.87379 -98.732114)
			(xy 40.901333 -98.625483) (xy 40.936498 -98.521117) (xy 40.979102 -98.41956) (xy 41.028923 -98.321343)
			(xy 41.085702 -98.226976) (xy 41.149141 -98.136952) (xy 41.218912 -98.051741) (xy 41.294649 -97.971786)
			(xy 41.375958 -97.897505) (xy 41.462415 -97.829285) (xy 41.553569 -97.76748) (xy 41.648946 -97.712415)
			(xy 41.748047 -97.664375) (xy 41.850356 -97.623611) (xy 41.95534 -97.590336) (xy 42.062451 -97.564723)
			(xy 42.171131 -97.546906) (xy 42.280814 -97.536977) (xy 42.390927 -97.534989) (xy 42.500897 -97.540951)
			(xy 42.61015 -97.554833) (xy 42.718116 -97.576563) (xy 42.824233 -97.606026) (xy 42.927947 -97.643069)
			(xy 43.028718 -97.6875) (xy 43.12602 -97.739087) (xy 43.219346 -97.797559) (xy 43.308209 -97.862614)
			(xy 43.392147 -97.933912) (xy 43.470722 -98.01108) (xy 43.543523 -98.093717) (xy 43.610171 -98.181391)
			(xy 43.67032 -98.273647) (xy 43.723654 -98.370002) (xy 43.769897 -98.469954) (xy 43.808807 -98.572982)
			(xy 43.840181 -98.67855) (xy 43.863856 -98.786106) (xy 43.879708 -98.89509) (xy 43.887655 -99.004934)
			(xy 43.888152 -99.06) (xy 60.396131 -99.06) (xy 60.400106 -98.949941) (xy 60.412014 -98.840455) (xy 60.43179 -98.732114)
			(xy 60.459333 -98.625483) (xy 60.494498 -98.521117) (xy 60.537102 -98.41956) (xy 60.586923 -98.321343)
			(xy 60.643702 -98.226976) (xy 60.707141 -98.136952) (xy 60.776912 -98.051741) (xy 60.852649 -97.971786)
			(xy 60.933958 -97.897505) (xy 61.020415 -97.829285) (xy 61.111569 -97.76748) (xy 61.206946 -97.712415)
			(xy 61.306047 -97.664375) (xy 61.408356 -97.623611) (xy 61.51334 -97.590336) (xy 61.620451 -97.564723)
			(xy 61.729131 -97.546906) (xy 61.838814 -97.536977) (xy 61.948927 -97.534989) (xy 62.058897 -97.540951)
			(xy 62.16815 -97.554833) (xy 62.276116 -97.576563) (xy 62.382233 -97.606026) (xy 62.485947 -97.643069)
			(xy 62.586718 -97.6875) (xy 62.68402 -97.739087) (xy 62.777346 -97.797559) (xy 62.866209 -97.862614)
			(xy 62.950147 -97.933912) (xy 63.028722 -98.01108) (xy 63.101523 -98.093717) (xy 63.168171 -98.181391)
			(xy 63.22832 -98.273647) (xy 63.281654 -98.370002) (xy 63.327897 -98.469954) (xy 63.366807 -98.572982)
			(xy 63.398181 -98.67855) (xy 63.421856 -98.786106) (xy 63.437708 -98.89509) (xy 63.445655 -99.004934)
			(xy 63.446152 -99.06) (xy 376.553741 -99.06) (xy 376.557716 -98.949941) (xy 376.569624 -98.840455)
			(xy 376.5894 -98.732114) (xy 376.616943 -98.625483) (xy 376.652108 -98.521117) (xy 376.694712 -98.41956)
			(xy 376.744533 -98.321343) (xy 376.801312 -98.226976) (xy 376.864751 -98.136952) (xy 376.934522 -98.051741)
			(xy 377.010259 -97.971786) (xy 377.091568 -97.897505) (xy 377.178025 -97.829285) (xy 377.269179 -97.76748)
			(xy 377.364556 -97.712415) (xy 377.463657 -97.664375) (xy 377.565966 -97.623611) (xy 377.67095 -97.590336)
			(xy 377.778061 -97.564723) (xy 377.886741 -97.546906) (xy 377.996424 -97.536977) (xy 378.106537 -97.534989)
			(xy 378.216507 -97.540951) (xy 378.32576 -97.554833) (xy 378.433726 -97.576563) (xy 378.539843 -97.606026)
			(xy 378.643557 -97.643069) (xy 378.744328 -97.6875) (xy 378.84163 -97.739087) (xy 378.934956 -97.797559)
			(xy 379.023819 -97.862614) (xy 379.107757 -97.933912) (xy 379.186332 -98.01108) (xy 379.259133 -98.093717)
			(xy 379.325781 -98.181391) (xy 379.38593 -98.273647) (xy 379.439264 -98.370002) (xy 379.485507 -98.469954)
			(xy 379.524417 -98.572982) (xy 379.555791 -98.67855) (xy 379.579466 -98.786106) (xy 379.595318 -98.89509)
			(xy 379.603265 -99.004934) (xy 379.603762 -99.06) (xy 396.111741 -99.06) (xy 396.115716 -98.949941)
			(xy 396.127624 -98.840455) (xy 396.1474 -98.732114) (xy 396.174943 -98.625483) (xy 396.210108 -98.521117)
			(xy 396.252712 -98.41956) (xy 396.302533 -98.321343) (xy 396.359312 -98.226976) (xy 396.422751 -98.136952)
			(xy 396.492522 -98.051741) (xy 396.568259 -97.971786) (xy 396.649568 -97.897505) (xy 396.736025 -97.829285)
			(xy 396.827179 -97.76748) (xy 396.922556 -97.712415) (xy 397.021657 -97.664375) (xy 397.123966 -97.623611)
			(xy 397.22895 -97.590336) (xy 397.336061 -97.564723) (xy 397.444741 -97.546906) (xy 397.554424 -97.536977)
			(xy 397.664537 -97.534989) (xy 397.774507 -97.540951) (xy 397.88376 -97.554833) (xy 397.991726 -97.576563)
			(xy 398.097843 -97.606026) (xy 398.201557 -97.643069) (xy 398.302328 -97.6875) (xy 398.39963 -97.739087)
			(xy 398.492956 -97.797559) (xy 398.581819 -97.862614) (xy 398.665757 -97.933912) (xy 398.744332 -98.01108)
			(xy 398.817133 -98.093717) (xy 398.883781 -98.181391) (xy 398.94393 -98.273647) (xy 398.997264 -98.370002)
			(xy 399.043507 -98.469954) (xy 399.082417 -98.572982) (xy 399.113791 -98.67855) (xy 399.137466 -98.786106)
			(xy 399.153318 -98.89509) (xy 399.161265 -99.004934) (xy 399.161762 -99.06) (xy 399.161265 -99.115066)
			(xy 399.153318 -99.22491) (xy 399.137466 -99.333894) (xy 399.113791 -99.44145) (xy 399.082417 -99.547018)
			(xy 399.043507 -99.650046) (xy 398.997264 -99.749998) (xy 398.94393 -99.846353) (xy 398.883781 -99.938609)
			(xy 398.817133 -100.026283) (xy 398.744332 -100.10892) (xy 398.665757 -100.186088) (xy 398.581819 -100.257386)
			(xy 398.492956 -100.322441) (xy 398.39963 -100.380913) (xy 398.302328 -100.4325) (xy 398.201557 -100.476931)
			(xy 398.097843 -100.513974) (xy 397.991726 -100.543437) (xy 397.88376 -100.565167) (xy 397.774507 -100.579049)
			(xy 397.664537 -100.585011) (xy 397.554424 -100.583023) (xy 397.444741 -100.573094) (xy 397.336061 -100.555277)
			(xy 397.22895 -100.529664) (xy 397.123966 -100.496389) (xy 397.021657 -100.455625) (xy 396.922556 -100.407585)
			(xy 396.827179 -100.35252) (xy 396.736025 -100.290715) (xy 396.649568 -100.222495) (xy 396.568259 -100.148214)
			(xy 396.492522 -100.068259) (xy 396.422751 -99.983048) (xy 396.359312 -99.893024) (xy 396.302533 -99.798657)
			(xy 396.252712 -99.70044) (xy 396.210108 -99.598883) (xy 396.174943 -99.494517) (xy 396.1474 -99.387886)
			(xy 396.127624 -99.279545) (xy 396.115716 -99.170059) (xy 396.111741 -99.06) (xy 379.603762 -99.06)
			(xy 379.603265 -99.115066) (xy 379.595318 -99.22491) (xy 379.579466 -99.333894) (xy 379.555791 -99.44145)
			(xy 379.524417 -99.547018) (xy 379.485507 -99.650046) (xy 379.439264 -99.749998) (xy 379.38593 -99.846353)
			(xy 379.325781 -99.938609) (xy 379.259133 -100.026283) (xy 379.186332 -100.10892) (xy 379.107757 -100.186088)
			(xy 379.023819 -100.257386) (xy 378.934956 -100.322441) (xy 378.84163 -100.380913) (xy 378.744328 -100.4325)
			(xy 378.643557 -100.476931) (xy 378.539843 -100.513974) (xy 378.433726 -100.543437) (xy 378.32576 -100.565167)
			(xy 378.216507 -100.579049) (xy 378.106537 -100.585011) (xy 377.996424 -100.583023) (xy 377.886741 -100.573094)
			(xy 377.778061 -100.555277) (xy 377.67095 -100.529664) (xy 377.565966 -100.496389) (xy 377.463657 -100.455625)
			(xy 377.364556 -100.407585) (xy 377.269179 -100.35252) (xy 377.178025 -100.290715) (xy 377.091568 -100.222495)
			(xy 377.010259 -100.148214) (xy 376.934522 -100.068259) (xy 376.864751 -99.983048) (xy 376.801312 -99.893024)
			(xy 376.744533 -99.798657) (xy 376.694712 -99.70044) (xy 376.652108 -99.598883) (xy 376.616943 -99.494517)
			(xy 376.5894 -99.387886) (xy 376.569624 -99.279545) (xy 376.557716 -99.170059) (xy 376.553741 -99.06)
			(xy 63.446152 -99.06) (xy 63.445655 -99.115066) (xy 63.437708 -99.22491) (xy 63.421856 -99.333894)
			(xy 63.398181 -99.44145) (xy 63.366807 -99.547018) (xy 63.327897 -99.650046) (xy 63.281654 -99.749998)
			(xy 63.22832 -99.846353) (xy 63.168171 -99.938609) (xy 63.101523 -100.026283) (xy 63.028722 -100.10892)
			(xy 62.950147 -100.186088) (xy 62.866209 -100.257386) (xy 62.777346 -100.322441) (xy 62.68402 -100.380913)
			(xy 62.586718 -100.4325) (xy 62.485947 -100.476931) (xy 62.382233 -100.513974) (xy 62.276116 -100.543437)
			(xy 62.16815 -100.565167) (xy 62.058897 -100.579049) (xy 61.948927 -100.585011) (xy 61.838814 -100.583023)
			(xy 61.729131 -100.573094) (xy 61.620451 -100.555277) (xy 61.51334 -100.529664) (xy 61.408356 -100.496389)
			(xy 61.306047 -100.455625) (xy 61.206946 -100.407585) (xy 61.111569 -100.35252) (xy 61.020415 -100.290715)
			(xy 60.933958 -100.222495) (xy 60.852649 -100.148214) (xy 60.776912 -100.068259) (xy 60.707141 -99.983048)
			(xy 60.643702 -99.893024) (xy 60.586923 -99.798657) (xy 60.537102 -99.70044) (xy 60.494498 -99.598883)
			(xy 60.459333 -99.494517) (xy 60.43179 -99.387886) (xy 60.412014 -99.279545) (xy 60.400106 -99.170059)
			(xy 60.396131 -99.06) (xy 43.888152 -99.06) (xy 43.887655 -99.115066) (xy 43.879708 -99.22491) (xy 43.863856 -99.333894)
			(xy 43.840181 -99.44145) (xy 43.808807 -99.547018) (xy 43.769897 -99.650046) (xy 43.723654 -99.749998)
			(xy 43.67032 -99.846353) (xy 43.610171 -99.938609) (xy 43.543523 -100.026283) (xy 43.470722 -100.10892)
			(xy 43.392147 -100.186088) (xy 43.308209 -100.257386) (xy 43.219346 -100.322441) (xy 43.12602 -100.380913)
			(xy 43.028718 -100.4325) (xy 42.927947 -100.476931) (xy 42.824233 -100.513974) (xy 42.718116 -100.543437)
			(xy 42.61015 -100.565167) (xy 42.500897 -100.579049) (xy 42.390927 -100.585011) (xy 42.280814 -100.583023)
			(xy 42.171131 -100.573094) (xy 42.062451 -100.555277) (xy 41.95534 -100.529664) (xy 41.850356 -100.496389)
			(xy 41.748047 -100.455625) (xy 41.648946 -100.407585) (xy 41.553569 -100.35252) (xy 41.462415 -100.290715)
			(xy 41.375958 -100.222495) (xy 41.294649 -100.148214) (xy 41.218912 -100.068259) (xy 41.149141 -99.983048)
			(xy 41.085702 -99.893024) (xy 41.028923 -99.798657) (xy 40.979102 -99.70044) (xy 40.936498 -99.598883)
			(xy 40.901333 -99.494517) (xy 40.87379 -99.387886) (xy 40.854014 -99.279545) (xy 40.842106 -99.170059)
			(xy 40.838131 -99.06) (xy 0.509016 -99.06) (xy 0.509016 -104.544876) (xy 12.484104 -104.544876) (xy 12.488134 -104.402541)
			(xy 12.500209 -104.260661) (xy 12.520292 -104.119693) (xy 12.548319 -103.980086) (xy 12.584199 -103.842288)
			(xy 12.627817 -103.706741) (xy 12.679034 -103.573879) (xy 12.737685 -103.444127) (xy 12.803583 -103.317901)
			(xy 12.876517 -103.195605) (xy 12.956254 -103.077632) (xy 13.042536 -102.964359) (xy 13.135089 -102.856148)
			(xy 13.233616 -102.753347) (xy 13.337801 -102.656285) (xy 13.44731 -102.565273) (xy 13.561793 -102.480601)
			(xy 13.680883 -102.402543) (xy 13.804198 -102.331347) (xy 13.931344 -102.267241) (xy 14.061913 -102.210432)
			(xy 14.195487 -102.1611) (xy 14.331638 -102.119404) (xy 14.469929 -102.085478) (xy 14.609919 -102.05943)
			(xy 14.751158 -102.041344) (xy 14.893194 -102.031277) (xy 15.035572 -102.029262) (xy 15.177836 -102.035305)
			(xy 15.31953 -102.049387) (xy 15.4602 -102.071463) (xy 15.599397 -102.101463) (xy 15.736673 -102.139289)
			(xy 15.871589 -102.184821) (xy 16.003713 -102.237912) (xy 16.132622 -102.298394) (xy 16.257903 -102.366072)
			(xy 16.379154 -102.440729) (xy 16.495987 -102.522127) (xy 16.608028 -102.610004) (xy 16.714918 -102.704079)
			(xy 16.816315 -102.804051) (xy 16.911893 -102.909599) (xy 17.001347 -103.020385) (xy 17.084389 -103.136054)
			(xy 17.160755 -103.256237) (xy 17.230199 -103.380547) (xy 17.292499 -103.508588) (xy 17.347455 -103.639947)
			(xy 17.394892 -103.774206) (xy 17.434656 -103.910933) (xy 17.466622 -104.049691) (xy 17.490687 -104.190035)
			(xy 17.506773 -104.331516) (xy 17.514828 -104.47368) (xy 17.515332 -104.544876) (xy 17.514828 -104.616072)
			(xy 17.506773 -104.758236) (xy 17.490687 -104.899717) (xy 17.466622 -105.040061) (xy 17.434656 -105.178819)
			(xy 17.394892 -105.315546) (xy 17.347455 -105.449805) (xy 17.292499 -105.581164) (xy 17.230199 -105.709205)
			(xy 17.160755 -105.833515) (xy 17.084389 -105.953698) (xy 17.001347 -106.069367) (xy 16.911893 -106.180153)
			(xy 16.816315 -106.285701) (xy 16.714918 -106.385673) (xy 16.608028 -106.479748) (xy 16.495987 -106.567625)
			(xy 16.379154 -106.649023) (xy 16.257903 -106.72368) (xy 16.132622 -106.791358) (xy 16.003713 -106.85184)
			(xy 15.871589 -106.904931) (xy 15.736673 -106.950463) (xy 15.599397 -106.988289) (xy 15.4602 -107.018289)
			(xy 15.31953 -107.040365) (xy 15.177836 -107.054447) (xy 15.035572 -107.06049) (xy 14.893194 -107.058475)
			(xy 14.751158 -107.048408) (xy 14.609919 -107.030322) (xy 14.469929 -107.004274) (xy 14.331638 -106.970348)
			(xy 14.195487 -106.928652) (xy 14.061913 -106.87932) (xy 13.931344 -106.822511) (xy 13.804198 -106.758405)
			(xy 13.680883 -106.687209) (xy 13.561793 -106.609151) (xy 13.44731 -106.524479) (xy 13.337801 -106.433467)
			(xy 13.233616 -106.336405) (xy 13.135089 -106.233604) (xy 13.042536 -106.125393) (xy 12.956254 -106.01212)
			(xy 12.876517 -105.894147) (xy 12.803583 -105.771851) (xy 12.737685 -105.645625) (xy 12.679034 -105.515873)
			(xy 12.627817 -105.383011) (xy 12.584199 -105.247464) (xy 12.548319 -105.109666) (xy 12.520292 -104.970059)
			(xy 12.500209 -104.829091) (xy 12.488134 -104.687211) (xy 12.484104 -104.544876) (xy 0.509016 -104.544876)
			(xy 0.509016 -111.879888) (xy 41.345622 -111.879888) (xy 41.349604 -111.789938) (xy 41.361521 -111.700691)
			(xy 41.381279 -111.612847) (xy 41.408723 -111.527093) (xy 41.443639 -111.4441) (xy 41.485753 -111.364518)
			(xy 41.534736 -111.288969) (xy 41.590204 -111.218045) (xy 41.651724 -111.1523) (xy 41.718813 -111.09225)
			(xy 41.790947 -111.038365) (xy 41.867561 -110.991065) (xy 41.948055 -110.950722) (xy 42.0318 -110.91765)
			(xy 42.118141 -110.89211) (xy 42.2064 -110.8743) (xy 42.295889 -110.86436) (xy 42.385905 -110.862369)
			(xy 42.475746 -110.86834) (xy 42.564707 -110.882229) (xy 42.652092 -110.903925) (xy 42.737218 -110.93326)
			(xy 42.819418 -110.970003) (xy 42.898049 -111.013867) (xy 42.972496 -111.064509) (xy 43.042176 -111.121533)
			(xy 43.106543 -111.184492) (xy 43.165094 -111.252893) (xy 43.217371 -111.326201) (xy 43.262964 -111.403843)
			(xy 43.301517 -111.48521) (xy 43.332728 -111.569666) (xy 43.356352 -111.65655) (xy 43.372205 -111.745182)
			(xy 43.380162 -111.834869) (xy 43.38066 -111.879888) (xy 60.903622 -111.879888) (xy 60.907604 -111.789938)
			(xy 60.919521 -111.700691) (xy 60.939279 -111.612847) (xy 60.966723 -111.527093) (xy 61.001639 -111.4441)
			(xy 61.043753 -111.364518) (xy 61.092736 -111.288969) (xy 61.148204 -111.218045) (xy 61.209724 -111.1523)
			(xy 61.276813 -111.09225) (xy 61.348947 -111.038365) (xy 61.425561 -110.991065) (xy 61.506055 -110.950722)
			(xy 61.5898 -110.91765) (xy 61.676141 -110.89211) (xy 61.7644 -110.8743) (xy 61.853889 -110.86436)
			(xy 61.943905 -110.862369) (xy 62.033746 -110.86834) (xy 62.122707 -110.882229) (xy 62.210092 -110.903925)
			(xy 62.295218 -110.93326) (xy 62.377418 -110.970003) (xy 62.456049 -111.013867) (xy 62.530496 -111.064509)
			(xy 62.600176 -111.121533) (xy 62.664543 -111.184492) (xy 62.723094 -111.252893) (xy 62.775371 -111.326201)
			(xy 62.820964 -111.403843) (xy 62.859517 -111.48521) (xy 62.890728 -111.569666) (xy 62.914352 -111.65655)
			(xy 62.930205 -111.745182) (xy 62.938162 -111.834869) (xy 62.93866 -111.879888) (xy 62.938162 -111.924907)
			(xy 62.930205 -112.014594) (xy 62.914352 -112.103226) (xy 62.890728 -112.19011) (xy 62.859517 -112.274566)
			(xy 62.820964 -112.355933) (xy 62.775371 -112.433575) (xy 62.723094 -112.506883) (xy 62.664543 -112.575284)
			(xy 62.600176 -112.638243) (xy 62.530496 -112.695267) (xy 62.456049 -112.745909) (xy 62.377418 -112.789773)
			(xy 62.295218 -112.826516) (xy 62.210092 -112.855851) (xy 62.122707 -112.877547) (xy 62.033746 -112.891436)
			(xy 61.943905 -112.897407) (xy 61.853889 -112.895416) (xy 61.7644 -112.885476) (xy 61.676141 -112.867666)
			(xy 61.5898 -112.842126) (xy 61.506055 -112.809054) (xy 61.425561 -112.768711) (xy 61.348947 -112.721411)
			(xy 61.276813 -112.667526) (xy 61.209724 -112.607476) (xy 61.148204 -112.541731) (xy 61.092736 -112.470807)
			(xy 61.043753 -112.395258) (xy 61.001639 -112.315676) (xy 60.966723 -112.232683) (xy 60.939279 -112.146929)
			(xy 60.919521 -112.059085) (xy 60.907604 -111.969838) (xy 60.903622 -111.879888) (xy 43.38066 -111.879888)
			(xy 43.380162 -111.924907) (xy 43.372205 -112.014594) (xy 43.356352 -112.103226) (xy 43.332728 -112.19011)
			(xy 43.301517 -112.274566) (xy 43.262964 -112.355933) (xy 43.217371 -112.433575) (xy 43.165094 -112.506883)
			(xy 43.106543 -112.575284) (xy 43.042176 -112.638243) (xy 42.972496 -112.695267) (xy 42.898049 -112.745909)
			(xy 42.819418 -112.789773) (xy 42.737218 -112.826516) (xy 42.652092 -112.855851) (xy 42.564707 -112.877547)
			(xy 42.475746 -112.891436) (xy 42.385905 -112.897407) (xy 42.295889 -112.895416) (xy 42.2064 -112.885476)
			(xy 42.118141 -112.867666) (xy 42.0318 -112.842126) (xy 41.948055 -112.809054) (xy 41.867561 -112.768711)
			(xy 41.790947 -112.721411) (xy 41.718813 -112.667526) (xy 41.651724 -112.607476) (xy 41.590204 -112.541731)
			(xy 41.534736 -112.470807) (xy 41.485753 -112.395258) (xy 41.443639 -112.315676) (xy 41.408723 -112.232683)
			(xy 41.381279 -112.146929) (xy 41.361521 -112.059085) (xy 41.349604 -111.969838) (xy 41.345622 -111.879888)
			(xy 0.509016 -111.879888) (xy 0.509016 -119.38) (xy 40.838131 -119.38) (xy 40.842106 -119.269941)
			(xy 40.854014 -119.160455) (xy 40.87379 -119.052114) (xy 40.901333 -118.945483) (xy 40.936498 -118.841117)
			(xy 40.979102 -118.73956) (xy 41.028923 -118.641343) (xy 41.085702 -118.546976) (xy 41.149141 -118.456952)
			(xy 41.218912 -118.371741) (xy 41.294649 -118.291786) (xy 41.375958 -118.217505) (xy 41.462415 -118.149285)
			(xy 41.553569 -118.08748) (xy 41.648946 -118.032415) (xy 41.748047 -117.984375) (xy 41.850356 -117.943611)
			(xy 41.95534 -117.910336) (xy 42.062451 -117.884723) (xy 42.171131 -117.866906) (xy 42.280814 -117.856977)
			(xy 42.390927 -117.854989) (xy 42.500897 -117.860951) (xy 42.61015 -117.874833) (xy 42.718116 -117.896563)
			(xy 42.824233 -117.926026) (xy 42.927947 -117.963069) (xy 43.028718 -118.0075) (xy 43.12602 -118.059087)
			(xy 43.219346 -118.117559) (xy 43.308209 -118.182614) (xy 43.392147 -118.253912) (xy 43.470722 -118.33108)
			(xy 43.543523 -118.413717) (xy 43.610171 -118.501391) (xy 43.67032 -118.593647) (xy 43.723654 -118.690002)
			(xy 43.769897 -118.789954) (xy 43.808807 -118.892982) (xy 43.840181 -118.99855) (xy 43.863856 -119.106106)
			(xy 43.879708 -119.21509) (xy 43.887655 -119.324934) (xy 43.888152 -119.38) (xy 60.396131 -119.38)
			(xy 60.400106 -119.269941) (xy 60.412014 -119.160455) (xy 60.43179 -119.052114) (xy 60.459333 -118.945483)
			(xy 60.494498 -118.841117) (xy 60.537102 -118.73956) (xy 60.586923 -118.641343) (xy 60.643702 -118.546976)
			(xy 60.707141 -118.456952) (xy 60.776912 -118.371741) (xy 60.852649 -118.291786) (xy 60.933958 -118.217505)
			(xy 61.020415 -118.149285) (xy 61.111569 -118.08748) (xy 61.206946 -118.032415) (xy 61.306047 -117.984375)
			(xy 61.408356 -117.943611) (xy 61.51334 -117.910336) (xy 61.620451 -117.884723) (xy 61.729131 -117.866906)
			(xy 61.838814 -117.856977) (xy 61.948927 -117.854989) (xy 62.058897 -117.860951) (xy 62.16815 -117.874833)
			(xy 62.276116 -117.896563) (xy 62.382233 -117.926026) (xy 62.485947 -117.963069) (xy 62.586718 -118.0075)
			(xy 62.68402 -118.059087) (xy 62.777346 -118.117559) (xy 62.866209 -118.182614) (xy 62.950147 -118.253912)
			(xy 63.028722 -118.33108) (xy 63.101523 -118.413717) (xy 63.168171 -118.501391) (xy 63.22832 -118.593647)
			(xy 63.281654 -118.690002) (xy 63.327897 -118.789954) (xy 63.366807 -118.892982) (xy 63.398181 -118.99855)
			(xy 63.421856 -119.106106) (xy 63.437708 -119.21509) (xy 63.445655 -119.324934) (xy 63.446152 -119.38)
			(xy 63.445655 -119.435066) (xy 63.437708 -119.54491) (xy 63.421856 -119.653894) (xy 63.398181 -119.76145)
			(xy 63.366807 -119.867018) (xy 63.327897 -119.970046) (xy 63.281654 -120.069998) (xy 63.22832 -120.166353)
			(xy 63.168171 -120.258609) (xy 63.101523 -120.346283) (xy 63.028722 -120.42892) (xy 62.950147 -120.506088)
			(xy 62.866209 -120.577386) (xy 62.777346 -120.642441) (xy 62.68402 -120.700913) (xy 62.586718 -120.7525)
			(xy 62.485947 -120.796931) (xy 62.382233 -120.833974) (xy 62.276116 -120.863437) (xy 62.16815 -120.885167)
			(xy 62.058897 -120.899049) (xy 61.948927 -120.905011) (xy 61.838814 -120.903023) (xy 61.729131 -120.893094)
			(xy 61.620451 -120.875277) (xy 61.51334 -120.849664) (xy 61.408356 -120.816389) (xy 61.306047 -120.775625)
			(xy 61.206946 -120.727585) (xy 61.111569 -120.67252) (xy 61.020415 -120.610715) (xy 60.933958 -120.542495)
			(xy 60.852649 -120.468214) (xy 60.776912 -120.388259) (xy 60.707141 -120.303048) (xy 60.643702 -120.213024)
			(xy 60.586923 -120.118657) (xy 60.537102 -120.02044) (xy 60.494498 -119.918883) (xy 60.459333 -119.814517)
			(xy 60.43179 -119.707886) (xy 60.412014 -119.599545) (xy 60.400106 -119.490059) (xy 60.396131 -119.38)
			(xy 43.888152 -119.38) (xy 43.887655 -119.435066) (xy 43.879708 -119.54491) (xy 43.863856 -119.653894)
			(xy 43.840181 -119.76145) (xy 43.808807 -119.867018) (xy 43.769897 -119.970046) (xy 43.723654 -120.069998)
			(xy 43.67032 -120.166353) (xy 43.610171 -120.258609) (xy 43.543523 -120.346283) (xy 43.470722 -120.42892)
			(xy 43.392147 -120.506088) (xy 43.308209 -120.577386) (xy 43.219346 -120.642441) (xy 43.12602 -120.700913)
			(xy 43.028718 -120.7525) (xy 42.927947 -120.796931) (xy 42.824233 -120.833974) (xy 42.718116 -120.863437)
			(xy 42.61015 -120.885167) (xy 42.500897 -120.899049) (xy 42.390927 -120.905011) (xy 42.280814 -120.903023)
			(xy 42.171131 -120.893094) (xy 42.062451 -120.875277) (xy 41.95534 -120.849664) (xy 41.850356 -120.816389)
			(xy 41.748047 -120.775625) (xy 41.648946 -120.727585) (xy 41.553569 -120.67252) (xy 41.462415 -120.610715)
			(xy 41.375958 -120.542495) (xy 41.294649 -120.468214) (xy 41.218912 -120.388259) (xy 41.149141 -120.303048)
			(xy 41.085702 -120.213024) (xy 41.028923 -120.118657) (xy 40.979102 -120.02044) (xy 40.936498 -119.918883)
			(xy 40.901333 -119.814517) (xy 40.87379 -119.707886) (xy 40.854014 -119.599545) (xy 40.842106 -119.490059)
			(xy 40.838131 -119.38) (xy 0.509016 -119.38) (xy 0.509016 -132.199888) (xy 41.345622 -132.199888)
			(xy 41.349604 -132.109938) (xy 41.361521 -132.020691) (xy 41.381279 -131.932847) (xy 41.408723 -131.847093)
			(xy 41.443639 -131.7641) (xy 41.485753 -131.684518) (xy 41.534736 -131.608969) (xy 41.590204 -131.538045)
			(xy 41.651724 -131.4723) (xy 41.718813 -131.41225) (xy 41.790947 -131.358365) (xy 41.867561 -131.311065)
			(xy 41.948055 -131.270722) (xy 42.0318 -131.23765) (xy 42.118141 -131.21211) (xy 42.2064 -131.1943)
			(xy 42.295889 -131.18436) (xy 42.385905 -131.182369) (xy 42.475746 -131.18834) (xy 42.564707 -131.202229)
			(xy 42.652092 -131.223925) (xy 42.737218 -131.25326) (xy 42.819418 -131.290003) (xy 42.898049 -131.333867)
			(xy 42.972496 -131.384509) (xy 43.042176 -131.441533) (xy 43.106543 -131.504492) (xy 43.165094 -131.572893)
			(xy 43.217371 -131.646201) (xy 43.262964 -131.723843) (xy 43.301517 -131.80521) (xy 43.332728 -131.889666)
			(xy 43.356352 -131.97655) (xy 43.372205 -132.065182) (xy 43.380162 -132.154869) (xy 43.38066 -132.199888)
			(xy 60.903622 -132.199888) (xy 60.907604 -132.109938) (xy 60.919521 -132.020691) (xy 60.939279 -131.932847)
			(xy 60.966723 -131.847093) (xy 61.001639 -131.7641) (xy 61.043753 -131.684518) (xy 61.092736 -131.608969)
			(xy 61.148204 -131.538045) (xy 61.209724 -131.4723) (xy 61.276813 -131.41225) (xy 61.348947 -131.358365)
			(xy 61.425561 -131.311065) (xy 61.506055 -131.270722) (xy 61.5898 -131.23765) (xy 61.676141 -131.21211)
			(xy 61.7644 -131.1943) (xy 61.853889 -131.18436) (xy 61.943905 -131.182369) (xy 62.033746 -131.18834)
			(xy 62.122707 -131.202229) (xy 62.210092 -131.223925) (xy 62.295218 -131.25326) (xy 62.377418 -131.290003)
			(xy 62.456049 -131.333867) (xy 62.530496 -131.384509) (xy 62.600176 -131.441533) (xy 62.664543 -131.504492)
			(xy 62.723094 -131.572893) (xy 62.775371 -131.646201) (xy 62.820964 -131.723843) (xy 62.859517 -131.80521)
			(xy 62.890728 -131.889666) (xy 62.914352 -131.97655) (xy 62.930205 -132.065182) (xy 62.938162 -132.154869)
			(xy 62.93866 -132.199888) (xy 62.938162 -132.244907) (xy 62.930205 -132.334594) (xy 62.914352 -132.423226)
			(xy 62.890728 -132.51011) (xy 62.859517 -132.594566) (xy 62.820964 -132.675933) (xy 62.775371 -132.753575)
			(xy 62.723094 -132.826883) (xy 62.664543 -132.895284) (xy 62.600176 -132.958243) (xy 62.530496 -133.015267)
			(xy 62.456049 -133.065909) (xy 62.377418 -133.109773) (xy 62.295218 -133.146516) (xy 62.210092 -133.175851)
			(xy 62.122707 -133.197547) (xy 62.033746 -133.211436) (xy 61.943905 -133.217407) (xy 61.853889 -133.215416)
			(xy 61.7644 -133.205476) (xy 61.676141 -133.187666) (xy 61.5898 -133.162126) (xy 61.506055 -133.129054)
			(xy 61.425561 -133.088711) (xy 61.348947 -133.041411) (xy 61.276813 -132.987526) (xy 61.209724 -132.927476)
			(xy 61.148204 -132.861731) (xy 61.092736 -132.790807) (xy 61.043753 -132.715258) (xy 61.001639 -132.635676)
			(xy 60.966723 -132.552683) (xy 60.939279 -132.466929) (xy 60.919521 -132.379085) (xy 60.907604 -132.289838)
			(xy 60.903622 -132.199888) (xy 43.38066 -132.199888) (xy 43.380162 -132.244907) (xy 43.372205 -132.334594)
			(xy 43.356352 -132.423226) (xy 43.332728 -132.51011) (xy 43.301517 -132.594566) (xy 43.262964 -132.675933)
			(xy 43.217371 -132.753575) (xy 43.165094 -132.826883) (xy 43.106543 -132.895284) (xy 43.042176 -132.958243)
			(xy 42.972496 -133.015267) (xy 42.898049 -133.065909) (xy 42.819418 -133.109773) (xy 42.737218 -133.146516)
			(xy 42.652092 -133.175851) (xy 42.564707 -133.197547) (xy 42.475746 -133.211436) (xy 42.385905 -133.217407)
			(xy 42.295889 -133.215416) (xy 42.2064 -133.205476) (xy 42.118141 -133.187666) (xy 42.0318 -133.162126)
			(xy 41.948055 -133.129054) (xy 41.867561 -133.088711) (xy 41.790947 -133.041411) (xy 41.718813 -132.987526)
			(xy 41.651724 -132.927476) (xy 41.590204 -132.861731) (xy 41.534736 -132.790807) (xy 41.485753 -132.715258)
			(xy 41.443639 -132.635676) (xy 41.408723 -132.552683) (xy 41.381279 -132.466929) (xy 41.361521 -132.379085)
			(xy 41.349604 -132.289838) (xy 41.345622 -132.199888) (xy 0.509016 -132.199888) (xy 0.509016 -139.7)
			(xy 40.838131 -139.7) (xy 40.842106 -139.589941) (xy 40.854014 -139.480455) (xy 40.87379 -139.372114)
			(xy 40.901333 -139.265483) (xy 40.936498 -139.161117) (xy 40.979102 -139.05956) (xy 41.028923 -138.961343)
			(xy 41.085702 -138.866976) (xy 41.149141 -138.776952) (xy 41.218912 -138.691741) (xy 41.294649 -138.611786)
			(xy 41.375958 -138.537505) (xy 41.462415 -138.469285) (xy 41.553569 -138.40748) (xy 41.648946 -138.352415)
			(xy 41.748047 -138.304375) (xy 41.850356 -138.263611) (xy 41.95534 -138.230336) (xy 42.062451 -138.204723)
			(xy 42.171131 -138.186906) (xy 42.280814 -138.176977) (xy 42.390927 -138.174989) (xy 42.500897 -138.180951)
			(xy 42.61015 -138.194833) (xy 42.718116 -138.216563) (xy 42.824233 -138.246026) (xy 42.927947 -138.283069)
			(xy 43.028718 -138.3275) (xy 43.12602 -138.379087) (xy 43.219346 -138.437559) (xy 43.308209 -138.502614)
			(xy 43.392147 -138.573912) (xy 43.470722 -138.65108) (xy 43.543523 -138.733717) (xy 43.610171 -138.821391)
			(xy 43.67032 -138.913647) (xy 43.723654 -139.010002) (xy 43.769897 -139.109954) (xy 43.808807 -139.212982)
			(xy 43.840181 -139.31855) (xy 43.863856 -139.426106) (xy 43.879708 -139.53509) (xy 43.887655 -139.644934)
			(xy 43.888152 -139.7) (xy 60.396131 -139.7) (xy 60.400106 -139.589941) (xy 60.412014 -139.480455)
			(xy 60.43179 -139.372114) (xy 60.459333 -139.265483) (xy 60.494498 -139.161117) (xy 60.537102 -139.05956)
			(xy 60.586923 -138.961343) (xy 60.643702 -138.866976) (xy 60.707141 -138.776952) (xy 60.776912 -138.691741)
			(xy 60.852649 -138.611786) (xy 60.933958 -138.537505) (xy 61.020415 -138.469285) (xy 61.111569 -138.40748)
			(xy 61.206946 -138.352415) (xy 61.306047 -138.304375) (xy 61.408356 -138.263611) (xy 61.51334 -138.230336)
			(xy 61.620451 -138.204723) (xy 61.729131 -138.186906) (xy 61.838814 -138.176977) (xy 61.948927 -138.174989)
			(xy 62.058897 -138.180951) (xy 62.16815 -138.194833) (xy 62.276116 -138.216563) (xy 62.382233 -138.246026)
			(xy 62.485947 -138.283069) (xy 62.586718 -138.3275) (xy 62.68402 -138.379087) (xy 62.777346 -138.437559)
			(xy 62.866209 -138.502614) (xy 62.950147 -138.573912) (xy 63.028722 -138.65108) (xy 63.101523 -138.733717)
			(xy 63.168171 -138.821391) (xy 63.22832 -138.913647) (xy 63.281654 -139.010002) (xy 63.327897 -139.109954)
			(xy 63.366807 -139.212982) (xy 63.398181 -139.31855) (xy 63.421856 -139.426106) (xy 63.437708 -139.53509)
			(xy 63.445655 -139.644934) (xy 63.446152 -139.7) (xy 63.445655 -139.755066) (xy 63.437708 -139.86491)
			(xy 63.421856 -139.973894) (xy 63.398181 -140.08145) (xy 63.366807 -140.187018) (xy 63.327897 -140.290046)
			(xy 63.281654 -140.389998) (xy 63.22832 -140.486353) (xy 63.168171 -140.578609) (xy 63.101523 -140.666283)
			(xy 63.028722 -140.74892) (xy 62.950147 -140.826088) (xy 62.866209 -140.897386) (xy 62.777346 -140.962441)
			(xy 62.68402 -141.020913) (xy 62.586718 -141.0725) (xy 62.485947 -141.116931) (xy 62.382233 -141.153974)
			(xy 62.276116 -141.183437) (xy 62.16815 -141.205167) (xy 62.058897 -141.219049) (xy 61.948927 -141.225011)
			(xy 61.838814 -141.223023) (xy 61.729131 -141.213094) (xy 61.620451 -141.195277) (xy 61.51334 -141.169664)
			(xy 61.408356 -141.136389) (xy 61.306047 -141.095625) (xy 61.206946 -141.047585) (xy 61.111569 -140.99252)
			(xy 61.020415 -140.930715) (xy 60.933958 -140.862495) (xy 60.852649 -140.788214) (xy 60.776912 -140.708259)
			(xy 60.707141 -140.623048) (xy 60.643702 -140.533024) (xy 60.586923 -140.438657) (xy 60.537102 -140.34044)
			(xy 60.494498 -140.238883) (xy 60.459333 -140.134517) (xy 60.43179 -140.027886) (xy 60.412014 -139.919545)
			(xy 60.400106 -139.810059) (xy 60.396131 -139.7) (xy 43.888152 -139.7) (xy 43.887655 -139.755066)
			(xy 43.879708 -139.86491) (xy 43.863856 -139.973894) (xy 43.840181 -140.08145) (xy 43.808807 -140.187018)
			(xy 43.769897 -140.290046) (xy 43.723654 -140.389998) (xy 43.67032 -140.486353) (xy 43.610171 -140.578609)
			(xy 43.543523 -140.666283) (xy 43.470722 -140.74892) (xy 43.392147 -140.826088) (xy 43.308209 -140.897386)
			(xy 43.219346 -140.962441) (xy 43.12602 -141.020913) (xy 43.028718 -141.0725) (xy 42.927947 -141.116931)
			(xy 42.824233 -141.153974) (xy 42.718116 -141.183437) (xy 42.61015 -141.205167) (xy 42.500897 -141.219049)
			(xy 42.390927 -141.225011) (xy 42.280814 -141.223023) (xy 42.171131 -141.213094) (xy 42.062451 -141.195277)
			(xy 41.95534 -141.169664) (xy 41.850356 -141.136389) (xy 41.748047 -141.095625) (xy 41.648946 -141.047585)
			(xy 41.553569 -140.99252) (xy 41.462415 -140.930715) (xy 41.375958 -140.862495) (xy 41.294649 -140.788214)
			(xy 41.218912 -140.708259) (xy 41.149141 -140.623048) (xy 41.085702 -140.533024) (xy 41.028923 -140.438657)
			(xy 40.979102 -140.34044) (xy 40.936498 -140.238883) (xy 40.901333 -140.134517) (xy 40.87379 -140.027886)
			(xy 40.854014 -139.919545) (xy 40.842106 -139.810059) (xy 40.838131 -139.7) (xy 0.509016 -139.7)
			(xy 0.509016 -153.299922) (xy 0.509522 -153.395255) (xy 0.517614 -153.58575) (xy 0.533784 -153.77573)
			(xy 0.558002 -153.964852) (xy 0.590225 -154.152777) (xy 0.630395 -154.339164) (xy 0.678438 -154.523678)
			(xy 0.73427 -154.705987) (xy 0.797789 -154.885763) (xy 0.86888 -155.06268) (xy 0.947416 -155.236421)
			(xy 1.033255 -155.406672) (xy 1.126242 -155.573127) (xy 1.22621 -155.735485) (xy 1.332979 -155.893455)
			(xy 1.446356 -156.04675) (xy 1.566136 -156.195096) (xy 1.692105 -156.338224) (xy 1.824035 -156.475877)
			(xy 1.961688 -156.607806) (xy 2.104816 -156.733775) (xy 2.253162 -156.853556) (xy 2.406457 -156.966932)
			(xy 2.564426 -157.073701) (xy 2.726785 -157.173669) (xy 2.893239 -157.266656) (xy 3.063491 -157.352495)
			(xy 3.237232 -157.431031) (xy 3.414149 -157.502122) (xy 3.593924 -157.565641) (xy 3.776234 -157.621472)
			(xy 3.960748 -157.669516) (xy 4.147135 -157.709685) (xy 4.335059 -157.741908) (xy 4.524182 -157.766126)
			(xy 4.714162 -157.782296) (xy 4.904657 -157.790388) (xy 4.99999 -157.790896) (xy 25.999948 -157.790896)
			(xy 26.105482 -157.791395) (xy 26.316396 -157.79948) (xy 26.526845 -157.815637) (xy 26.73652 -157.839843)
			(xy 26.945115 -157.872062) (xy 27.152323 -157.912248) (xy 27.357839 -157.96034) (xy 27.561362 -158.016269)
			(xy 27.762594 -158.079953) (xy 27.961239 -158.151298) (xy 28.157005 -158.230198) (xy 28.349606 -158.31654)
			(xy 28.538758 -158.410195) (xy 28.724184 -158.511027) (xy 28.905612 -158.618886) (xy 29.082776 -158.733616)
			(xy 29.255415 -158.855048) (xy 29.423276 -158.983003) (xy 29.586113 -159.117293) (xy 29.743686 -159.257723)
			(xy 29.895766 -159.404084) (xy 30.042127 -159.556164) (xy 30.182557 -159.713737) (xy 30.316847 -159.876574)
			(xy 30.444802 -160.044435) (xy 30.566234 -160.217074) (xy 30.680964 -160.394238) (xy 30.788823 -160.575666)
			(xy 30.889655 -160.761092) (xy 30.98331 -160.950244) (xy 31.069652 -161.142845) (xy 31.148552 -161.338611)
			(xy 31.219897 -161.537256) (xy 31.283581 -161.738488) (xy 31.33951 -161.942011) (xy 31.387602 -162.147527)
			(xy 31.427788 -162.354735) (xy 31.460007 -162.56333) (xy 31.484213 -162.773005) (xy 31.50037 -162.983454)
			(xy 31.508455 -163.194368) (xy 31.508954 -163.299902) (xy 31.508954 -166.649908) (xy 31.50946 -166.745241)
			(xy 31.517552 -166.935736) (xy 31.533721 -167.125716) (xy 31.557939 -167.314839) (xy 31.590162 -167.502763)
			(xy 31.630332 -167.689151) (xy 31.678375 -167.873665) (xy 31.734207 -168.055975) (xy 31.797726 -168.23575)
			(xy 31.868817 -168.412668) (xy 31.947353 -168.586409) (xy 32.033192 -168.75666) (xy 32.074156 -168.82999)
			(xy 33.661096 -168.82999) (xy 33.661535 -168.782327) (xy 33.669022 -168.687296) (xy 33.683942 -168.593144)
			(xy 33.706203 -168.500454) (xy 33.735667 -168.409796) (xy 33.772152 -168.321729) (xy 33.815435 -168.236795)
			(xy 33.865248 -168.15552) (xy 33.921283 -168.078402) (xy 33.983196 -168.005919) (xy 34.050605 -167.938517)
			(xy 34.086546 -167.907208) (xy 34.094571 -167.899638) (xy 34.103786 -167.879619) (xy 34.104326 -167.8686)
			(xy 34.104326 -167.791384) (xy 34.103789 -167.780365) (xy 34.094568 -167.760349) (xy 34.086546 -167.752776)
			(xy 34.050612 -167.721463) (xy 33.983218 -167.654051) (xy 33.921318 -167.581561) (xy 33.865293 -167.504441)
			(xy 33.815489 -167.423164) (xy 33.772212 -167.338232) (xy 33.735729 -167.250168) (xy 33.706265 -167.159514)
			(xy 33.684 -167.066828) (xy 33.669073 -166.972682) (xy 33.661575 -166.877655) (xy 33.661096 -166.829994)
			(xy 33.661537 -166.782331) (xy 33.669025 -166.6873) (xy 33.683944 -166.593149) (xy 33.706205 -166.500458)
			(xy 33.735668 -166.4098) (xy 33.772154 -166.321733) (xy 33.815436 -166.2368) (xy 33.865249 -166.155524)
			(xy 33.921284 -166.078407) (xy 33.983197 -166.005923) (xy 34.050605 -165.938521) (xy 34.086546 -165.907212)
			(xy 34.094569 -165.89964) (xy 34.103786 -165.879623) (xy 34.104326 -165.868604) (xy 34.104326 -165.791388)
			(xy 34.103786 -165.78037) (xy 34.094567 -165.760354) (xy 34.086546 -165.75278) (xy 34.050614 -165.721464)
			(xy 33.98322 -165.654053) (xy 33.92132 -165.581563) (xy 33.865295 -165.504443) (xy 33.815491 -165.423167)
			(xy 33.772214 -165.338235) (xy 33.735731 -165.250171) (xy 33.706266 -165.159517) (xy 33.684001 -165.066832)
			(xy 33.669073 -164.972686) (xy 33.661575 -164.877659) (xy 33.661096 -164.829998) (xy 33.66154 -164.782335)
			(xy 33.669027 -164.687304) (xy 33.683947 -164.593153) (xy 33.706207 -164.500463) (xy 33.73567 -164.409804)
			(xy 33.772155 -164.321737) (xy 33.815437 -164.236804) (xy 33.865249 -164.155528) (xy 33.921284 -164.078411)
			(xy 33.983197 -164.005927) (xy 34.050606 -163.938525) (xy 34.086546 -163.907216) (xy 34.094567 -163.899643)
			(xy 34.103785 -163.879626) (xy 34.104326 -163.868608) (xy 34.104326 -163.791392) (xy 34.103784 -163.780374)
			(xy 34.094567 -163.760358) (xy 34.086546 -163.752784) (xy 34.050616 -163.721466) (xy 33.983221 -163.654055)
			(xy 33.921321 -163.581566) (xy 33.865297 -163.504446) (xy 33.815492 -163.42317) (xy 33.772215 -163.338238)
			(xy 33.735732 -163.250174) (xy 33.706267 -163.15952) (xy 33.684002 -163.066835) (xy 33.669074 -162.972689)
			(xy 33.661575 -162.877663) (xy 33.661096 -162.830002) (xy 33.661543 -162.782339) (xy 33.66903 -162.687308)
			(xy 33.683949 -162.593157) (xy 33.706209 -162.500467) (xy 33.735672 -162.409809) (xy 33.772157 -162.321741)
			(xy 33.815438 -162.236808) (xy 33.86525 -162.155532) (xy 33.921285 -162.078415) (xy 33.983197 -162.005932)
			(xy 34.050606 -161.938529) (xy 34.086546 -161.90722) (xy 34.094565 -161.899645) (xy 34.103784 -161.87963)
			(xy 34.104326 -161.868612) (xy 34.104326 -161.791396) (xy 34.103782 -161.780378) (xy 34.094566 -161.760362)
			(xy 34.086546 -161.752788) (xy 34.050618 -161.721468) (xy 33.983223 -161.654057) (xy 33.921323 -161.581568)
			(xy 33.865298 -161.504448) (xy 33.815494 -161.423172) (xy 33.772217 -161.338241) (xy 33.735733 -161.250177)
			(xy 33.706268 -161.159524) (xy 33.684002 -161.066839) (xy 33.669074 -160.972693) (xy 33.661575 -160.877667)
			(xy 33.661096 -160.830006) (xy 33.661546 -160.782343) (xy 33.669032 -160.687312) (xy 33.683951 -160.593161)
			(xy 33.70621 -160.500471) (xy 33.735673 -160.409813) (xy 33.772158 -160.321746) (xy 33.815439 -160.236812)
			(xy 33.865251 -160.155537) (xy 33.921286 -160.078419) (xy 33.983198 -160.005936) (xy 34.050606 -159.938533)
			(xy 34.086546 -159.907224) (xy 34.094563 -159.899647) (xy 34.103783 -159.879633) (xy 34.104326 -159.868616)
			(xy 34.104326 -159.7914) (xy 34.10378 -159.780382) (xy 34.094565 -159.760366) (xy 34.086546 -159.752792)
			(xy 34.05062 -159.72147) (xy 33.983225 -159.654059) (xy 33.921325 -159.58157) (xy 33.8653 -159.504451)
			(xy 33.815495 -159.423175) (xy 33.772218 -159.338244) (xy 33.735734 -159.250181) (xy 33.706269 -159.159527)
			(xy 33.684003 -159.066842) (xy 33.669075 -158.972697) (xy 33.661575 -158.877671) (xy 33.661096 -158.83001)
			(xy 33.661549 -158.782347) (xy 33.669035 -158.687316) (xy 33.683953 -158.593165) (xy 33.706212 -158.500475)
			(xy 33.735675 -158.409817) (xy 33.772159 -158.32175) (xy 33.815441 -158.236817) (xy 33.865252 -158.155541)
			(xy 33.921286 -158.078423) (xy 33.983198 -158.00594) (xy 34.050606 -157.938537) (xy 34.086546 -157.907228)
			(xy 34.094562 -157.89965) (xy 34.103782 -157.879637) (xy 34.104326 -157.86862) (xy 34.104326 -157.791404)
			(xy 34.103778 -157.780387) (xy 34.094565 -157.76037) (xy 34.086546 -157.752796) (xy 34.050621 -157.721472)
			(xy 33.983227 -157.654061) (xy 33.921327 -157.581573) (xy 33.865302 -157.504453) (xy 33.815497 -157.423178)
			(xy 33.772219 -157.338247) (xy 33.735735 -157.250184) (xy 33.70627 -157.159531) (xy 33.684004 -157.066846)
			(xy 33.669075 -156.972701) (xy 33.661575 -156.877675) (xy 33.661096 -156.830014) (xy 33.661552 -156.782351)
			(xy 33.669037 -156.68732) (xy 33.683956 -156.59317) (xy 33.706214 -156.50048) (xy 33.735677 -156.409821)
			(xy 33.772161 -156.321754) (xy 33.815442 -156.236821) (xy 33.865253 -156.155545) (xy 33.921287 -156.078428)
			(xy 33.983198 -156.005944) (xy 34.050606 -155.938541) (xy 34.086546 -155.907232) (xy 34.09456 -155.899652)
			(xy 34.103782 -155.879641) (xy 34.104326 -155.868624) (xy 34.104326 -155.791408) (xy 34.103776 -155.780391)
			(xy 34.094564 -155.760375) (xy 34.086546 -155.7528) (xy 34.050623 -155.721473) (xy 33.983229 -155.654063)
			(xy 33.921329 -155.581575) (xy 33.865303 -155.504456) (xy 33.815499 -155.423181) (xy 33.772221 -155.33825)
			(xy 33.735736 -155.250187) (xy 33.706271 -155.159534) (xy 33.684005 -155.06685) (xy 33.669076 -154.972705)
			(xy 33.661575 -154.877679) (xy 33.661096 -154.830018) (xy 33.661555 -154.782355) (xy 33.66904 -154.687325)
			(xy 33.683958 -154.593174) (xy 33.706216 -154.500484) (xy 33.735678 -154.409826) (xy 33.772162 -154.321759)
			(xy 33.815443 -154.236825) (xy 33.865254 -154.155549) (xy 33.921287 -154.078432) (xy 33.983199 -154.005948)
			(xy 34.050606 -153.938545) (xy 34.086546 -153.907236) (xy 34.094558 -153.899654) (xy 34.103781 -153.879644)
			(xy 34.104326 -153.868628) (xy 34.104326 -153.791412) (xy 34.103773 -153.780395) (xy 34.094564 -153.760379)
			(xy 34.086546 -153.752804) (xy 34.050625 -153.721475) (xy 33.983231 -153.654065) (xy 33.92133 -153.581577)
			(xy 33.865305 -153.504458) (xy 33.8155 -153.423183) (xy 33.772222 -153.338253) (xy 33.735738 -153.25019)
			(xy 33.706272 -153.159538) (xy 33.684005 -153.066853) (xy 33.669076 -152.972708) (xy 33.661576 -152.877683)
			(xy 33.661096 -152.830022) (xy 33.661673 -152.779839) (xy 33.66996 -152.679815) (xy 33.686478 -152.580818)
			(xy 33.711114 -152.483522) (xy 33.743701 -152.388593) (xy 33.784016 -152.29668) (xy 33.831783 -152.208409)
			(xy 33.886676 -152.124385) (xy 33.94832 -152.04518) (xy 34.016294 -151.971337) (xy 34.090135 -151.903359)
			(xy 34.169336 -151.841711) (xy 34.253358 -151.786813) (xy 34.341626 -151.739042) (xy 34.433537 -151.698723)
			(xy 34.528465 -151.666131) (xy 34.625759 -151.64149) (xy 34.724756 -151.624967) (xy 34.824779 -151.616676)
			(xy 34.874962 -151.616156) (xy 34.922624 -151.616643) (xy 35.017654 -151.624127) (xy 35.111803 -151.639042)
			(xy 35.204493 -151.661299) (xy 35.29515 -151.690758) (xy 35.383217 -151.727239) (xy 35.468151 -151.770517)
			(xy 35.549427 -151.820325) (xy 35.626545 -151.876355) (xy 35.69903 -151.938264) (xy 35.766434 -152.005668)
			(xy 35.797744 -152.041606) (xy 35.80534 -152.049603) (xy 35.825339 -152.058836) (xy 35.836352 -152.059386)
			(xy 35.913568 -152.059386) (xy 35.924585 -152.058835) (xy 35.944602 -152.049625) (xy 35.952176 -152.041606)
			(xy 35.983506 -152.005687) (xy 36.050917 -151.938293) (xy 36.123405 -151.876393) (xy 36.200524 -151.820369)
			(xy 36.281799 -151.770564) (xy 36.366729 -151.727286) (xy 36.454792 -151.690802) (xy 36.545444 -151.661335)
			(xy 36.638128 -151.639068) (xy 36.732272 -151.624138) (xy 36.827298 -151.616636) (xy 36.874958 -151.616156)
			(xy 36.925143 -151.616679) (xy 37.02517 -151.624964) (xy 37.124172 -151.641481) (xy 37.221471 -151.666118)
			(xy 37.316403 -151.698706) (xy 37.40832 -151.739022) (xy 37.496594 -151.786792) (xy 37.580621 -151.841687)
			(xy 37.659828 -151.903335) (xy 37.733673 -151.971313) (xy 37.801652 -152.045157) (xy 37.863301 -152.124363)
			(xy 37.918198 -152.208389) (xy 37.965969 -152.296662) (xy 38.006287 -152.388578) (xy 38.038876 -152.48351)
			(xy 38.063514 -152.580809) (xy 38.080034 -152.67981) (xy 38.08832 -152.779837) (xy 38.088824 -152.830022)
			(xy 38.088387 -152.877685) (xy 38.080899 -152.972716) (xy 38.065978 -153.066867) (xy 38.043717 -153.159558)
			(xy 38.014253 -153.250216) (xy 37.977767 -153.338283) (xy 37.934484 -153.423216) (xy 37.884671 -153.504492)
			(xy 37.828636 -153.581609) (xy 37.766723 -153.654092) (xy 37.699315 -153.721495) (xy 37.663374 -153.752804)
			(xy 37.655347 -153.760372) (xy 37.646132 -153.780392) (xy 37.645594 -153.791412) (xy 37.645594 -153.868628)
			(xy 37.646118 -153.879648) (xy 37.655348 -153.899665) (xy 37.663374 -153.907236) (xy 37.699318 -153.938538)
			(xy 37.766712 -154.005952) (xy 37.828611 -154.078443) (xy 37.884634 -154.155565) (xy 37.934437 -154.236842)
			(xy 37.977713 -154.321776) (xy 38.014195 -154.409841) (xy 38.043659 -154.500496) (xy 38.065922 -154.593182)
			(xy 38.080849 -154.687329) (xy 38.088346 -154.782357) (xy 38.088824 -154.830018) (xy 38.088384 -154.877681)
			(xy 38.080896 -154.972712) (xy 38.065976 -155.066863) (xy 38.043715 -155.159553) (xy 38.014251 -155.250211)
			(xy 37.977765 -155.338278) (xy 37.934483 -155.423212) (xy 37.884671 -155.504487) (xy 37.828635 -155.581605)
			(xy 37.766723 -155.654088) (xy 37.699314 -155.721491) (xy 37.663374 -155.7528) (xy 37.655349 -155.76037)
			(xy 37.646132 -155.780389) (xy 37.645594 -155.791408) (xy 37.645594 -155.868624) (xy 37.64612 -155.879644)
			(xy 37.655348 -155.89966) (xy 37.663374 -155.907232) (xy 37.699316 -155.938536) (xy 37.76671 -156.00595)
			(xy 37.828609 -156.07844) (xy 37.884632 -156.155562) (xy 37.934436 -156.23684) (xy 37.977712 -156.321773)
			(xy 38.014194 -156.409838) (xy 38.043658 -156.500492) (xy 38.065921 -156.593179) (xy 38.080848 -156.687325)
			(xy 38.088346 -156.782353) (xy 38.088824 -156.830014) (xy 38.088381 -156.877677) (xy 38.080894 -156.972708)
			(xy 38.065974 -157.066859) (xy 38.043713 -157.159549) (xy 38.014249 -157.250207) (xy 37.977764 -157.338274)
			(xy 37.934482 -157.423207) (xy 37.88467 -157.504483) (xy 37.828635 -157.581601) (xy 37.766722 -157.654084)
			(xy 37.699314 -157.721487) (xy 37.663374 -157.752796) (xy 37.65535 -157.760367) (xy 37.646133 -157.780385)
			(xy 37.645594 -157.791404) (xy 37.645594 -157.86862) (xy 37.646123 -157.87964) (xy 37.655349 -157.899656)
			(xy 37.663374 -157.907228) (xy 37.699314 -157.938534) (xy 37.766708 -158.005947) (xy 37.828607 -158.078438)
			(xy 37.884631 -158.155559) (xy 37.934434 -158.236837) (xy 37.97771 -158.32177) (xy 38.014193 -158.409834)
			(xy 38.043657 -158.500489) (xy 38.065921 -158.593175) (xy 38.080848 -158.687322) (xy 38.088346 -158.782349)
			(xy 38.088824 -158.830006) (xy 47.585872 -158.830006) (xy 47.589977 -158.730238) (xy 47.602263 -158.631145)
			(xy 47.62265 -158.533395) (xy 47.650997 -158.437651) (xy 47.687114 -158.344559) (xy 47.730757 -158.254749)
			(xy 47.781631 -158.168828) (xy 47.839391 -158.087377) (xy 47.903647 -158.010946) (xy 47.973966 -157.940053)
			(xy 48.011588 -157.907228) (xy 48.019595 -157.899641) (xy 48.028823 -157.879635) (xy 48.029368 -157.86862)
			(xy 48.029368 -157.791404) (xy 48.028838 -157.780384) (xy 48.019614 -157.760367) (xy 48.011588 -157.752796)
			(xy 47.975656 -157.721488) (xy 47.908285 -157.654066) (xy 47.846409 -157.581568) (xy 47.790409 -157.504442)
			(xy 47.74063 -157.423161) (xy 47.697378 -157.338227) (xy 47.660919 -157.250163) (xy 47.631479 -157.159511)
			(xy 47.609239 -157.06683) (xy 47.594335 -156.972689) (xy 47.586859 -156.87767) (xy 47.586392 -156.830014)
			(xy 47.586965 -156.779838) (xy 47.59525 -156.679827) (xy 47.611764 -156.580842) (xy 47.636395 -156.483559)
			(xy 47.668973 -156.388642) (xy 47.709278 -156.296738) (xy 47.757033 -156.208477) (xy 47.811913 -156.124459)
			(xy 47.873542 -156.04526) (xy 47.9415 -155.97142) (xy 48.015323 -155.903443) (xy 48.094507 -155.841793)
			(xy 48.17851 -155.786892) (xy 48.26676 -155.739114) (xy 48.358653 -155.698786) (xy 48.453562 -155.666183)
			(xy 48.550839 -155.641528) (xy 48.64982 -155.624989) (xy 48.749828 -155.616678) (xy 48.800004 -155.616148)
			(xy 48.847666 -155.616608) (xy 48.942697 -155.624094) (xy 49.036847 -155.639013) (xy 49.129537 -155.661272)
			(xy 49.220195 -155.690735) (xy 49.308261 -155.727219) (xy 49.393195 -155.770499) (xy 49.474471 -155.820309)
			(xy 49.551588 -155.876342) (xy 49.624073 -155.938253) (xy 49.691476 -156.005659) (xy 49.722786 -156.041598)
			(xy 49.730366 -156.049613) (xy 49.750377 -156.058836) (xy 49.761394 -156.059378) (xy 49.83861 -156.059378)
			(xy 49.849631 -156.058852) (xy 49.869647 -156.049625) (xy 49.877218 -156.041598) (xy 49.908523 -156.005656)
			(xy 49.975937 -155.938264) (xy 50.048428 -155.876365) (xy 50.12555 -155.820342) (xy 50.206827 -155.770539)
			(xy 50.29176 -155.727263) (xy 50.379825 -155.690781) (xy 50.470479 -155.661317) (xy 50.563165 -155.639053)
			(xy 50.657312 -155.624125) (xy 50.752339 -155.616627) (xy 50.8 -155.616148) (xy 50.850166 -155.616706)
			(xy 50.950156 -155.62499) (xy 51.04912 -155.641502) (xy 51.146384 -155.666128) (xy 51.241281 -155.698701)
			(xy 51.333166 -155.738998) (xy 51.421409 -155.786744) (xy 51.505409 -155.841614) (xy 51.584592 -155.903231)
			(xy 51.658416 -155.971176) (xy 51.726379 -156.044984) (xy 51.788016 -156.124152) (xy 51.842905 -156.208138)
			(xy 51.890673 -156.29637) (xy 51.930992 -156.388245) (xy 51.963588 -156.483134) (xy 51.988238 -156.580392)
			(xy 52.004774 -156.679352) (xy 52.013082 -156.77934) (xy 52.013612 -156.829506) (xy 52.013612 -156.830014)
			(xy 52.013125 -156.87767) (xy 52.005656 -156.972689) (xy 51.990757 -157.06683) (xy 51.968521 -157.159512)
			(xy 51.939083 -157.250164) (xy 51.902626 -157.338228) (xy 51.859375 -157.423162) (xy 51.809594 -157.504441)
			(xy 51.753592 -157.581566) (xy 51.691714 -157.65406) (xy 51.62434 -157.721478) (xy 51.588416 -157.752796)
			(xy 51.580399 -157.760374) (xy 51.571177 -157.780386) (xy 51.570636 -157.791404) (xy 51.570636 -157.86862)
			(xy 51.571152 -157.879642) (xy 51.580386 -157.899659) (xy 51.588416 -157.907228) (xy 51.626049 -157.940041)
			(xy 51.696367 -158.010936) (xy 51.760624 -158.087368) (xy 51.818385 -158.16882) (xy 51.869259 -158.254742)
			(xy 51.912903 -158.344553) (xy 51.94902 -158.437646) (xy 51.977368 -158.533392) (xy 51.997754 -158.631142)
			(xy 52.010041 -158.730237) (xy 52.014146 -158.830007) (xy 52.01004 -158.929776) (xy 51.997752 -159.028871)
			(xy 51.977365 -159.126621) (xy 51.949016 -159.222366) (xy 51.912897 -159.315459) (xy 51.869253 -159.405269)
			(xy 51.818378 -159.491191) (xy 51.760616 -159.572642) (xy 51.696359 -159.649074) (xy 51.626039 -159.719967)
			(xy 51.588416 -159.752792) (xy 51.580401 -159.760372) (xy 51.571178 -159.780383) (xy 51.570636 -159.7914)
			(xy 51.570636 -159.868616) (xy 51.571154 -159.879638) (xy 51.580386 -159.899655) (xy 51.588416 -159.907224)
			(xy 51.624359 -159.93852) (xy 51.691729 -160.005944) (xy 51.753604 -160.078442) (xy 51.809604 -160.15557)
			(xy 51.859382 -160.236852) (xy 51.902633 -160.321787) (xy 51.939091 -160.409853) (xy 51.96853 -160.500506)
			(xy 51.990769 -160.593188) (xy 52.005671 -160.687329) (xy 52.013145 -160.782349) (xy 52.013612 -160.830006)
			(xy 52.013509 -160.852379) (xy 52.011856 -160.897094) (xy 52.01031 -160.919414) (xy 52.01031 -160.919668)
			(xy 52.010063 -160.928551) (xy 52.014939 -160.945628) (xy 52.025303 -160.960049) (xy 52.032408 -160.965388)
			(xy 52.10556 -161.014664) (xy 52.113141 -161.019381) (xy 52.130424 -161.023806) (xy 52.148176 -161.022038)
			(xy 52.15636 -161.018474) (xy 52.156614 -161.01822) (xy 52.206696 -160.994237) (xy 52.309828 -160.953049)
			(xy 52.415788 -160.919811) (xy 52.523967 -160.894713) (xy 52.633739 -160.877899) (xy 52.74447 -160.869468)
			(xy 52.855522 -160.869468) (xy 52.966253 -160.877899) (xy 53.076025 -160.894713) (xy 53.184204 -160.919811)
			(xy 53.290164 -160.953049) (xy 53.393296 -160.994237) (xy 53.443378 -161.01822) (xy 53.443632 -161.018474)
			(xy 53.451831 -161.022014) (xy 53.469582 -161.023818) (xy 53.486874 -161.019416) (xy 53.494432 -161.014664)
			(xy 53.567584 -160.965388) (xy 53.574788 -160.960147) (xy 53.585215 -160.945714) (xy 53.590029 -160.928571)
			(xy 53.589682 -160.919668) (xy 53.589682 -160.919414) (xy 53.588137 -160.897094) (xy 53.586483 -160.852379)
			(xy 53.58638 -160.830006) (xy 53.58685 -160.782349) (xy 53.594318 -160.687329) (xy 53.609216 -160.593187)
			(xy 53.631453 -160.500504) (xy 53.660891 -160.409851) (xy 53.69735 -160.321786) (xy 53.740604 -160.236853)
			(xy 53.790387 -160.155574) (xy 53.846391 -160.07845) (xy 53.908273 -160.005957) (xy 53.975651 -159.938541)
			(xy 54.011576 -159.907224) (xy 54.019598 -159.899652) (xy 54.028814 -159.879634) (xy 54.029356 -159.868616)
			(xy 54.029356 -159.7914) (xy 54.028832 -159.780379) (xy 54.019604 -159.760362) (xy 54.011576 -159.752792)
			(xy 53.973961 -159.719958) (xy 53.903637 -159.649067) (xy 53.839375 -159.572639) (xy 53.78161 -159.491189)
			(xy 53.730732 -159.405269) (xy 53.687085 -159.315459) (xy 53.650964 -159.222367) (xy 53.622613 -159.126622)
			(xy 53.602224 -159.028872) (xy 53.589935 -158.929776) (xy 53.585829 -158.830006) (xy 53.589934 -158.730237)
			(xy 53.602222 -158.631141) (xy 53.62261 -158.533391) (xy 53.650959 -158.437645) (xy 53.68708 -158.344553)
			(xy 53.730726 -158.254743) (xy 53.781603 -158.168822) (xy 53.839368 -158.087371) (xy 53.903628 -158.010942)
			(xy 53.973951 -157.940051) (xy 54.011576 -157.907228) (xy 54.019596 -157.899654) (xy 54.028813 -157.879638)
			(xy 54.029356 -157.86862) (xy 54.029356 -157.791404) (xy 54.02883 -157.780383) (xy 54.019604 -157.760366)
			(xy 54.011576 -157.752796) (xy 53.975641 -157.721491) (xy 53.908271 -157.654068) (xy 53.846396 -157.58157)
			(xy 53.790396 -157.504443) (xy 53.740617 -157.423162) (xy 53.697365 -157.338228) (xy 53.660907 -157.250164)
			(xy 53.631467 -157.159512) (xy 53.609227 -157.06683) (xy 53.594323 -156.97269) (xy 53.586847 -156.87767)
			(xy 53.58638 -156.830014) (xy 53.586866 -156.779835) (xy 53.595151 -156.67982) (xy 53.611667 -156.580831)
			(xy 53.636299 -156.483544) (xy 53.668881 -156.388622) (xy 53.709189 -156.296715) (xy 53.756949 -156.208451)
			(xy 53.811833 -156.124431) (xy 53.873468 -156.04523) (xy 53.941431 -155.971389) (xy 54.01526 -155.903411)
			(xy 54.09445 -155.841762) (xy 54.17846 -155.786862) (xy 54.266716 -155.739087) (xy 54.358615 -155.698762)
			(xy 54.453531 -155.666163) (xy 54.550814 -155.641512) (xy 54.6498 -155.624979) (xy 54.749813 -155.616675)
			(xy 54.799992 -155.616148) (xy 54.847654 -155.616616) (xy 54.942685 -155.624102) (xy 55.036835 -155.63902)
			(xy 55.129524 -155.661278) (xy 55.220182 -155.69074) (xy 55.308249 -155.727223) (xy 55.393182 -155.770502)
			(xy 55.474458 -155.820312) (xy 55.551576 -155.876344) (xy 55.62406 -155.938254) (xy 55.691464 -156.005659)
			(xy 55.722774 -156.041598) (xy 55.730359 -156.049607) (xy 55.750366 -156.058833) (xy 55.761382 -156.059378)
			(xy 55.838598 -156.059378) (xy 55.849618 -156.058846) (xy 55.869635 -156.049623) (xy 55.877206 -156.041598)
			(xy 55.908518 -156.005662) (xy 55.975931 -155.93827) (xy 56.048421 -155.876371) (xy 56.125542 -155.820347)
			(xy 56.206819 -155.770544) (xy 56.291751 -155.727267) (xy 56.379815 -155.690784) (xy 56.470469 -155.66132)
			(xy 56.563154 -155.639055) (xy 56.6573 -155.624127) (xy 56.752327 -155.616627) (xy 56.799988 -155.616148)
			(xy 56.850154 -155.616717) (xy 56.950144 -155.625) (xy 57.049108 -155.641511) (xy 57.146371 -155.666137)
			(xy 57.241269 -155.698709) (xy 57.333153 -155.739005) (xy 57.421396 -155.786751) (xy 57.505396 -155.841619)
			(xy 57.584579 -155.903236) (xy 57.658404 -155.97118) (xy 57.726366 -156.044988) (xy 57.788003 -156.124155)
			(xy 57.842893 -156.208141) (xy 57.89066 -156.296372) (xy 57.93098 -156.388246) (xy 57.963576 -156.483136)
			(xy 57.988226 -156.580393) (xy 58.004762 -156.679353) (xy 58.01307 -156.77934) (xy 58.0136 -156.829506)
			(xy 58.0136 -156.830014) (xy 58.013117 -156.87767) (xy 58.005648 -156.97269) (xy 57.990749 -157.06683)
			(xy 57.968513 -157.159512) (xy 57.939075 -157.250165) (xy 57.902617 -157.338229) (xy 57.859365 -157.423163)
			(xy 57.809584 -157.504442) (xy 57.753582 -157.581567) (xy 57.691703 -157.654061) (xy 57.624328 -157.721478)
			(xy 57.588404 -157.752796) (xy 57.580385 -157.760372) (xy 57.571164 -157.780386) (xy 57.570624 -157.791404)
			(xy 57.570624 -157.86862) (xy 57.571143 -157.879641) (xy 57.580375 -157.899658) (xy 57.588404 -157.907228)
			(xy 57.626037 -157.940041) (xy 57.696356 -158.010935) (xy 57.760614 -158.087367) (xy 57.818375 -158.168819)
			(xy 57.86925 -158.254741) (xy 57.912894 -158.344552) (xy 57.949012 -158.437645) (xy 57.97736 -158.533391)
			(xy 57.997746 -158.631142) (xy 58.010033 -158.730237) (xy 58.014138 -158.830006) (xy 61.785988 -158.830006)
			(xy 61.790092 -158.730238) (xy 61.802379 -158.631144) (xy 61.822766 -158.533394) (xy 61.851114 -158.437649)
			(xy 61.887232 -158.344557) (xy 61.930876 -158.254747) (xy 61.981751 -158.168826) (xy 62.039512 -158.087375)
			(xy 62.10377 -158.010945) (xy 62.174089 -157.940052) (xy 62.211712 -157.907228) (xy 62.219722 -157.899645)
			(xy 62.228947 -157.879636) (xy 62.229492 -157.86862) (xy 62.229492 -157.791404) (xy 62.228954 -157.780385)
			(xy 62.219735 -157.760368) (xy 62.211712 -157.752796) (xy 62.175785 -157.721482) (xy 62.108414 -157.654061)
			(xy 62.046537 -157.581565) (xy 61.990536 -157.504439) (xy 61.940756 -157.423159) (xy 61.897503 -157.338226)
			(xy 61.861045 -157.250162) (xy 61.831604 -157.15951) (xy 61.809363 -157.066829) (xy 61.794459 -156.972689)
			(xy 61.786983 -156.87767) (xy 61.786516 -156.830014) (xy 61.787065 -156.779837) (xy 61.79535 -156.679825)
			(xy 61.811865 -156.580839) (xy 61.836496 -156.483555) (xy 61.869075 -156.388636) (xy 61.909381 -156.296732)
			(xy 61.957137 -156.20847) (xy 62.012018 -156.124451) (xy 62.073649 -156.045252) (xy 62.141609 -155.971411)
			(xy 62.215433 -155.903434) (xy 62.294619 -155.841785) (xy 62.378624 -155.786884) (xy 62.466875 -155.739107)
			(xy 62.55877 -155.698779) (xy 62.653681 -155.666178) (xy 62.750959 -155.641524) (xy 62.849941 -155.624986)
			(xy 62.949951 -155.616677) (xy 63.000128 -155.616148) (xy 63.047791 -155.61659) (xy 63.142822 -155.624079)
			(xy 63.236972 -155.639) (xy 63.329662 -155.661261) (xy 63.42032 -155.690725) (xy 63.508387 -155.72721)
			(xy 63.59332 -155.770492) (xy 63.674596 -155.820304) (xy 63.751713 -155.876339) (xy 63.824197 -155.938251)
			(xy 63.891601 -156.005658) (xy 63.92291 -156.041598) (xy 63.93048 -156.049623) (xy 63.950499 -156.058841)
			(xy 63.961518 -156.059378) (xy 64.038734 -156.059378) (xy 64.049756 -156.058866) (xy 64.069773 -156.049629)
			(xy 64.077342 -156.041598) (xy 64.108634 -156.005645) (xy 64.176049 -155.938253) (xy 64.248542 -155.876355)
			(xy 64.325665 -155.820332) (xy 64.406944 -155.77053) (xy 64.491878 -155.727255) (xy 64.579944 -155.690774)
			(xy 64.6706 -155.661311) (xy 64.763287 -155.639048) (xy 64.857434 -155.624123) (xy 64.952462 -155.616626)
			(xy 65.000124 -155.616148) (xy 65.050291 -155.616683) (xy 65.150281 -155.624969) (xy 65.249246 -155.641482)
			(xy 65.346509 -155.666111) (xy 65.441407 -155.698685) (xy 65.533292 -155.738984) (xy 65.621535 -155.786732)
			(xy 65.705535 -155.841602) (xy 65.784717 -155.903221) (xy 65.858542 -155.971167) (xy 65.926504 -156.044977)
			(xy 65.988141 -156.124145) (xy 66.04303 -156.208133) (xy 66.090797 -156.296366) (xy 66.131116 -156.388241)
			(xy 66.163712 -156.483132) (xy 66.188362 -156.58039) (xy 66.204898 -156.679351) (xy 66.213206 -156.77934)
			(xy 66.213736 -156.829506) (xy 66.213736 -156.830014) (xy 66.213275 -156.877671) (xy 66.205806 -156.972691)
			(xy 66.190906 -157.066833) (xy 66.168668 -157.159516) (xy 66.139228 -157.250169) (xy 66.102769 -157.338234)
			(xy 66.059514 -157.423167) (xy 66.009731 -157.504446) (xy 65.953726 -157.58157) (xy 65.891843 -157.654063)
			(xy 65.824465 -157.721479) (xy 65.78854 -157.752796) (xy 65.780512 -157.760363) (xy 65.771299 -157.780384)
			(xy 65.77076 -157.791404) (xy 65.77076 -157.86862) (xy 65.771299 -157.879638) (xy 65.780519 -157.899654)
			(xy 65.78854 -157.907228) (xy 65.826175 -157.94004) (xy 65.896498 -158.010933) (xy 65.960758 -158.087363)
			(xy 66.018523 -158.168815) (xy 66.0694 -158.254736) (xy 66.113046 -158.344548) (xy 66.149166 -158.437641)
			(xy 66.177516 -158.533388) (xy 66.197904 -158.631139) (xy 66.210191 -158.730236) (xy 66.214296 -158.830006)
			(xy 67.78598 -158.830006) (xy 67.790084 -158.730238) (xy 67.802371 -158.631144) (xy 67.822758 -158.533394)
			(xy 67.851106 -158.43765) (xy 67.887223 -158.344558) (xy 67.930867 -158.254748) (xy 67.981741 -158.168827)
			(xy 68.039502 -158.087376) (xy 68.103758 -158.010946) (xy 68.174077 -157.940052) (xy 68.2117 -157.907228)
			(xy 68.219709 -157.899643) (xy 68.228935 -157.879636) (xy 68.22948 -157.86862) (xy 68.22948 -157.791404)
			(xy 68.228946 -157.780384) (xy 68.219725 -157.760368) (xy 68.2117 -157.752796) (xy 68.17577 -157.721485)
			(xy 68.108399 -157.654063) (xy 68.046523 -157.581566) (xy 67.990523 -157.50444) (xy 67.940743 -157.42316)
			(xy 67.897491 -157.338227) (xy 67.861032 -157.250163) (xy 67.831592 -157.159511) (xy 67.809351 -157.066829)
			(xy 67.794447 -156.972689) (xy 67.786971 -156.87767) (xy 67.786504 -156.830014) (xy 67.787065 -156.779837)
			(xy 67.79535 -156.679826) (xy 67.811864 -156.580841) (xy 67.836495 -156.483557) (xy 67.869074 -156.388639)
			(xy 67.90938 -156.296735) (xy 67.957135 -156.208473) (xy 68.012016 -156.124455) (xy 68.073646 -156.045256)
			(xy 68.141605 -155.971415) (xy 68.215428 -155.903438) (xy 68.294613 -155.841789) (xy 68.378617 -155.786888)
			(xy 68.466867 -155.73911) (xy 68.558761 -155.698783) (xy 68.653671 -155.66618) (xy 68.750949 -155.641526)
			(xy 68.84993 -155.624987) (xy 68.949939 -155.616678) (xy 69.000116 -155.616148) (xy 69.047779 -155.616599)
			(xy 69.142809 -155.624087) (xy 69.23696 -155.639006) (xy 69.32965 -155.661267) (xy 69.420307 -155.69073)
			(xy 69.508374 -155.727214) (xy 69.593307 -155.770496) (xy 69.674583 -155.820307) (xy 69.751701 -155.87634)
			(xy 69.824185 -155.938252) (xy 69.891588 -156.005658) (xy 69.922898 -156.041598) (xy 69.930473 -156.049618)
			(xy 69.950488 -156.058838) (xy 69.961506 -156.059378) (xy 70.038722 -156.059378) (xy 70.049743 -156.058859)
			(xy 70.06976 -156.049627) (xy 70.07733 -156.041598) (xy 70.108628 -156.005651) (xy 70.176043 -155.938258)
			(xy 70.248535 -155.87636) (xy 70.325657 -155.820337) (xy 70.406936 -155.770534) (xy 70.491869 -155.727259)
			(xy 70.579934 -155.690777) (xy 70.67059 -155.661314) (xy 70.763276 -155.639051) (xy 70.857423 -155.624124)
			(xy 70.952451 -155.616626) (xy 71.000112 -155.616148) (xy 71.050278 -155.616694) (xy 71.150268 -155.624979)
			(xy 71.249233 -155.641492) (xy 71.346496 -155.666119) (xy 71.441394 -155.698693) (xy 71.533279 -155.738991)
			(xy 71.621522 -155.786738) (xy 71.705522 -155.841608) (xy 71.784704 -155.903226) (xy 71.858529 -155.971171)
			(xy 71.926492 -156.04498) (xy 71.988128 -156.124149) (xy 72.043017 -156.208136) (xy 72.090785 -156.296368)
			(xy 72.131104 -156.388243) (xy 72.1637 -156.483133) (xy 72.18835 -156.580391) (xy 72.204886 -156.679352)
			(xy 72.213194 -156.77934) (xy 72.213724 -156.829506) (xy 72.213724 -156.830014) (xy 72.213267 -156.877671)
			(xy 72.205798 -156.972692) (xy 72.190898 -157.066833) (xy 72.16866 -157.159517) (xy 72.13922 -157.25017)
			(xy 72.10276 -157.338235) (xy 72.059505 -157.423168) (xy 72.009721 -157.504447) (xy 71.953715 -157.581571)
			(xy 71.891832 -157.654064) (xy 71.824454 -157.721479) (xy 71.788528 -157.752796) (xy 71.780497 -157.760361)
			(xy 71.771286 -157.780384) (xy 71.770748 -157.791404) (xy 71.770748 -157.86862) (xy 71.77126 -157.879642)
			(xy 71.780496 -157.89966) (xy 71.788528 -157.907228) (xy 71.826961 -157.940728) (xy 71.898668 -158.013216)
			(xy 71.964043 -158.091463) (xy 72.022625 -158.174917) (xy 72.074 -158.26299) (xy 72.096376 -158.308802)
			(xy 72.100948 -158.318454) (xy 72.11695 -158.332424) (xy 72.199246 -158.357316) (xy 72.209509 -158.35998)
			(xy 72.230544 -158.357501) (xy 72.239886 -158.35249) (xy 72.285848 -158.325685) (xy 72.380951 -158.27795)
			(xy 72.479225 -158.237137) (xy 72.580165 -158.203457) (xy 72.683255 -158.17708) (xy 72.787967 -158.158142)
			(xy 72.893765 -158.146741) (xy 73.000108 -158.142934) (xy 73.106451 -158.146741) (xy 73.212249 -158.158142)
			(xy 73.316961 -158.17708) (xy 73.420051 -158.203457) (xy 73.520991 -158.237137) (xy 73.619265 -158.27795)
			(xy 73.714368 -158.325685) (xy 73.76033 -158.35249) (xy 73.769716 -158.357372) (xy 73.790702 -158.359866)
			(xy 73.80097 -158.357316) (xy 73.883266 -158.332424) (xy 73.899268 -158.318454) (xy 73.90384 -158.308802)
			(xy 73.92622 -158.262993) (xy 73.97759 -158.174915) (xy 74.036169 -158.09146) (xy 74.101545 -158.013214)
			(xy 74.173257 -157.940731) (xy 74.211688 -157.907228) (xy 74.219695 -157.899641) (xy 74.228923 -157.879635)
			(xy 74.229468 -157.86862) (xy 74.229468 -157.791404) (xy 74.228938 -157.780384) (xy 74.219714 -157.760367)
			(xy 74.211688 -157.752796) (xy 74.175756 -157.721488) (xy 74.108385 -157.654066) (xy 74.046509 -157.581568)
			(xy 73.990509 -157.504442) (xy 73.94073 -157.423161) (xy 73.897478 -157.338227) (xy 73.861019 -157.250163)
			(xy 73.831579 -157.159511) (xy 73.809339 -157.06683) (xy 73.794435 -156.972689) (xy 73.786959 -156.87767)
			(xy 73.786492 -156.830014) (xy 73.787065 -156.779838) (xy 73.79535 -156.679827) (xy 73.811864 -156.580842)
			(xy 73.836495 -156.483559) (xy 73.869073 -156.388642) (xy 73.909378 -156.296738) (xy 73.957133 -156.208477)
			(xy 74.012013 -156.124459) (xy 74.073642 -156.04526) (xy 74.1416 -155.97142) (xy 74.215423 -155.903443)
			(xy 74.294607 -155.841793) (xy 74.37861 -155.786892) (xy 74.46686 -155.739114) (xy 74.558753 -155.698786)
			(xy 74.653662 -155.666183) (xy 74.750939 -155.641528) (xy 74.84992 -155.624989) (xy 74.949928 -155.616678)
			(xy 75.000104 -155.616148) (xy 75.047766 -155.616608) (xy 75.142797 -155.624094) (xy 75.236947 -155.639013)
			(xy 75.329637 -155.661272) (xy 75.420295 -155.690735) (xy 75.508361 -155.727219) (xy 75.593295 -155.770499)
			(xy 75.674571 -155.820309) (xy 75.751688 -155.876342) (xy 75.824173 -155.938253) (xy 75.891576 -156.005659)
			(xy 75.922886 -156.041598) (xy 75.930466 -156.049613) (xy 75.950477 -156.058836) (xy 75.961494 -156.059378)
			(xy 76.03871 -156.059378) (xy 76.049731 -156.058852) (xy 76.069747 -156.049625) (xy 76.077318 -156.041598)
			(xy 76.108623 -156.005656) (xy 76.176037 -155.938264) (xy 76.248528 -155.876365) (xy 76.32565 -155.820342)
			(xy 76.406927 -155.770539) (xy 76.49186 -155.727263) (xy 76.579925 -155.690781) (xy 76.670579 -155.661317)
			(xy 76.763265 -155.639053) (xy 76.857412 -155.624125) (xy 76.952439 -155.616627) (xy 77.0001 -155.616148)
			(xy 77.050266 -155.616706) (xy 77.150256 -155.62499) (xy 77.24922 -155.641502) (xy 77.346484 -155.666128)
			(xy 77.441381 -155.698701) (xy 77.533266 -155.738998) (xy 77.621509 -155.786744) (xy 77.705509 -155.841614)
			(xy 77.784692 -155.903231) (xy 77.858516 -155.971176) (xy 77.926479 -156.044984) (xy 77.988116 -156.124152)
			(xy 78.043005 -156.208138) (xy 78.090773 -156.29637) (xy 78.131092 -156.388245) (xy 78.163688 -156.483134)
			(xy 78.188338 -156.580392) (xy 78.204874 -156.679352) (xy 78.213182 -156.77934) (xy 78.213712 -156.829506)
			(xy 78.213712 -156.830014) (xy 78.213225 -156.87767) (xy 78.205756 -156.972689) (xy 78.190857 -157.06683)
			(xy 78.168621 -157.159512) (xy 78.139183 -157.250164) (xy 78.102726 -157.338228) (xy 78.059475 -157.423162)
			(xy 78.009694 -157.504441) (xy 77.953692 -157.581566) (xy 77.891814 -157.65406) (xy 77.82444 -157.721478)
			(xy 77.788516 -157.752796) (xy 77.780499 -157.760374) (xy 77.771277 -157.780386) (xy 77.770736 -157.791404)
			(xy 77.770736 -157.86862) (xy 77.771252 -157.879642) (xy 77.780486 -157.899659) (xy 77.788516 -157.907228)
			(xy 77.826149 -157.940041) (xy 77.896467 -158.010936) (xy 77.960724 -158.087368) (xy 78.018485 -158.16882)
			(xy 78.069359 -158.254742) (xy 78.113003 -158.344553) (xy 78.14912 -158.437646) (xy 78.177468 -158.533392)
			(xy 78.197854 -158.631142) (xy 78.210141 -158.730237) (xy 78.214246 -158.830007) (xy 78.21014 -158.929776)
			(xy 78.197852 -159.028871) (xy 78.177465 -159.126621) (xy 78.149116 -159.222366) (xy 78.112997 -159.315459)
			(xy 78.069353 -159.405269) (xy 78.018478 -159.491191) (xy 77.960716 -159.572642) (xy 77.896459 -159.649074)
			(xy 77.826139 -159.719967) (xy 77.788516 -159.752792) (xy 77.780501 -159.760372) (xy 77.771278 -159.780383)
			(xy 77.770736 -159.7914) (xy 77.770736 -159.868616) (xy 77.771254 -159.879638) (xy 77.780486 -159.899655)
			(xy 77.788516 -159.907224) (xy 77.824459 -159.93852) (xy 77.891829 -160.005944) (xy 77.953704 -160.078442)
			(xy 78.009704 -160.15557) (xy 78.059482 -160.236852) (xy 78.102733 -160.321787) (xy 78.139191 -160.409853)
			(xy 78.16863 -160.500506) (xy 78.190869 -160.593188) (xy 78.205771 -160.687329) (xy 78.213245 -160.782349)
			(xy 78.213712 -160.830006) (xy 78.213154 -160.880183) (xy 78.204867 -160.980193) (xy 78.188352 -161.079178)
			(xy 78.16372 -161.176461) (xy 78.13114 -161.271379) (xy 78.090834 -161.363282) (xy 78.043078 -161.451544)
			(xy 77.988197 -161.535561) (xy 77.926567 -161.61476) (xy 77.858608 -161.6886) (xy 77.784785 -161.756577)
			(xy 77.7056 -161.818226) (xy 77.621596 -161.873127) (xy 77.533346 -161.920905) (xy 77.441453 -161.961233)
			(xy 77.346543 -161.993836) (xy 77.249266 -162.018492) (xy 77.150285 -162.035031) (xy 77.050276 -162.043342)
			(xy 77.0001 -162.043872) (xy 76.952438 -162.043402) (xy 76.857408 -162.035916) (xy 76.763258 -162.020998)
			(xy 76.670569 -161.998739) (xy 76.579911 -161.969278) (xy 76.491844 -161.932795) (xy 76.406911 -161.889516)
			(xy 76.325635 -161.839706) (xy 76.248517 -161.783675) (xy 76.176032 -161.721766) (xy 76.108628 -161.654361)
			(xy 76.077318 -161.618422) (xy 76.069749 -161.610397) (xy 76.049729 -161.601183) (xy 76.03871 -161.600642)
			(xy 75.961494 -161.600642) (xy 75.950473 -161.601163) (xy 75.930456 -161.610393) (xy 75.922886 -161.618422)
			(xy 75.891584 -161.654366) (xy 75.824169 -161.721758) (xy 75.751678 -161.783656) (xy 75.674555 -161.839679)
			(xy 75.593277 -161.889481) (xy 75.508344 -161.932757) (xy 75.420279 -161.969239) (xy 75.329625 -161.998703)
			(xy 75.236939 -162.020967) (xy 75.142792 -162.035894) (xy 75.047765 -162.043393) (xy 75.000104 -162.043872)
			(xy 74.950123 -162.043374) (xy 74.8505 -162.035138) (xy 74.751892 -162.018736) (xy 74.654967 -161.994281)
			(xy 74.560381 -161.961938) (xy 74.468775 -161.921925) (xy 74.380771 -161.874515) (xy 74.296963 -161.820029)
			(xy 74.21792 -161.758834) (xy 74.144177 -161.691347) (xy 74.076234 -161.618024) (xy 74.014551 -161.539362)
			(xy 73.959545 -161.455893) (xy 73.911591 -161.368184) (xy 73.871011 -161.276829) (xy 73.838082 -161.182445)
			(xy 73.813027 -161.085673) (xy 73.804018 -161.036508) (xy 73.801427 -161.024877) (xy 73.787397 -161.005661)
			(xy 73.777094 -160.999678) (xy 73.693528 -160.957514) (xy 73.669906 -160.95726) (xy 73.658984 -160.962594)
			(xy 73.611709 -160.985464) (xy 73.514509 -161.025256) (xy 73.414743 -161.058087) (xy 73.312908 -161.083794)
			(xy 73.209512 -161.102248) (xy 73.105072 -161.113358) (xy 73.000108 -161.117067) (xy 72.895144 -161.113358)
			(xy 72.790704 -161.102248) (xy 72.687308 -161.083794) (xy 72.585473 -161.058087) (xy 72.485707 -161.025256)
			(xy 72.388507 -160.985464) (xy 72.341232 -160.962594) (xy 72.330331 -160.957905) (xy 72.306624 -160.958056)
			(xy 72.295766 -160.962848) (xy 72.223122 -160.999678) (xy 72.212846 -161.005698) (xy 72.198797 -161.024888)
			(xy 72.196198 -161.036508) (xy 72.187209 -161.085679) (xy 72.162169 -161.18246) (xy 72.129253 -161.276853)
			(xy 72.088683 -161.368219) (xy 72.040735 -161.455937) (xy 71.985733 -161.539413) (xy 71.924051 -161.618083)
			(xy 71.856106 -161.691411) (xy 71.78236 -161.758901) (xy 71.703311 -161.820096) (xy 71.619496 -161.874581)
			(xy 71.531484 -161.921986) (xy 71.439869 -161.961991) (xy 71.345275 -161.994323) (xy 71.248341 -162.018765)
			(xy 71.149725 -162.035149) (xy 71.050096 -162.043365) (xy 71.000112 -162.043872) (xy 70.95245 -162.043394)
			(xy 70.85742 -162.035909) (xy 70.76327 -162.020991) (xy 70.670581 -161.998734) (xy 70.579924 -161.969273)
			(xy 70.491857 -161.932791) (xy 70.406924 -161.889512) (xy 70.325648 -161.839704) (xy 70.248529 -161.783673)
			(xy 70.176045 -161.721764) (xy 70.10864 -161.65436) (xy 70.07733 -161.618422) (xy 70.069756 -161.610402)
			(xy 70.04974 -161.601185) (xy 70.038722 -161.600642) (xy 69.961506 -161.600642) (xy 69.950486 -161.60117)
			(xy 69.930468 -161.610395) (xy 69.922898 -161.618422) (xy 69.891589 -161.65436) (xy 69.824175 -161.721752)
			(xy 69.751684 -161.78365) (xy 69.674563 -161.839674) (xy 69.593286 -161.889477) (xy 69.508353 -161.932753)
			(xy 69.420289 -161.969235) (xy 69.329635 -161.9987) (xy 69.23695 -162.020965) (xy 69.142804 -162.035893)
			(xy 69.047777 -162.043393) (xy 69.000116 -162.043872) (xy 68.949948 -162.043379) (xy 68.849954 -162.035095)
			(xy 68.750986 -162.018583) (xy 68.653719 -161.993956) (xy 68.558818 -161.961382) (xy 68.466931 -161.921082)
			(xy 68.378685 -161.873333) (xy 68.294683 -161.818461) (xy 68.215498 -161.756839) (xy 68.141672 -161.68889)
			(xy 68.073709 -161.615077) (xy 68.012073 -161.535905) (xy 67.957185 -161.451913) (xy 67.909419 -161.363676)
			(xy 67.869102 -161.271796) (xy 67.836509 -161.176901) (xy 67.811864 -161.079639) (xy 67.795333 -160.980674)
			(xy 67.787031 -160.880682) (xy 67.786504 -160.830514) (xy 67.786504 -160.830006) (xy 67.787 -160.78235)
			(xy 67.794468 -160.687331) (xy 67.809365 -160.593191) (xy 67.8316 -160.500509) (xy 67.861037 -160.409856)
			(xy 67.897493 -160.321792) (xy 67.940744 -160.236858) (xy 67.990524 -160.155579) (xy 68.046525 -160.078454)
			(xy 68.108403 -160.00596) (xy 68.175777 -159.938542) (xy 68.2117 -159.907224) (xy 68.21971 -159.89964)
			(xy 68.228936 -159.879632) (xy 68.22948 -159.868616) (xy 68.22948 -159.7914) (xy 68.228948 -159.78038)
			(xy 68.219725 -159.760363) (xy 68.2117 -159.752792) (xy 68.174087 -159.719957) (xy 68.103767 -159.649064)
			(xy 68.039509 -159.572634) (xy 67.981748 -159.491184) (xy 67.930873 -159.405263) (xy 67.887228 -159.315454)
			(xy 67.85111 -159.222362) (xy 67.822761 -159.126618) (xy 67.802374 -159.028869) (xy 67.790086 -158.929775)
			(xy 67.78598 -158.830006) (xy 66.214296 -158.830006) (xy 66.21019 -158.929777) (xy 66.197902 -159.028873)
			(xy 66.177513 -159.126625) (xy 66.149162 -159.222371) (xy 66.113041 -159.315464) (xy 66.069394 -159.405275)
			(xy 66.018516 -159.491196) (xy 65.96075 -159.572647) (xy 65.896489 -159.649077) (xy 65.826165 -159.719969)
			(xy 65.78854 -159.752792) (xy 65.780513 -159.76036) (xy 65.771299 -159.780381) (xy 65.77076 -159.7914)
			(xy 65.77076 -159.868616) (xy 65.771302 -159.879634) (xy 65.78052 -159.89965) (xy 65.78854 -159.907224)
			(xy 65.824488 -159.938515) (xy 65.891857 -160.005939) (xy 65.953732 -160.078439) (xy 66.009731 -160.155567)
			(xy 66.059509 -160.23685) (xy 66.102759 -160.321786) (xy 66.139216 -160.409851) (xy 66.168654 -160.500505)
			(xy 66.190893 -160.593188) (xy 66.205795 -160.687329) (xy 66.213269 -160.782349) (xy 66.213736 -160.830006)
			(xy 66.213254 -160.880185) (xy 66.204967 -160.980199) (xy 66.18845 -161.079188) (xy 66.163816 -161.176475)
			(xy 66.131233 -161.271396) (xy 66.090925 -161.363302) (xy 66.043165 -161.451566) (xy 65.98828 -161.535585)
			(xy 65.926645 -161.614786) (xy 65.858681 -161.688627) (xy 65.784852 -161.756604) (xy 65.705663 -161.818253)
			(xy 65.621653 -161.873153) (xy 65.533398 -161.920929) (xy 65.441499 -161.961254) (xy 65.346584 -161.993854)
			(xy 65.249301 -162.018505) (xy 65.150316 -162.03504) (xy 65.050303 -162.043345) (xy 65.000124 -162.043872)
			(xy 64.952462 -162.043385) (xy 64.857433 -162.035901) (xy 64.763283 -162.020984) (xy 64.670594 -161.998728)
			(xy 64.579937 -161.969268) (xy 64.49187 -161.932787) (xy 64.406937 -161.889509) (xy 64.32566 -161.839701)
			(xy 64.248542 -161.783671) (xy 64.176057 -161.721763) (xy 64.108652 -161.65436) (xy 64.077342 -161.618422)
			(xy 64.069763 -161.610408) (xy 64.049751 -161.601187) (xy 64.038734 -161.600642) (xy 63.961518 -161.600642)
			(xy 63.950498 -161.601177) (xy 63.930481 -161.610397) (xy 63.92291 -161.618422) (xy 63.891594 -161.654354)
			(xy 63.824181 -161.721746) (xy 63.751691 -161.783645) (xy 63.674571 -161.839668) (xy 63.593294 -161.889472)
			(xy 63.508362 -161.932748) (xy 63.420299 -161.969232) (xy 63.329645 -161.998697) (xy 63.23696 -162.020963)
			(xy 63.142815 -162.035892) (xy 63.047789 -162.043392) (xy 63.000128 -162.043872) (xy 62.94996 -162.043367)
			(xy 62.849967 -162.035085) (xy 62.750999 -162.018574) (xy 62.653732 -161.993947) (xy 62.558831 -161.961374)
			(xy 62.466944 -161.921075) (xy 62.378698 -161.873327) (xy 62.294695 -161.818455) (xy 62.215511 -161.756835)
			(xy 62.141685 -161.688886) (xy 62.073722 -161.615074) (xy 62.012086 -161.535902) (xy 61.957197 -161.45191)
			(xy 61.909431 -161.363674) (xy 61.869114 -161.271795) (xy 61.836522 -161.1769) (xy 61.811876 -161.079638)
			(xy 61.795345 -160.980673) (xy 61.787043 -160.880682) (xy 61.786516 -160.830514) (xy 61.786516 -160.830006)
			(xy 61.787008 -160.78235) (xy 61.794476 -160.687331) (xy 61.809373 -160.59319) (xy 61.831609 -160.500508)
			(xy 61.861045 -160.409855) (xy 61.897502 -160.321791) (xy 61.940753 -160.236858) (xy 61.990533 -160.155578)
			(xy 62.046535 -160.078454) (xy 62.108414 -160.005959) (xy 62.175788 -159.938542) (xy 62.211712 -159.907224)
			(xy 62.219724 -159.899642) (xy 62.228948 -159.879632) (xy 62.229492 -159.868616) (xy 62.229492 -159.7914)
			(xy 62.228956 -159.780381) (xy 62.219736 -159.760364) (xy 62.211712 -159.752792) (xy 62.174098 -159.719957)
			(xy 62.103778 -159.649065) (xy 62.03952 -159.572635) (xy 61.981758 -159.491185) (xy 61.930882 -159.405264)
			(xy 61.887237 -159.315455) (xy 61.851118 -159.222363) (xy 61.822769 -159.126619) (xy 61.802382 -159.028869)
			(xy 61.790093 -158.929775) (xy 61.785988 -158.830006) (xy 58.014138 -158.830006) (xy 58.014138 -158.830007)
			(xy 58.010032 -158.929776) (xy 57.997744 -159.028871) (xy 57.977357 -159.126622) (xy 57.949007 -159.222367)
			(xy 57.912888 -159.315459) (xy 57.869244 -159.40527) (xy 57.818368 -159.491192) (xy 57.760606 -159.572643)
			(xy 57.696348 -159.649074) (xy 57.626027 -159.719968) (xy 57.588404 -159.752792) (xy 57.580387 -159.76037)
			(xy 57.571165 -159.780382) (xy 57.570624 -159.7914) (xy 57.570624 -159.868616) (xy 57.571146 -159.879637)
			(xy 57.580376 -159.899654) (xy 57.588404 -159.907224) (xy 57.624344 -159.938523) (xy 57.691715 -160.005946)
			(xy 57.753591 -160.078444) (xy 57.80959 -160.155572) (xy 57.859369 -160.236853) (xy 57.902621 -160.321788)
			(xy 57.939078 -160.409853) (xy 57.968517 -160.500506) (xy 57.990757 -160.593189) (xy 58.005659 -160.68733)
			(xy 58.013133 -160.782349) (xy 58.0136 -160.830006) (xy 58.013054 -160.880183) (xy 58.004767 -160.980194)
			(xy 57.988252 -161.07918) (xy 57.963619 -161.176464) (xy 57.931039 -161.271382) (xy 57.890733 -161.363285)
			(xy 57.842976 -161.451547) (xy 57.788095 -161.535565) (xy 57.726464 -161.614764) (xy 57.658504 -161.688604)
			(xy 57.584679 -161.756581) (xy 57.505494 -161.818231) (xy 57.42149 -161.873131) (xy 57.333239 -161.920909)
			(xy 57.241344 -161.961236) (xy 57.146434 -161.993839) (xy 57.049156 -162.018494) (xy 56.950174 -162.035032)
			(xy 56.850165 -162.043342) (xy 56.799988 -162.043872) (xy 56.752326 -162.043411) (xy 56.657295 -162.035924)
			(xy 56.563145 -162.021005) (xy 56.470456 -161.998745) (xy 56.379798 -161.969283) (xy 56.291731 -161.932799)
			(xy 56.206798 -161.889519) (xy 56.125522 -161.839709) (xy 56.048404 -161.783676) (xy 55.97592 -161.721767)
			(xy 55.908516 -161.654361) (xy 55.877206 -161.618422) (xy 55.869641 -161.610391) (xy 55.849618 -161.60118)
			(xy 55.838598 -161.600642) (xy 55.761382 -161.600642) (xy 55.75036 -161.601157) (xy 55.730343 -161.610391)
			(xy 55.722774 -161.618422) (xy 55.691478 -161.654372) (xy 55.624063 -161.721763) (xy 55.551571 -161.783661)
			(xy 55.474448 -161.839684) (xy 55.393169 -161.889486) (xy 55.308235 -161.932761) (xy 55.22017 -161.969242)
			(xy 55.129515 -161.998706) (xy 55.036828 -162.020969) (xy 54.942681 -162.035896) (xy 54.847653 -162.043394)
			(xy 54.799992 -162.043872) (xy 54.745712 -162.043259) (xy 54.637587 -162.033538) (xy 54.530764 -162.014191)
			(xy 54.426097 -161.985373) (xy 54.37505 -161.96691) (xy 54.362096 -161.962084) (xy 54.33568 -161.966656)
			(xy 54.246526 -162.040316) (xy 54.237128 -162.06597) (xy 54.239414 -162.079432) (xy 54.248227 -162.132911)
			(xy 54.25886 -162.240785) (xy 54.26147 -162.34915) (xy 54.256041 -162.457411) (xy 54.242604 -162.564971)
			(xy 54.221232 -162.67124) (xy 54.192043 -162.775633) (xy 54.155197 -162.877575) (xy 54.110898 -162.976507)
			(xy 54.059389 -163.071883) (xy 54.000952 -163.163179) (xy 53.935911 -163.249894) (xy 53.864621 -163.331549)
			(xy 53.787476 -163.407697) (xy 53.7049 -163.477918) (xy 53.617346 -163.541825) (xy 53.525297 -163.599069)
			(xy 53.429259 -163.649333) (xy 53.329759 -163.692341) (xy 53.227346 -163.727856) (xy 53.122582 -163.755684)
			(xy 53.016044 -163.775672) (xy 52.908318 -163.787708) (xy 52.799996 -163.791727) (xy 52.691674 -163.787708)
			(xy 52.583948 -163.775672) (xy 52.47741 -163.755684) (xy 52.372646 -163.727856) (xy 52.270233 -163.692341)
			(xy 52.170733 -163.649333) (xy 52.074695 -163.599069) (xy 51.982646 -163.541825) (xy 51.895092 -163.477918)
			(xy 51.812516 -163.407697) (xy 51.735371 -163.331549) (xy 51.664081 -163.249894) (xy 51.59904 -163.163179)
			(xy 51.540603 -163.071883) (xy 51.489094 -162.976507) (xy 51.444795 -162.877575) (xy 51.407949 -162.775633)
			(xy 51.37876 -162.67124) (xy 51.357388 -162.564971) (xy 51.343951 -162.457411) (xy 51.338522 -162.34915)
			(xy 51.341132 -162.240785) (xy 51.351765 -162.132911) (xy 51.360578 -162.079432) (xy 51.362864 -162.06597)
			(xy 51.353466 -162.040316) (xy 51.264312 -161.966656) (xy 51.237896 -161.962084) (xy 51.224942 -161.96691)
			(xy 51.173891 -161.985361) (xy 51.069222 -162.01416) (xy 50.962401 -162.033507) (xy 50.854279 -162.043245)
			(xy 50.8 -162.043872) (xy 50.752338 -162.043402) (xy 50.657308 -162.035916) (xy 50.563158 -162.020998)
			(xy 50.470469 -161.998739) (xy 50.379811 -161.969278) (xy 50.291744 -161.932795) (xy 50.206811 -161.889516)
			(xy 50.125535 -161.839706) (xy 50.048417 -161.783675) (xy 49.975932 -161.721766) (xy 49.908528 -161.654361)
			(xy 49.877218 -161.618422) (xy 49.869649 -161.610397) (xy 49.849629 -161.601183) (xy 49.83861 -161.600642)
			(xy 49.761394 -161.600642) (xy 49.750373 -161.601163) (xy 49.730356 -161.610393) (xy 49.722786 -161.618422)
			(xy 49.691484 -161.654366) (xy 49.624069 -161.721758) (xy 49.551578 -161.783656) (xy 49.474455 -161.839679)
			(xy 49.393177 -161.889481) (xy 49.308244 -161.932757) (xy 49.220179 -161.969239) (xy 49.129525 -161.998703)
			(xy 49.036839 -162.020967) (xy 48.942692 -162.035894) (xy 48.847665 -162.043393) (xy 48.800004 -162.043872)
			(xy 48.749836 -162.04339) (xy 48.649842 -162.035106) (xy 48.550873 -162.018593) (xy 48.453607 -161.993965)
			(xy 48.358705 -161.961389) (xy 48.266818 -161.921089) (xy 48.178572 -161.873339) (xy 48.09457 -161.818466)
			(xy 48.015385 -161.756844) (xy 47.94156 -161.688895) (xy 47.873597 -161.615081) (xy 47.811961 -161.535908)
			(xy 47.757072 -161.451916) (xy 47.709307 -161.363678) (xy 47.66899 -161.271798) (xy 47.636397 -161.176903)
			(xy 47.611752 -161.07964) (xy 47.595221 -160.980675) (xy 47.586919 -160.880682) (xy 47.586392 -160.830514)
			(xy 47.586392 -160.830006) (xy 47.586892 -160.78235) (xy 47.59436 -160.687331) (xy 47.609257 -160.593191)
			(xy 47.631492 -160.500509) (xy 47.660928 -160.409857) (xy 47.697384 -160.321793) (xy 47.740635 -160.236859)
			(xy 47.790414 -160.15558) (xy 47.846414 -160.078455) (xy 47.908292 -160.00596) (xy 47.975665 -159.938542)
			(xy 48.011588 -159.907224) (xy 48.019597 -159.899639) (xy 48.028824 -159.879632) (xy 48.029368 -159.868616)
			(xy 48.029368 -159.7914) (xy 48.02884 -159.78038) (xy 48.019615 -159.760363) (xy 48.011588 -159.752792)
			(xy 47.973975 -159.719956) (xy 47.903656 -159.649064) (xy 47.839399 -159.572633) (xy 47.781638 -159.491183)
			(xy 47.730764 -159.405262) (xy 47.68712 -159.315453) (xy 47.651001 -159.222361) (xy 47.622653 -159.126618)
			(xy 47.602266 -159.028868) (xy 47.589978 -158.929775) (xy 47.585872 -158.830006) (xy 38.088824 -158.830006)
			(xy 38.088824 -158.83001) (xy 38.088378 -158.877673) (xy 38.080891 -158.972704) (xy 38.065971 -159.066855)
			(xy 38.043711 -159.159545) (xy 38.014248 -159.250203) (xy 37.977763 -159.33827) (xy 37.934481 -159.423203)
			(xy 37.884669 -159.504479) (xy 37.828634 -159.581596) (xy 37.766722 -159.65408) (xy 37.699314 -159.721483)
			(xy 37.663374 -159.752792) (xy 37.655352 -159.760365) (xy 37.646134 -159.780381) (xy 37.645594 -159.7914)
			(xy 37.645594 -159.868616) (xy 37.646125 -159.879636) (xy 37.655349 -159.899652) (xy 37.663374 -159.907224)
			(xy 37.699313 -159.938533) (xy 37.766706 -160.005945) (xy 37.828605 -160.078436) (xy 37.884629 -160.155557)
			(xy 37.934433 -160.236834) (xy 37.977709 -160.321767) (xy 38.014192 -160.409831) (xy 38.043656 -160.500486)
			(xy 38.06592 -160.593171) (xy 38.080847 -160.687318) (xy 38.088345 -160.782345) (xy 38.088824 -160.830006)
			(xy 38.088376 -160.877669) (xy 38.080889 -160.9727) (xy 38.065969 -161.066851) (xy 38.043709 -161.159541)
			(xy 38.014246 -161.250199) (xy 37.977761 -161.338266) (xy 37.93448 -161.423199) (xy 37.884668 -161.504475)
			(xy 37.828634 -161.581592) (xy 37.766722 -161.654076) (xy 37.699314 -161.721479) (xy 37.663374 -161.752788)
			(xy 37.655354 -161.760363) (xy 37.646135 -161.780378) (xy 37.645594 -161.791396) (xy 37.645594 -161.868612)
			(xy 37.646127 -161.879631) (xy 37.65535 -161.899648) (xy 37.663374 -161.90722) (xy 37.699311 -161.938531)
			(xy 37.766704 -162.005943) (xy 37.828603 -162.078433) (xy 37.884627 -162.155554) (xy 37.934431 -162.236831)
			(xy 37.977708 -162.321764) (xy 38.01419 -162.409828) (xy 38.043655 -162.500482) (xy 38.065919 -162.593168)
			(xy 38.080847 -162.687314) (xy 38.088345 -162.782341) (xy 38.088824 -162.830002) (xy 38.088373 -162.877665)
			(xy 38.080886 -162.972696) (xy 38.065967 -163.066846) (xy 38.043707 -163.159536) (xy 38.014244 -163.250194)
			(xy 37.97776 -163.338261) (xy 37.934478 -163.423195) (xy 37.884667 -163.504471) (xy 37.828633 -163.581588)
			(xy 37.766721 -163.654072) (xy 37.699314 -163.721475) (xy 37.663374 -163.752784) (xy 37.655356 -163.76036)
			(xy 37.646136 -163.780374) (xy 37.645594 -163.791392) (xy 37.645594 -163.868608) (xy 37.646129 -163.879627)
			(xy 37.655351 -163.899644) (xy 37.663374 -163.907216) (xy 37.699309 -163.938529) (xy 37.766702 -164.005941)
			(xy 37.828602 -164.078431) (xy 37.884626 -164.155552) (xy 37.93443 -164.236829) (xy 37.977706 -164.321761)
			(xy 38.014189 -164.409825) (xy 38.043654 -164.500479) (xy 38.065919 -164.593164) (xy 38.080846 -164.68731)
			(xy 38.088345 -164.782337) (xy 38.088824 -164.829998) (xy 38.08837 -164.877661) (xy 38.080883 -164.972691)
			(xy 38.065965 -165.066842) (xy 38.043705 -165.159532) (xy 38.014243 -165.25019) (xy 37.977758 -165.338257)
			(xy 37.934477 -165.42319) (xy 37.884666 -165.504466) (xy 37.828632 -165.581584) (xy 37.766721 -165.654068)
			(xy 37.699314 -165.721471) (xy 37.663374 -165.75278) (xy 37.655358 -165.760358) (xy 37.646136 -165.780371)
			(xy 37.645594 -165.791388) (xy 37.645594 -165.868604) (xy 37.646131 -165.879623) (xy 37.655351 -165.899639)
			(xy 37.663374 -165.907212) (xy 37.699307 -165.938527) (xy 37.7667 -166.005939) (xy 37.8286 -166.078429)
			(xy 37.884624 -166.155549) (xy 37.934428 -166.236826) (xy 37.977705 -166.321758) (xy 38.014188 -166.409822)
			(xy 38.043653 -166.500475) (xy 38.065918 -166.593161) (xy 38.080846 -166.687307) (xy 38.088345 -166.782333)
			(xy 38.088824 -166.829994) (xy 38.088367 -166.877657) (xy 38.080881 -166.972687) (xy 38.065962 -167.066838)
			(xy 38.043703 -167.159528) (xy 38.014241 -167.250186) (xy 37.977757 -167.338253) (xy 37.934476 -167.423186)
			(xy 37.884665 -167.504462) (xy 37.828632 -167.58158) (xy 37.766721 -167.654063) (xy 37.736366 -167.684417)
			(xy 65.5137 -167.684417) (xy 65.5137 -167.575771) (xy 65.521631 -167.467414) (xy 65.53745 -167.359925)
			(xy 65.561073 -167.253878) (xy 65.592374 -167.149838) (xy 65.631186 -167.04836) (xy 65.677301 -166.949986)
			(xy 65.730475 -166.855241) (xy 65.790423 -166.76463) (xy 65.856825 -166.678636) (xy 65.929327 -166.597719)
			(xy 66.007542 -166.522311) (xy 66.091053 -166.452812) (xy 66.179414 -166.389595) (xy 66.272154 -166.332997)
			(xy 66.368778 -166.283319) (xy 66.46877 -166.240827) (xy 66.571598 -166.205747) (xy 66.676712 -166.178267)
			(xy 66.783551 -166.158532) (xy 66.891546 -166.146649) (xy 67.00012 -166.142682) (xy 67.108694 -166.146649)
			(xy 67.216689 -166.158532) (xy 67.323528 -166.178267) (xy 67.428642 -166.205747) (xy 67.53147 -166.240827)
			(xy 67.631462 -166.283319) (xy 67.728086 -166.332997) (xy 67.820826 -166.389595) (xy 67.909187 -166.452812)
			(xy 67.992698 -166.522311) (xy 68.070913 -166.597719) (xy 68.143415 -166.678636) (xy 68.209817 -166.76463)
			(xy 68.269765 -166.855241) (xy 68.322939 -166.949986) (xy 68.369054 -167.04836) (xy 68.407866 -167.149838)
			(xy 68.439167 -167.253878) (xy 68.46279 -167.359925) (xy 68.478609 -167.467414) (xy 68.48654 -167.575771)
			(xy 68.487036 -167.630094) (xy 68.48654 -167.684417) (xy 68.478609 -167.792774) (xy 68.46279 -167.900263)
			(xy 68.439167 -168.00631) (xy 68.407866 -168.11035) (xy 68.369054 -168.211828) (xy 68.322939 -168.310202)
			(xy 68.269765 -168.404947) (xy 68.209817 -168.495558) (xy 68.143415 -168.581552) (xy 68.070913 -168.662469)
			(xy 67.992698 -168.737877) (xy 67.909187 -168.807376) (xy 67.820826 -168.870593) (xy 67.728086 -168.927191)
			(xy 67.631462 -168.976869) (xy 67.53147 -169.019361) (xy 67.428642 -169.054441) (xy 67.323528 -169.081921)
			(xy 67.216689 -169.101656) (xy 67.108694 -169.113539) (xy 67.00012 -169.117507) (xy 66.891546 -169.113539)
			(xy 66.783551 -169.101656) (xy 66.676712 -169.081921) (xy 66.571598 -169.054441) (xy 66.46877 -169.019361)
			(xy 66.368778 -168.976869) (xy 66.272154 -168.927191) (xy 66.179414 -168.870593) (xy 66.091053 -168.807376)
			(xy 66.007542 -168.737877) (xy 65.929327 -168.662469) (xy 65.856825 -168.581552) (xy 65.790423 -168.495558)
			(xy 65.730475 -168.404947) (xy 65.677301 -168.310202) (xy 65.631186 -168.211828) (xy 65.592374 -168.11035)
			(xy 65.561073 -168.00631) (xy 65.53745 -167.900263) (xy 65.521631 -167.792774) (xy 65.5137 -167.684417)
			(xy 37.736366 -167.684417) (xy 37.699314 -167.721467) (xy 37.663374 -167.752776) (xy 37.655359 -167.760356)
			(xy 37.646137 -167.780367) (xy 37.645594 -167.791384) (xy 37.645594 -167.8686) (xy 37.646134 -167.879619)
			(xy 37.655352 -167.899635) (xy 37.663374 -167.907208) (xy 37.699305 -167.938525) (xy 37.766698 -168.005937)
			(xy 37.828598 -168.078427) (xy 37.884622 -168.155547) (xy 37.934426 -168.236823) (xy 37.977703 -168.321755)
			(xy 38.014187 -168.409818) (xy 38.043652 -168.500472) (xy 38.065917 -168.593157) (xy 38.080845 -168.687303)
			(xy 38.088345 -168.782329) (xy 38.088824 -168.82999) (xy 38.088352 -168.880176) (xy 38.080064 -168.980205)
			(xy 38.063544 -169.079208) (xy 38.038904 -169.176509) (xy 38.006313 -169.271442) (xy 37.965994 -169.36336)
			(xy 37.918222 -169.451634) (xy 37.863323 -169.535662) (xy 37.801672 -169.614869) (xy 37.733691 -169.688714)
			(xy 37.659844 -169.756693) (xy 37.580636 -169.818341) (xy 37.496607 -169.873238) (xy 37.408331 -169.921008)
			(xy 37.316412 -169.961325) (xy 37.221478 -169.993913) (xy 37.124177 -170.01855) (xy 37.025173 -170.035068)
			(xy 36.925144 -170.043353) (xy 36.874958 -170.043856) (xy 36.827296 -170.04335) (xy 36.732267 -170.035868)
			(xy 36.638118 -170.020954) (xy 36.545429 -169.9987) (xy 36.454772 -169.969242) (xy 36.366705 -169.932763)
			(xy 36.281772 -169.889487) (xy 36.200495 -169.839681) (xy 36.123377 -169.783652) (xy 36.050891 -169.721746)
			(xy 35.983486 -169.654343) (xy 35.952176 -169.618406) (xy 35.944611 -169.610375) (xy 35.924589 -169.601161)
			(xy 35.913568 -169.600626) (xy 35.836352 -169.600626) (xy 35.825335 -169.601184) (xy 35.805318 -169.610389)
			(xy 35.797744 -169.618406) (xy 35.766406 -169.654318) (xy 35.698996 -169.721711) (xy 35.626508 -169.783611)
			(xy 35.54939 -169.839636) (xy 35.468116 -169.889441) (xy 35.383187 -169.93272) (xy 35.295125 -169.969205)
			(xy 35.204474 -169.998672) (xy 35.111791 -170.02094) (xy 35.017647 -170.035872) (xy 34.922622 -170.043375)
			(xy 34.874962 -170.043856) (xy 34.824777 -170.043384) (xy 34.724749 -170.035093) (xy 34.625748 -170.018569)
			(xy 34.52845 -169.993927) (xy 34.433518 -169.961334) (xy 34.341603 -169.921014) (xy 34.253331 -169.87324)
			(xy 34.169305 -169.818341) (xy 34.0901 -169.75669) (xy 34.016256 -169.68871) (xy 33.948279 -169.614863)
			(xy 33.886631 -169.535656) (xy 33.831735 -169.451628) (xy 33.783965 -169.363354) (xy 33.743648 -169.271437)
			(xy 33.711059 -169.176504) (xy 33.686421 -169.079205) (xy 33.669902 -168.980203) (xy 33.661614 -168.880175)
			(xy 33.661096 -168.82999) (xy 32.074156 -168.82999) (xy 32.126179 -168.923115) (xy 32.226147 -169.085474)
			(xy 32.332915 -169.243443) (xy 32.446292 -169.396739) (xy 32.566073 -169.545084) (xy 32.692041 -169.688213)
			(xy 32.823971 -169.825866) (xy 32.961624 -169.957796) (xy 33.104753 -170.083765) (xy 33.253098 -170.203545)
			(xy 33.406394 -170.316922) (xy 33.564363 -170.423691) (xy 33.726721 -170.523659) (xy 33.893176 -170.616647)
			(xy 34.063427 -170.702486) (xy 34.237168 -170.781022) (xy 34.414086 -170.852113) (xy 34.593862 -170.915632)
			(xy 34.776171 -170.971463) (xy 34.960685 -171.019507) (xy 35.147073 -171.059677) (xy 35.334997 -171.0919)
			(xy 35.52412 -171.116118) (xy 35.7141 -171.132288) (xy 35.904595 -171.14038) (xy 35.999928 -171.140882)
		)
		(stroke
			(width 0)
			(type solid)
		)
		(fill yes)
		(layer "In1.Cu")
		(net "GND")
	)
	(gr_circle
		(center 34.874962 -168.82999)
		(end 36.088066 -168.82999)
		(stroke
			(width 0.2)
			(type default)
		)
		(fill no)
		(layer "In1.Cu")
	)
	(gr_circle
		(center 34.874962 -166.829994)
		(end 36.088066 -166.829994)
		(stroke
			(width 0.2)
			(type default)
		)
		(fill no)
		(layer "In1.Cu")
	)
	(gr_circle
		(center 34.874962 -164.829998)
		(end 36.088066 -164.829998)
		(stroke
			(width 0.2)
			(type default)
		)
		(fill no)
		(layer "In1.Cu")
	)
	(gr_circle
		(center 34.874962 -162.830002)
		(end 36.088066 -162.830002)
		(stroke
			(width 0.2)
			(type default)
		)
		(fill no)
		(layer "In1.Cu")
	)
	(gr_circle
		(center 34.874962 -160.830006)
		(end 36.088066 -160.830006)
		(stroke
			(width 0.2)
			(type default)
		)
		(fill no)
		(layer "In1.Cu")
	)
	(gr_circle
		(center 34.874962 -158.83001)
		(end 36.088066 -158.83001)
		(stroke
			(width 0.2)
			(type default)
		)
		(fill no)
		(layer "In1.Cu")
	)
	(gr_circle
		(center 34.874962 -156.830014)
		(end 36.088066 -156.830014)
		(stroke
			(width 0.2)
			(type default)
		)
		(fill no)
		(layer "In1.Cu")
	)
	(gr_circle
		(center 34.874962 -154.830018)
		(end 36.088066 -154.830018)
		(stroke
			(width 0.2)
			(type default)
		)
		(fill no)
		(layer "In1.Cu")
	)
	(gr_circle
		(center 34.874962 -152.830022)
		(end 36.088066 -152.830022)
		(stroke
			(width 0.2)
			(type default)
		)
		(fill no)
		(layer "In1.Cu")
	)
	(gr_circle
		(center 35.858958 -167.769794)
		(end 37.072062 -167.769794)
		(stroke
			(width 0.2)
			(type default)
		)
		(fill no)
		(layer "In1.Cu")
	)
	(gr_circle
		(center 35.858958 -165.769798)
		(end 37.072062 -165.769798)
		(stroke
			(width 0.2)
			(type default)
		)
		(fill no)
		(layer "In1.Cu")
	)
	(gr_circle
		(center 35.858958 -163.769802)
		(end 37.072062 -163.769802)
		(stroke
			(width 0.2)
			(type default)
		)
		(fill no)
		(layer "In1.Cu")
	)
	(gr_circle
		(center 35.858958 -161.769806)
		(end 37.072062 -161.769806)
		(stroke
			(width 0.2)
			(type default)
		)
		(fill no)
		(layer "In1.Cu")
	)
	(gr_circle
		(center 35.858958 -159.76981)
		(end 37.072062 -159.76981)
		(stroke
			(width 0.2)
			(type default)
		)
		(fill no)
		(layer "In1.Cu")
	)
	(gr_circle
		(center 35.858958 -157.769814)
		(end 37.072062 -157.769814)
		(stroke
			(width 0.2)
			(type default)
		)
		(fill no)
		(layer "In1.Cu")
	)
	(gr_circle
		(center 35.858958 -155.769818)
		(end 37.072062 -155.769818)
		(stroke
			(width 0.2)
			(type default)
		)
		(fill no)
		(layer "In1.Cu")
	)
	(gr_circle
		(center 35.858958 -153.769822)
		(end 37.072062 -153.769822)
		(stroke
			(width 0.2)
			(type default)
		)
		(fill no)
		(layer "In1.Cu")
	)
	(gr_circle
		(center 36.874958 -168.82999)
		(end 38.088062 -168.82999)
		(stroke
			(width 0.2)
			(type default)
		)
		(fill no)
		(layer "In1.Cu")
	)
	(gr_circle
		(center 36.874958 -166.829994)
		(end 38.088062 -166.829994)
		(stroke
			(width 0.2)
			(type default)
		)
		(fill no)
		(layer "In1.Cu")
	)
	(gr_circle
		(center 36.874958 -164.829998)
		(end 38.088062 -164.829998)
		(stroke
			(width 0.2)
			(type default)
		)
		(fill no)
		(layer "In1.Cu")
	)
	(gr_circle
		(center 36.874958 -162.830002)
		(end 38.088062 -162.830002)
		(stroke
			(width 0.2)
			(type default)
		)
		(fill no)
		(layer "In1.Cu")
	)
	(gr_circle
		(center 36.874958 -160.830006)
		(end 38.088062 -160.830006)
		(stroke
			(width 0.2)
			(type default)
		)
		(fill no)
		(layer "In1.Cu")
	)
	(gr_circle
		(center 36.874958 -158.83001)
		(end 38.088062 -158.83001)
		(stroke
			(width 0.2)
			(type default)
		)
		(fill no)
		(layer "In1.Cu")
	)
	(gr_circle
		(center 36.874958 -156.830014)
		(end 38.088062 -156.830014)
		(stroke
			(width 0.2)
			(type default)
		)
		(fill no)
		(layer "In1.Cu")
	)
	(gr_circle
		(center 36.874958 -154.830018)
		(end 38.088062 -154.830018)
		(stroke
			(width 0.2)
			(type default)
		)
		(fill no)
		(layer "In1.Cu")
	)
	(gr_circle
		(center 36.874958 -152.830022)
		(end 38.088062 -152.830022)
		(stroke
			(width 0.2)
			(type default)
		)
		(fill no)
		(layer "In1.Cu")
	)
	(gr_circle
		(center 42.36339 -139.7)
		(end 43.88739 -139.7)
		(stroke
			(width 0.2)
			(type default)
		)
		(fill no)
		(layer "In1.Cu")
	)
	(gr_circle
		(center 42.36339 -119.38)
		(end 43.88739 -119.38)
		(stroke
			(width 0.2)
			(type default)
		)
		(fill no)
		(layer "In1.Cu")
	)
	(gr_circle
		(center 42.36339 -99.06)
		(end 43.88739 -99.06)
		(stroke
			(width 0.2)
			(type default)
		)
		(fill no)
		(layer "In1.Cu")
	)
	(gr_circle
		(center 42.36339 -78.74)
		(end 43.88739 -78.74)
		(stroke
			(width 0.2)
			(type default)
		)
		(fill no)
		(layer "In1.Cu")
	)
	(gr_circle
		(center 42.36339 -58.42)
		(end 43.88739 -58.42)
		(stroke
			(width 0.2)
			(type default)
		)
		(fill no)
		(layer "In1.Cu")
	)
	(gr_circle
		(center 48.800004 -160.830006)
		(end 50.013108 -160.830006)
		(stroke
			(width 0.2)
			(type default)
		)
		(fill no)
		(layer "In1.Cu")
	)
	(gr_circle
		(center 48.800004 -158.83001)
		(end 50.013108 -158.83001)
		(stroke
			(width 0.2)
			(type default)
		)
		(fill no)
		(layer "In1.Cu")
	)
	(gr_circle
		(center 48.800004 -156.830014)
		(end 50.013108 -156.830014)
		(stroke
			(width 0.2)
			(type default)
		)
		(fill no)
		(layer "In1.Cu")
	)
	(gr_circle
		(center 49.784 -159.82061)
		(end 50.997104 -159.82061)
		(stroke
			(width 0.2)
			(type default)
		)
		(fill no)
		(layer "In1.Cu")
	)
	(gr_circle
		(center 49.784 -157.820614)
		(end 50.997104 -157.820614)
		(stroke
			(width 0.2)
			(type default)
		)
		(fill no)
		(layer "In1.Cu")
	)
	(gr_circle
		(center 50.8 -160.830006)
		(end 52.013104 -160.830006)
		(stroke
			(width 0.2)
			(type default)
		)
		(fill no)
		(layer "In1.Cu")
	)
	(gr_circle
		(center 50.8 -158.83001)
		(end 52.013104 -158.83001)
		(stroke
			(width 0.2)
			(type default)
		)
		(fill no)
		(layer "In1.Cu")
	)
	(gr_circle
		(center 50.8 -156.830014)
		(end 52.013104 -156.830014)
		(stroke
			(width 0.2)
			(type default)
		)
		(fill no)
		(layer "In1.Cu")
	)
	(gr_circle
		(center 54.799992 -160.830006)
		(end 56.013096 -160.830006)
		(stroke
			(width 0.2)
			(type default)
		)
		(fill no)
		(layer "In1.Cu")
	)
	(gr_circle
		(center 54.799992 -158.83001)
		(end 56.013096 -158.83001)
		(stroke
			(width 0.2)
			(type default)
		)
		(fill no)
		(layer "In1.Cu")
	)
	(gr_circle
		(center 54.799992 -156.830014)
		(end 56.013096 -156.830014)
		(stroke
			(width 0.2)
			(type default)
		)
		(fill no)
		(layer "In1.Cu")
	)
	(gr_circle
		(center 55.707788 -159.79521)
		(end 56.920892 -159.79521)
		(stroke
			(width 0.2)
			(type default)
		)
		(fill no)
		(layer "In1.Cu")
	)
	(gr_circle
		(center 55.707788 -157.795214)
		(end 56.920892 -157.795214)
		(stroke
			(width 0.2)
			(type default)
		)
		(fill no)
		(layer "In1.Cu")
	)
	(gr_circle
		(center 56.799988 -160.830006)
		(end 58.013092 -160.830006)
		(stroke
			(width 0.2)
			(type default)
		)
		(fill no)
		(layer "In1.Cu")
	)
	(gr_circle
		(center 56.799988 -158.83001)
		(end 58.013092 -158.83001)
		(stroke
			(width 0.2)
			(type default)
		)
		(fill no)
		(layer "In1.Cu")
	)
	(gr_circle
		(center 56.799988 -156.830014)
		(end 58.013092 -156.830014)
		(stroke
			(width 0.2)
			(type default)
		)
		(fill no)
		(layer "In1.Cu")
	)
	(gr_circle
		(center 61.92139 -139.7)
		(end 63.44539 -139.7)
		(stroke
			(width 0.2)
			(type default)
		)
		(fill no)
		(layer "In1.Cu")
	)
	(gr_circle
		(center 61.92139 -119.38)
		(end 63.44539 -119.38)
		(stroke
			(width 0.2)
			(type default)
		)
		(fill no)
		(layer "In1.Cu")
	)
	(gr_circle
		(center 61.92139 -99.06)
		(end 63.44539 -99.06)
		(stroke
			(width 0.2)
			(type default)
		)
		(fill no)
		(layer "In1.Cu")
	)
	(gr_circle
		(center 61.92139 -78.74)
		(end 63.44539 -78.74)
		(stroke
			(width 0.2)
			(type default)
		)
		(fill no)
		(layer "In1.Cu")
	)
	(gr_circle
		(center 61.92139 -58.42)
		(end 63.44539 -58.42)
		(stroke
			(width 0.2)
			(type default)
		)
		(fill no)
		(layer "In1.Cu")
	)
	(gr_circle
		(center 63.000128 -160.830006)
		(end 64.213232 -160.830006)
		(stroke
			(width 0.2)
			(type default)
		)
		(fill no)
		(layer "In1.Cu")
	)
	(gr_circle
		(center 63.000128 -158.83001)
		(end 64.213232 -158.83001)
		(stroke
			(width 0.2)
			(type default)
		)
		(fill no)
		(layer "In1.Cu")
	)
	(gr_circle
		(center 63.000128 -156.830014)
		(end 64.213232 -156.830014)
		(stroke
			(width 0.2)
			(type default)
		)
		(fill no)
		(layer "In1.Cu")
	)
	(gr_circle
		(center 63.719964 -2.590038)
		(end 64.933068 -2.590038)
		(stroke
			(width 0.2)
			(type default)
		)
		(fill no)
		(layer "In1.Cu")
	)
	(gr_circle
		(center 63.886588 -159.89681)
		(end 65.099692 -159.89681)
		(stroke
			(width 0.2)
			(type default)
		)
		(fill no)
		(layer "In1.Cu")
	)
	(gr_circle
		(center 63.886588 -157.896814)
		(end 65.099692 -157.896814)
		(stroke
			(width 0.2)
			(type default)
		)
		(fill no)
		(layer "In1.Cu")
	)
	(gr_circle
		(center 65.000124 -160.830006)
		(end 66.213228 -160.830006)
		(stroke
			(width 0.2)
			(type default)
		)
		(fill no)
		(layer "In1.Cu")
	)
	(gr_circle
		(center 65.000124 -158.83001)
		(end 66.213228 -158.83001)
		(stroke
			(width 0.2)
			(type default)
		)
		(fill no)
		(layer "In1.Cu")
	)
	(gr_circle
		(center 65.000124 -156.830014)
		(end 66.213228 -156.830014)
		(stroke
			(width 0.2)
			(type default)
		)
		(fill no)
		(layer "In1.Cu")
	)
	(gr_circle
		(center 66.259964 -2.590038)
		(end 67.473068 -2.590038)
		(stroke
			(width 0.2)
			(type default)
		)
		(fill no)
		(layer "In1.Cu")
	)
	(gr_circle
		(center 69.000116 -160.830006)
		(end 70.21322 -160.830006)
		(stroke
			(width 0.2)
			(type default)
		)
		(fill no)
		(layer "In1.Cu")
	)
	(gr_circle
		(center 69.000116 -158.83001)
		(end 70.21322 -158.83001)
		(stroke
			(width 0.2)
			(type default)
		)
		(fill no)
		(layer "In1.Cu")
	)
	(gr_circle
		(center 69.000116 -156.830014)
		(end 70.21322 -156.830014)
		(stroke
			(width 0.2)
			(type default)
		)
		(fill no)
		(layer "In1.Cu")
	)
	(gr_circle
		(center 70.033388 -159.79521)
		(end 71.246492 -159.79521)
		(stroke
			(width 0.2)
			(type default)
		)
		(fill no)
		(layer "In1.Cu")
	)
	(gr_circle
		(center 70.033388 -157.795214)
		(end 71.246492 -157.795214)
		(stroke
			(width 0.2)
			(type default)
		)
		(fill no)
		(layer "In1.Cu")
	)
	(gr_circle
		(center 71.000112 -160.830006)
		(end 72.213216 -160.830006)
		(stroke
			(width 0.2)
			(type default)
		)
		(fill no)
		(layer "In1.Cu")
	)
	(gr_circle
		(center 71.000112 -158.83001)
		(end 72.213216 -158.83001)
		(stroke
			(width 0.2)
			(type default)
		)
		(fill no)
		(layer "In1.Cu")
	)
	(gr_circle
		(center 71.000112 -156.830014)
		(end 72.213216 -156.830014)
		(stroke
			(width 0.2)
			(type default)
		)
		(fill no)
		(layer "In1.Cu")
	)
	(gr_circle
		(center 75.000104 -160.830006)
		(end 76.213208 -160.830006)
		(stroke
			(width 0.2)
			(type default)
		)
		(fill no)
		(layer "In1.Cu")
	)
	(gr_circle
		(center 75.000104 -158.83001)
		(end 76.213208 -158.83001)
		(stroke
			(width 0.2)
			(type default)
		)
		(fill no)
		(layer "In1.Cu")
	)
	(gr_circle
		(center 75.000104 -156.830014)
		(end 76.213208 -156.830014)
		(stroke
			(width 0.2)
			(type default)
		)
		(fill no)
		(layer "In1.Cu")
	)
	(gr_circle
		(center 76.002388 -159.87141)
		(end 77.215492 -159.87141)
		(stroke
			(width 0.2)
			(type default)
		)
		(fill no)
		(layer "In1.Cu")
	)
	(gr_circle
		(center 76.002388 -157.871414)
		(end 77.215492 -157.871414)
		(stroke
			(width 0.2)
			(type default)
		)
		(fill no)
		(layer "In1.Cu")
	)
	(gr_circle
		(center 77.0001 -160.830006)
		(end 78.213204 -160.830006)
		(stroke
			(width 0.2)
			(type default)
		)
		(fill no)
		(layer "In1.Cu")
	)
	(gr_circle
		(center 77.0001 -158.83001)
		(end 78.213204 -158.83001)
		(stroke
			(width 0.2)
			(type default)
		)
		(fill no)
		(layer "In1.Cu")
	)
	(gr_circle
		(center 77.0001 -156.830014)
		(end 78.213204 -156.830014)
		(stroke
			(width 0.2)
			(type default)
		)
		(fill no)
		(layer "In1.Cu")
	)
	(gr_circle
		(center 82.677 -5.334)
		(end 83.566 -5.334)
		(stroke
			(width 0.2)
			(type default)
		)
		(fill no)
		(layer "In1.Cu")
	)
	(gr_circle
		(center 82.677 -4.572)
		(end 83.566 -4.572)
		(stroke
			(width 0.2)
			(type default)
		)
		(fill no)
		(layer "In1.Cu")
	)
	(gr_circle
		(center 82.677 -3.81)
		(end 83.566 -3.81)
		(stroke
			(width 0.2)
			(type default)
		)
		(fill no)
		(layer "In1.Cu")
	)
	(gr_circle
		(center 83.439 -5.334)
		(end 84.328 -5.334)
		(stroke
			(width 0.2)
			(type default)
		)
		(fill no)
		(layer "In1.Cu")
	)
	(gr_circle
		(center 83.439 -4.572)
		(end 84.328 -4.572)
		(stroke
			(width 0.2)
			(type default)
		)
		(fill no)
		(layer "In1.Cu")
	)
	(gr_circle
		(center 83.439 -3.81)
		(end 84.328 -3.81)
		(stroke
			(width 0.2)
			(type default)
		)
		(fill no)
		(layer "In1.Cu")
	)
	(gr_circle
		(center 84.201 -5.334)
		(end 85.09 -5.334)
		(stroke
			(width 0.2)
			(type default)
		)
		(fill no)
		(layer "In1.Cu")
	)
	(gr_circle
		(center 84.201 -4.572)
		(end 85.09 -4.572)
		(stroke
			(width 0.2)
			(type default)
		)
		(fill no)
		(layer "In1.Cu")
	)
	(gr_circle
		(center 84.201 -3.81)
		(end 85.09 -3.81)
		(stroke
			(width 0.2)
			(type default)
		)
		(fill no)
		(layer "In1.Cu")
	)
	(gr_circle
		(center 84.963 -5.334)
		(end 85.852 -5.334)
		(stroke
			(width 0.2)
			(type default)
		)
		(fill no)
		(layer "In1.Cu")
	)
	(gr_circle
		(center 84.963 -4.572)
		(end 85.852 -4.572)
		(stroke
			(width 0.2)
			(type default)
		)
		(fill no)
		(layer "In1.Cu")
	)
	(gr_circle
		(center 84.963 -3.81)
		(end 85.852 -3.81)
		(stroke
			(width 0.2)
			(type default)
		)
		(fill no)
		(layer "In1.Cu")
	)
	(gr_circle
		(center 85.725 -5.334)
		(end 86.614 -5.334)
		(stroke
			(width 0.2)
			(type default)
		)
		(fill no)
		(layer "In1.Cu")
	)
	(gr_circle
		(center 85.725 -4.572)
		(end 86.614 -4.572)
		(stroke
			(width 0.2)
			(type default)
		)
		(fill no)
		(layer "In1.Cu")
	)
	(gr_circle
		(center 85.725 -3.81)
		(end 86.614 -3.81)
		(stroke
			(width 0.2)
			(type default)
		)
		(fill no)
		(layer "In1.Cu")
	)
	(gr_circle
		(center 86.487 -5.334)
		(end 87.376 -5.334)
		(stroke
			(width 0.2)
			(type default)
		)
		(fill no)
		(layer "In1.Cu")
	)
	(gr_circle
		(center 86.487 -4.572)
		(end 87.376 -4.572)
		(stroke
			(width 0.2)
			(type default)
		)
		(fill no)
		(layer "In1.Cu")
	)
	(gr_circle
		(center 86.487 -3.81)
		(end 87.376 -3.81)
		(stroke
			(width 0.2)
			(type default)
		)
		(fill no)
		(layer "In1.Cu")
	)
	(gr_circle
		(center 108.782358 -42.432224)
		(end 109.671358 -42.432224)
		(stroke
			(width 0.2)
			(type default)
		)
		(fill no)
		(layer "In1.Cu")
	)
	(gr_circle
		(center 109.374432 -53.692806)
		(end 110.263432 -53.692806)
		(stroke
			(width 0.2)
			(type default)
		)
		(fill no)
		(layer "In1.Cu")
	)
	(gr_circle
		(center 111.2774 -54.483)
		(end 112.1664 -54.483)
		(stroke
			(width 0.2)
			(type default)
		)
		(fill no)
		(layer "In1.Cu")
	)
	(gr_circle
		(center 111.2774 -43.18)
		(end 112.1664 -43.18)
		(stroke
			(width 0.2)
			(type default)
		)
		(fill no)
		(layer "In1.Cu")
	)
	(gr_circle
		(center 112.252252 -78.6638)
		(end 113.141252 -78.6638)
		(stroke
			(width 0.2)
			(type default)
		)
		(fill no)
		(layer "In1.Cu")
	)
	(gr_circle
		(center 112.252252 -67.3862)
		(end 113.141252 -67.3862)
		(stroke
			(width 0.2)
			(type default)
		)
		(fill no)
		(layer "In1.Cu")
	)
	(gr_circle
		(center 112.252252 -56.1086)
		(end 113.141252 -56.1086)
		(stroke
			(width 0.2)
			(type default)
		)
		(fill no)
		(layer "In1.Cu")
	)
	(gr_circle
		(center 112.252252 -44.831)
		(end 113.141252 -44.831)
		(stroke
			(width 0.2)
			(type default)
		)
		(fill no)
		(layer "In1.Cu")
	)
	(gr_circle
		(center 112.252252 -33.5534)
		(end 113.141252 -33.5534)
		(stroke
			(width 0.2)
			(type default)
		)
		(fill no)
		(layer "In1.Cu")
	)
	(gr_circle
		(center 112.252252 -22.2758)
		(end 113.141252 -22.2758)
		(stroke
			(width 0.2)
			(type default)
		)
		(fill no)
		(layer "In1.Cu")
	)
	(gr_circle
		(center 112.455452 -73.66)
		(end 113.344452 -73.66)
		(stroke
			(width 0.2)
			(type default)
		)
		(fill no)
		(layer "In1.Cu")
	)
	(gr_circle
		(center 112.455452 -72.898)
		(end 113.344452 -72.898)
		(stroke
			(width 0.2)
			(type default)
		)
		(fill no)
		(layer "In1.Cu")
	)
	(gr_circle
		(center 112.455452 -72.136)
		(end 113.344452 -72.136)
		(stroke
			(width 0.2)
			(type default)
		)
		(fill no)
		(layer "In1.Cu")
	)
	(gr_circle
		(center 112.455452 -71.374)
		(end 113.344452 -71.374)
		(stroke
			(width 0.2)
			(type default)
		)
		(fill no)
		(layer "In1.Cu")
	)
	(gr_circle
		(center 112.455452 -70.612)
		(end 113.344452 -70.612)
		(stroke
			(width 0.2)
			(type default)
		)
		(fill no)
		(layer "In1.Cu")
	)
	(gr_circle
		(center 112.455452 -62.3824)
		(end 113.344452 -62.3824)
		(stroke
			(width 0.2)
			(type default)
		)
		(fill no)
		(layer "In1.Cu")
	)
	(gr_circle
		(center 112.455452 -61.6204)
		(end 113.344452 -61.6204)
		(stroke
			(width 0.2)
			(type default)
		)
		(fill no)
		(layer "In1.Cu")
	)
	(gr_circle
		(center 112.455452 -60.8584)
		(end 113.344452 -60.8584)
		(stroke
			(width 0.2)
			(type default)
		)
		(fill no)
		(layer "In1.Cu")
	)
	(gr_circle
		(center 112.455452 -60.0964)
		(end 113.344452 -60.0964)
		(stroke
			(width 0.2)
			(type default)
		)
		(fill no)
		(layer "In1.Cu")
	)
	(gr_circle
		(center 112.455452 -59.3344)
		(end 113.344452 -59.3344)
		(stroke
			(width 0.2)
			(type default)
		)
		(fill no)
		(layer "In1.Cu")
	)
	(gr_circle
		(center 112.455452 -51.1048)
		(end 113.344452 -51.1048)
		(stroke
			(width 0.2)
			(type default)
		)
		(fill no)
		(layer "In1.Cu")
	)
	(gr_circle
		(center 112.455452 -50.3428)
		(end 113.344452 -50.3428)
		(stroke
			(width 0.2)
			(type default)
		)
		(fill no)
		(layer "In1.Cu")
	)
	(gr_circle
		(center 112.455452 -49.5808)
		(end 113.344452 -49.5808)
		(stroke
			(width 0.2)
			(type default)
		)
		(fill no)
		(layer "In1.Cu")
	)
	(gr_circle
		(center 112.455452 -48.8188)
		(end 113.344452 -48.8188)
		(stroke
			(width 0.2)
			(type default)
		)
		(fill no)
		(layer "In1.Cu")
	)
	(gr_circle
		(center 112.455452 -48.0568)
		(end 113.344452 -48.0568)
		(stroke
			(width 0.2)
			(type default)
		)
		(fill no)
		(layer "In1.Cu")
	)
	(gr_circle
		(center 112.455452 -39.8272)
		(end 113.344452 -39.8272)
		(stroke
			(width 0.2)
			(type default)
		)
		(fill no)
		(layer "In1.Cu")
	)
	(gr_circle
		(center 112.455452 -39.0652)
		(end 113.344452 -39.0652)
		(stroke
			(width 0.2)
			(type default)
		)
		(fill no)
		(layer "In1.Cu")
	)
	(gr_circle
		(center 112.455452 -38.3032)
		(end 113.344452 -38.3032)
		(stroke
			(width 0.2)
			(type default)
		)
		(fill no)
		(layer "In1.Cu")
	)
	(gr_circle
		(center 112.455452 -37.5412)
		(end 113.344452 -37.5412)
		(stroke
			(width 0.2)
			(type default)
		)
		(fill no)
		(layer "In1.Cu")
	)
	(gr_circle
		(center 112.455452 -36.7792)
		(end 113.344452 -36.7792)
		(stroke
			(width 0.2)
			(type default)
		)
		(fill no)
		(layer "In1.Cu")
	)
	(gr_circle
		(center 112.455452 -28.5496)
		(end 113.344452 -28.5496)
		(stroke
			(width 0.2)
			(type default)
		)
		(fill no)
		(layer "In1.Cu")
	)
	(gr_circle
		(center 112.455452 -27.7876)
		(end 113.344452 -27.7876)
		(stroke
			(width 0.2)
			(type default)
		)
		(fill no)
		(layer "In1.Cu")
	)
	(gr_circle
		(center 112.455452 -27.0256)
		(end 113.344452 -27.0256)
		(stroke
			(width 0.2)
			(type default)
		)
		(fill no)
		(layer "In1.Cu")
	)
	(gr_circle
		(center 112.455452 -26.2636)
		(end 113.344452 -26.2636)
		(stroke
			(width 0.2)
			(type default)
		)
		(fill no)
		(layer "In1.Cu")
	)
	(gr_circle
		(center 112.455452 -25.5016)
		(end 113.344452 -25.5016)
		(stroke
			(width 0.2)
			(type default)
		)
		(fill no)
		(layer "In1.Cu")
	)
	(gr_circle
		(center 112.455452 -17.272)
		(end 113.344452 -17.272)
		(stroke
			(width 0.2)
			(type default)
		)
		(fill no)
		(layer "In1.Cu")
	)
	(gr_circle
		(center 112.455452 -16.51)
		(end 113.344452 -16.51)
		(stroke
			(width 0.2)
			(type default)
		)
		(fill no)
		(layer "In1.Cu")
	)
	(gr_circle
		(center 112.455452 -15.748)
		(end 113.344452 -15.748)
		(stroke
			(width 0.2)
			(type default)
		)
		(fill no)
		(layer "In1.Cu")
	)
	(gr_circle
		(center 112.455452 -14.986)
		(end 113.344452 -14.986)
		(stroke
			(width 0.2)
			(type default)
		)
		(fill no)
		(layer "In1.Cu")
	)
	(gr_circle
		(center 112.455452 -14.224)
		(end 113.344452 -14.224)
		(stroke
			(width 0.2)
			(type default)
		)
		(fill no)
		(layer "In1.Cu")
	)
	(gr_circle
		(center 113.217452 -73.66)
		(end 114.106452 -73.66)
		(stroke
			(width 0.2)
			(type default)
		)
		(fill no)
		(layer "In1.Cu")
	)
	(gr_circle
		(center 113.217452 -72.898)
		(end 114.106452 -72.898)
		(stroke
			(width 0.2)
			(type default)
		)
		(fill no)
		(layer "In1.Cu")
	)
	(gr_circle
		(center 113.217452 -72.136)
		(end 114.106452 -72.136)
		(stroke
			(width 0.2)
			(type default)
		)
		(fill no)
		(layer "In1.Cu")
	)
	(gr_circle
		(center 113.217452 -71.374)
		(end 114.106452 -71.374)
		(stroke
			(width 0.2)
			(type default)
		)
		(fill no)
		(layer "In1.Cu")
	)
	(gr_circle
		(center 113.217452 -70.612)
		(end 114.106452 -70.612)
		(stroke
			(width 0.2)
			(type default)
		)
		(fill no)
		(layer "In1.Cu")
	)
	(gr_circle
		(center 113.217452 -62.3824)
		(end 114.106452 -62.3824)
		(stroke
			(width 0.2)
			(type default)
		)
		(fill no)
		(layer "In1.Cu")
	)
	(gr_circle
		(center 113.217452 -61.6204)
		(end 114.106452 -61.6204)
		(stroke
			(width 0.2)
			(type default)
		)
		(fill no)
		(layer "In1.Cu")
	)
	(gr_circle
		(center 113.217452 -60.8584)
		(end 114.106452 -60.8584)
		(stroke
			(width 0.2)
			(type default)
		)
		(fill no)
		(layer "In1.Cu")
	)
	(gr_circle
		(center 113.217452 -60.0964)
		(end 114.106452 -60.0964)
		(stroke
			(width 0.2)
			(type default)
		)
		(fill no)
		(layer "In1.Cu")
	)
	(gr_circle
		(center 113.217452 -59.3344)
		(end 114.106452 -59.3344)
		(stroke
			(width 0.2)
			(type default)
		)
		(fill no)
		(layer "In1.Cu")
	)
	(gr_circle
		(center 113.217452 -51.1048)
		(end 114.106452 -51.1048)
		(stroke
			(width 0.2)
			(type default)
		)
		(fill no)
		(layer "In1.Cu")
	)
	(gr_circle
		(center 113.217452 -50.3428)
		(end 114.106452 -50.3428)
		(stroke
			(width 0.2)
			(type default)
		)
		(fill no)
		(layer "In1.Cu")
	)
	(gr_circle
		(center 113.217452 -49.5808)
		(end 114.106452 -49.5808)
		(stroke
			(width 0.2)
			(type default)
		)
		(fill no)
		(layer "In1.Cu")
	)
	(gr_circle
		(center 113.217452 -48.8188)
		(end 114.106452 -48.8188)
		(stroke
			(width 0.2)
			(type default)
		)
		(fill no)
		(layer "In1.Cu")
	)
	(gr_circle
		(center 113.217452 -48.0568)
		(end 114.106452 -48.0568)
		(stroke
			(width 0.2)
			(type default)
		)
		(fill no)
		(layer "In1.Cu")
	)
	(gr_circle
		(center 113.217452 -39.8272)
		(end 114.106452 -39.8272)
		(stroke
			(width 0.2)
			(type default)
		)
		(fill no)
		(layer "In1.Cu")
	)
	(gr_circle
		(center 113.217452 -39.0652)
		(end 114.106452 -39.0652)
		(stroke
			(width 0.2)
			(type default)
		)
		(fill no)
		(layer "In1.Cu")
	)
	(gr_circle
		(center 113.217452 -38.3032)
		(end 114.106452 -38.3032)
		(stroke
			(width 0.2)
			(type default)
		)
		(fill no)
		(layer "In1.Cu")
	)
	(gr_circle
		(center 113.217452 -37.5412)
		(end 114.106452 -37.5412)
		(stroke
			(width 0.2)
			(type default)
		)
		(fill no)
		(layer "In1.Cu")
	)
	(gr_circle
		(center 113.217452 -36.7792)
		(end 114.106452 -36.7792)
		(stroke
			(width 0.2)
			(type default)
		)
		(fill no)
		(layer "In1.Cu")
	)
	(gr_circle
		(center 113.217452 -28.5496)
		(end 114.106452 -28.5496)
		(stroke
			(width 0.2)
			(type default)
		)
		(fill no)
		(layer "In1.Cu")
	)
	(gr_circle
		(center 113.217452 -27.7876)
		(end 114.106452 -27.7876)
		(stroke
			(width 0.2)
			(type default)
		)
		(fill no)
		(layer "In1.Cu")
	)
	(gr_circle
		(center 113.217452 -27.0256)
		(end 114.106452 -27.0256)
		(stroke
			(width 0.2)
			(type default)
		)
		(fill no)
		(layer "In1.Cu")
	)
	(gr_circle
		(center 113.217452 -26.2636)
		(end 114.106452 -26.2636)
		(stroke
			(width 0.2)
			(type default)
		)
		(fill no)
		(layer "In1.Cu")
	)
	(gr_circle
		(center 113.217452 -25.5016)
		(end 114.106452 -25.5016)
		(stroke
			(width 0.2)
			(type default)
		)
		(fill no)
		(layer "In1.Cu")
	)
	(gr_circle
		(center 113.217452 -17.272)
		(end 114.106452 -17.272)
		(stroke
			(width 0.2)
			(type default)
		)
		(fill no)
		(layer "In1.Cu")
	)
	(gr_circle
		(center 113.217452 -16.51)
		(end 114.106452 -16.51)
		(stroke
			(width 0.2)
			(type default)
		)
		(fill no)
		(layer "In1.Cu")
	)
	(gr_circle
		(center 113.217452 -15.748)
		(end 114.106452 -15.748)
		(stroke
			(width 0.2)
			(type default)
		)
		(fill no)
		(layer "In1.Cu")
	)
	(gr_circle
		(center 113.217452 -14.986)
		(end 114.106452 -14.986)
		(stroke
			(width 0.2)
			(type default)
		)
		(fill no)
		(layer "In1.Cu")
	)
	(gr_circle
		(center 113.217452 -14.224)
		(end 114.106452 -14.224)
		(stroke
			(width 0.2)
			(type default)
		)
		(fill no)
		(layer "In1.Cu")
	)
	(gr_circle
		(center 113.979452 -73.66)
		(end 114.868452 -73.66)
		(stroke
			(width 0.2)
			(type default)
		)
		(fill no)
		(layer "In1.Cu")
	)
	(gr_circle
		(center 113.979452 -72.898)
		(end 114.868452 -72.898)
		(stroke
			(width 0.2)
			(type default)
		)
		(fill no)
		(layer "In1.Cu")
	)
	(gr_circle
		(center 113.979452 -72.136)
		(end 114.868452 -72.136)
		(stroke
			(width 0.2)
			(type default)
		)
		(fill no)
		(layer "In1.Cu")
	)
	(gr_circle
		(center 113.979452 -71.374)
		(end 114.868452 -71.374)
		(stroke
			(width 0.2)
			(type default)
		)
		(fill no)
		(layer "In1.Cu")
	)
	(gr_circle
		(center 113.979452 -70.612)
		(end 114.868452 -70.612)
		(stroke
			(width 0.2)
			(type default)
		)
		(fill no)
		(layer "In1.Cu")
	)
	(gr_circle
		(center 113.979452 -62.3824)
		(end 114.868452 -62.3824)
		(stroke
			(width 0.2)
			(type default)
		)
		(fill no)
		(layer "In1.Cu")
	)
	(gr_circle
		(center 113.979452 -61.6204)
		(end 114.868452 -61.6204)
		(stroke
			(width 0.2)
			(type default)
		)
		(fill no)
		(layer "In1.Cu")
	)
	(gr_circle
		(center 113.979452 -60.8584)
		(end 114.868452 -60.8584)
		(stroke
			(width 0.2)
			(type default)
		)
		(fill no)
		(layer "In1.Cu")
	)
	(gr_circle
		(center 113.979452 -60.0964)
		(end 114.868452 -60.0964)
		(stroke
			(width 0.2)
			(type default)
		)
		(fill no)
		(layer "In1.Cu")
	)
	(gr_circle
		(center 113.979452 -59.3344)
		(end 114.868452 -59.3344)
		(stroke
			(width 0.2)
			(type default)
		)
		(fill no)
		(layer "In1.Cu")
	)
	(gr_circle
		(center 113.979452 -51.1048)
		(end 114.868452 -51.1048)
		(stroke
			(width 0.2)
			(type default)
		)
		(fill no)
		(layer "In1.Cu")
	)
	(gr_circle
		(center 113.979452 -50.3428)
		(end 114.868452 -50.3428)
		(stroke
			(width 0.2)
			(type default)
		)
		(fill no)
		(layer "In1.Cu")
	)
	(gr_circle
		(center 113.979452 -49.5808)
		(end 114.868452 -49.5808)
		(stroke
			(width 0.2)
			(type default)
		)
		(fill no)
		(layer "In1.Cu")
	)
	(gr_circle
		(center 113.979452 -48.8188)
		(end 114.868452 -48.8188)
		(stroke
			(width 0.2)
			(type default)
		)
		(fill no)
		(layer "In1.Cu")
	)
	(gr_circle
		(center 113.979452 -48.0568)
		(end 114.868452 -48.0568)
		(stroke
			(width 0.2)
			(type default)
		)
		(fill no)
		(layer "In1.Cu")
	)
	(gr_circle
		(center 113.979452 -39.8272)
		(end 114.868452 -39.8272)
		(stroke
			(width 0.2)
			(type default)
		)
		(fill no)
		(layer "In1.Cu")
	)
	(gr_circle
		(center 113.979452 -39.0652)
		(end 114.868452 -39.0652)
		(stroke
			(width 0.2)
			(type default)
		)
		(fill no)
		(layer "In1.Cu")
	)
	(gr_circle
		(center 113.979452 -38.3032)
		(end 114.868452 -38.3032)
		(stroke
			(width 0.2)
			(type default)
		)
		(fill no)
		(layer "In1.Cu")
	)
	(gr_circle
		(center 113.979452 -37.5412)
		(end 114.868452 -37.5412)
		(stroke
			(width 0.2)
			(type default)
		)
		(fill no)
		(layer "In1.Cu")
	)
	(gr_circle
		(center 113.979452 -36.7792)
		(end 114.868452 -36.7792)
		(stroke
			(width 0.2)
			(type default)
		)
		(fill no)
		(layer "In1.Cu")
	)
	(gr_circle
		(center 113.979452 -28.5496)
		(end 114.868452 -28.5496)
		(stroke
			(width 0.2)
			(type default)
		)
		(fill no)
		(layer "In1.Cu")
	)
	(gr_circle
		(center 113.979452 -27.7876)
		(end 114.868452 -27.7876)
		(stroke
			(width 0.2)
			(type default)
		)
		(fill no)
		(layer "In1.Cu")
	)
	(gr_circle
		(center 113.979452 -27.0256)
		(end 114.868452 -27.0256)
		(stroke
			(width 0.2)
			(type default)
		)
		(fill no)
		(layer "In1.Cu")
	)
	(gr_circle
		(center 113.979452 -26.2636)
		(end 114.868452 -26.2636)
		(stroke
			(width 0.2)
			(type default)
		)
		(fill no)
		(layer "In1.Cu")
	)
	(gr_circle
		(center 113.979452 -25.5016)
		(end 114.868452 -25.5016)
		(stroke
			(width 0.2)
			(type default)
		)
		(fill no)
		(layer "In1.Cu")
	)
	(gr_circle
		(center 113.979452 -17.272)
		(end 114.868452 -17.272)
		(stroke
			(width 0.2)
			(type default)
		)
		(fill no)
		(layer "In1.Cu")
	)
	(gr_circle
		(center 113.979452 -16.51)
		(end 114.868452 -16.51)
		(stroke
			(width 0.2)
			(type default)
		)
		(fill no)
		(layer "In1.Cu")
	)
	(gr_circle
		(center 113.979452 -15.748)
		(end 114.868452 -15.748)
		(stroke
			(width 0.2)
			(type default)
		)
		(fill no)
		(layer "In1.Cu")
	)
	(gr_circle
		(center 113.979452 -14.986)
		(end 114.868452 -14.986)
		(stroke
			(width 0.2)
			(type default)
		)
		(fill no)
		(layer "In1.Cu")
	)
	(gr_circle
		(center 113.979452 -14.224)
		(end 114.868452 -14.224)
		(stroke
			(width 0.2)
			(type default)
		)
		(fill no)
		(layer "In1.Cu")
	)
	(gr_circle
		(center 114.741452 -73.66)
		(end 115.630452 -73.66)
		(stroke
			(width 0.2)
			(type default)
		)
		(fill no)
		(layer "In1.Cu")
	)
	(gr_circle
		(center 114.741452 -72.898)
		(end 115.630452 -72.898)
		(stroke
			(width 0.2)
			(type default)
		)
		(fill no)
		(layer "In1.Cu")
	)
	(gr_circle
		(center 114.741452 -72.136)
		(end 115.630452 -72.136)
		(stroke
			(width 0.2)
			(type default)
		)
		(fill no)
		(layer "In1.Cu")
	)
	(gr_circle
		(center 114.741452 -71.374)
		(end 115.630452 -71.374)
		(stroke
			(width 0.2)
			(type default)
		)
		(fill no)
		(layer "In1.Cu")
	)
	(gr_circle
		(center 114.741452 -70.612)
		(end 115.630452 -70.612)
		(stroke
			(width 0.2)
			(type default)
		)
		(fill no)
		(layer "In1.Cu")
	)
	(gr_circle
		(center 114.741452 -62.3824)
		(end 115.630452 -62.3824)
		(stroke
			(width 0.2)
			(type default)
		)
		(fill no)
		(layer "In1.Cu")
	)
	(gr_circle
		(center 114.741452 -61.6204)
		(end 115.630452 -61.6204)
		(stroke
			(width 0.2)
			(type default)
		)
		(fill no)
		(layer "In1.Cu")
	)
	(gr_circle
		(center 114.741452 -60.8584)
		(end 115.630452 -60.8584)
		(stroke
			(width 0.2)
			(type default)
		)
		(fill no)
		(layer "In1.Cu")
	)
	(gr_circle
		(center 114.741452 -60.0964)
		(end 115.630452 -60.0964)
		(stroke
			(width 0.2)
			(type default)
		)
		(fill no)
		(layer "In1.Cu")
	)
	(gr_circle
		(center 114.741452 -59.3344)
		(end 115.630452 -59.3344)
		(stroke
			(width 0.2)
			(type default)
		)
		(fill no)
		(layer "In1.Cu")
	)
	(gr_circle
		(center 114.741452 -51.1048)
		(end 115.630452 -51.1048)
		(stroke
			(width 0.2)
			(type default)
		)
		(fill no)
		(layer "In1.Cu")
	)
	(gr_circle
		(center 114.741452 -50.3428)
		(end 115.630452 -50.3428)
		(stroke
			(width 0.2)
			(type default)
		)
		(fill no)
		(layer "In1.Cu")
	)
	(gr_circle
		(center 114.741452 -49.5808)
		(end 115.630452 -49.5808)
		(stroke
			(width 0.2)
			(type default)
		)
		(fill no)
		(layer "In1.Cu")
	)
	(gr_circle
		(center 114.741452 -48.8188)
		(end 115.630452 -48.8188)
		(stroke
			(width 0.2)
			(type default)
		)
		(fill no)
		(layer "In1.Cu")
	)
	(gr_circle
		(center 114.741452 -48.0568)
		(end 115.630452 -48.0568)
		(stroke
			(width 0.2)
			(type default)
		)
		(fill no)
		(layer "In1.Cu")
	)
	(gr_circle
		(center 114.741452 -39.8272)
		(end 115.630452 -39.8272)
		(stroke
			(width 0.2)
			(type default)
		)
		(fill no)
		(layer "In1.Cu")
	)
	(gr_circle
		(center 114.741452 -39.0652)
		(end 115.630452 -39.0652)
		(stroke
			(width 0.2)
			(type default)
		)
		(fill no)
		(layer "In1.Cu")
	)
	(gr_circle
		(center 114.741452 -38.3032)
		(end 115.630452 -38.3032)
		(stroke
			(width 0.2)
			(type default)
		)
		(fill no)
		(layer "In1.Cu")
	)
	(gr_circle
		(center 114.741452 -37.5412)
		(end 115.630452 -37.5412)
		(stroke
			(width 0.2)
			(type default)
		)
		(fill no)
		(layer "In1.Cu")
	)
	(gr_circle
		(center 114.741452 -36.7792)
		(end 115.630452 -36.7792)
		(stroke
			(width 0.2)
			(type default)
		)
		(fill no)
		(layer "In1.Cu")
	)
	(gr_circle
		(center 114.741452 -28.5496)
		(end 115.630452 -28.5496)
		(stroke
			(width 0.2)
			(type default)
		)
		(fill no)
		(layer "In1.Cu")
	)
	(gr_circle
		(center 114.741452 -27.7876)
		(end 115.630452 -27.7876)
		(stroke
			(width 0.2)
			(type default)
		)
		(fill no)
		(layer "In1.Cu")
	)
	(gr_circle
		(center 114.741452 -27.0256)
		(end 115.630452 -27.0256)
		(stroke
			(width 0.2)
			(type default)
		)
		(fill no)
		(layer "In1.Cu")
	)
	(gr_circle
		(center 114.741452 -26.2636)
		(end 115.630452 -26.2636)
		(stroke
			(width 0.2)
			(type default)
		)
		(fill no)
		(layer "In1.Cu")
	)
	(gr_circle
		(center 114.741452 -25.5016)
		(end 115.630452 -25.5016)
		(stroke
			(width 0.2)
			(type default)
		)
		(fill no)
		(layer "In1.Cu")
	)
	(gr_circle
		(center 114.741452 -17.272)
		(end 115.630452 -17.272)
		(stroke
			(width 0.2)
			(type default)
		)
		(fill no)
		(layer "In1.Cu")
	)
	(gr_circle
		(center 114.741452 -16.51)
		(end 115.630452 -16.51)
		(stroke
			(width 0.2)
			(type default)
		)
		(fill no)
		(layer "In1.Cu")
	)
	(gr_circle
		(center 114.741452 -15.748)
		(end 115.630452 -15.748)
		(stroke
			(width 0.2)
			(type default)
		)
		(fill no)
		(layer "In1.Cu")
	)
	(gr_circle
		(center 114.741452 -14.986)
		(end 115.630452 -14.986)
		(stroke
			(width 0.2)
			(type default)
		)
		(fill no)
		(layer "In1.Cu")
	)
	(gr_circle
		(center 114.741452 -14.224)
		(end 115.630452 -14.224)
		(stroke
			(width 0.2)
			(type default)
		)
		(fill no)
		(layer "In1.Cu")
	)
	(gr_circle
		(center 115.503452 -73.66)
		(end 116.392452 -73.66)
		(stroke
			(width 0.2)
			(type default)
		)
		(fill no)
		(layer "In1.Cu")
	)
	(gr_circle
		(center 115.503452 -72.898)
		(end 116.392452 -72.898)
		(stroke
			(width 0.2)
			(type default)
		)
		(fill no)
		(layer "In1.Cu")
	)
	(gr_circle
		(center 115.503452 -72.136)
		(end 116.392452 -72.136)
		(stroke
			(width 0.2)
			(type default)
		)
		(fill no)
		(layer "In1.Cu")
	)
	(gr_circle
		(center 115.503452 -71.374)
		(end 116.392452 -71.374)
		(stroke
			(width 0.2)
			(type default)
		)
		(fill no)
		(layer "In1.Cu")
	)
	(gr_circle
		(center 115.503452 -70.612)
		(end 116.392452 -70.612)
		(stroke
			(width 0.2)
			(type default)
		)
		(fill no)
		(layer "In1.Cu")
	)
	(gr_circle
		(center 115.503452 -62.3824)
		(end 116.392452 -62.3824)
		(stroke
			(width 0.2)
			(type default)
		)
		(fill no)
		(layer "In1.Cu")
	)
	(gr_circle
		(center 115.503452 -61.6204)
		(end 116.392452 -61.6204)
		(stroke
			(width 0.2)
			(type default)
		)
		(fill no)
		(layer "In1.Cu")
	)
	(gr_circle
		(center 115.503452 -60.8584)
		(end 116.392452 -60.8584)
		(stroke
			(width 0.2)
			(type default)
		)
		(fill no)
		(layer "In1.Cu")
	)
	(gr_circle
		(center 115.503452 -60.0964)
		(end 116.392452 -60.0964)
		(stroke
			(width 0.2)
			(type default)
		)
		(fill no)
		(layer "In1.Cu")
	)
	(gr_circle
		(center 115.503452 -59.3344)
		(end 116.392452 -59.3344)
		(stroke
			(width 0.2)
			(type default)
		)
		(fill no)
		(layer "In1.Cu")
	)
	(gr_circle
		(center 115.503452 -51.1048)
		(end 116.392452 -51.1048)
		(stroke
			(width 0.2)
			(type default)
		)
		(fill no)
		(layer "In1.Cu")
	)
	(gr_circle
		(center 115.503452 -50.3428)
		(end 116.392452 -50.3428)
		(stroke
			(width 0.2)
			(type default)
		)
		(fill no)
		(layer "In1.Cu")
	)
	(gr_circle
		(center 115.503452 -49.5808)
		(end 116.392452 -49.5808)
		(stroke
			(width 0.2)
			(type default)
		)
		(fill no)
		(layer "In1.Cu")
	)
	(gr_circle
		(center 115.503452 -48.8188)
		(end 116.392452 -48.8188)
		(stroke
			(width 0.2)
			(type default)
		)
		(fill no)
		(layer "In1.Cu")
	)
	(gr_circle
		(center 115.503452 -48.0568)
		(end 116.392452 -48.0568)
		(stroke
			(width 0.2)
			(type default)
		)
		(fill no)
		(layer "In1.Cu")
	)
	(gr_circle
		(center 115.503452 -39.8272)
		(end 116.392452 -39.8272)
		(stroke
			(width 0.2)
			(type default)
		)
		(fill no)
		(layer "In1.Cu")
	)
	(gr_circle
		(center 115.503452 -39.0652)
		(end 116.392452 -39.0652)
		(stroke
			(width 0.2)
			(type default)
		)
		(fill no)
		(layer "In1.Cu")
	)
	(gr_circle
		(center 115.503452 -38.3032)
		(end 116.392452 -38.3032)
		(stroke
			(width 0.2)
			(type default)
		)
		(fill no)
		(layer "In1.Cu")
	)
	(gr_circle
		(center 115.503452 -37.5412)
		(end 116.392452 -37.5412)
		(stroke
			(width 0.2)
			(type default)
		)
		(fill no)
		(layer "In1.Cu")
	)
	(gr_circle
		(center 115.503452 -36.7792)
		(end 116.392452 -36.7792)
		(stroke
			(width 0.2)
			(type default)
		)
		(fill no)
		(layer "In1.Cu")
	)
	(gr_circle
		(center 115.503452 -28.5496)
		(end 116.392452 -28.5496)
		(stroke
			(width 0.2)
			(type default)
		)
		(fill no)
		(layer "In1.Cu")
	)
	(gr_circle
		(center 115.503452 -27.7876)
		(end 116.392452 -27.7876)
		(stroke
			(width 0.2)
			(type default)
		)
		(fill no)
		(layer "In1.Cu")
	)
	(gr_circle
		(center 115.503452 -27.0256)
		(end 116.392452 -27.0256)
		(stroke
			(width 0.2)
			(type default)
		)
		(fill no)
		(layer "In1.Cu")
	)
	(gr_circle
		(center 115.503452 -26.2636)
		(end 116.392452 -26.2636)
		(stroke
			(width 0.2)
			(type default)
		)
		(fill no)
		(layer "In1.Cu")
	)
	(gr_circle
		(center 115.503452 -25.5016)
		(end 116.392452 -25.5016)
		(stroke
			(width 0.2)
			(type default)
		)
		(fill no)
		(layer "In1.Cu")
	)
	(gr_circle
		(center 115.503452 -17.272)
		(end 116.392452 -17.272)
		(stroke
			(width 0.2)
			(type default)
		)
		(fill no)
		(layer "In1.Cu")
	)
	(gr_circle
		(center 115.503452 -16.51)
		(end 116.392452 -16.51)
		(stroke
			(width 0.2)
			(type default)
		)
		(fill no)
		(layer "In1.Cu")
	)
	(gr_circle
		(center 115.503452 -15.748)
		(end 116.392452 -15.748)
		(stroke
			(width 0.2)
			(type default)
		)
		(fill no)
		(layer "In1.Cu")
	)
	(gr_circle
		(center 115.503452 -14.986)
		(end 116.392452 -14.986)
		(stroke
			(width 0.2)
			(type default)
		)
		(fill no)
		(layer "In1.Cu")
	)
	(gr_circle
		(center 115.503452 -14.224)
		(end 116.392452 -14.224)
		(stroke
			(width 0.2)
			(type default)
		)
		(fill no)
		(layer "In1.Cu")
	)
	(gr_line
		(start 122.8344 -79.883)
		(end 123.4694 -80.518)
		(stroke
			(width 1.016)
			(type default)
		)
		(layer "In1.Cu")
	)
	(gr_line
		(start 122.8344 -46.863)
		(end 122.8344 -79.883)
		(stroke
			(width 1.016)
			(type default)
		)
		(layer "In1.Cu")
	)
	(gr_line
		(start 122.8344 -46.863)
		(end 122.8344 -13.081)
		(stroke
			(width 1.016)
			(type default)
		)
		(layer "In1.Cu")
	)
	(gr_line
		(start 122.8344 -13.081)
		(end 123.4694 -12.446)
		(stroke
			(width 1.016)
			(type default)
		)
		(layer "In1.Cu")
	)
	(gr_line
		(start 123.3424 -46.355)
		(end 122.8344 -46.863)
		(stroke
			(width 1.016)
			(type default)
		)
		(layer "In1.Cu")
	)
	(gr_line
		(start 123.3424 -46.355)
		(end 122.8344 -45.847)
		(stroke
			(width 1.016)
			(type default)
		)
		(layer "In1.Cu")
	)
	(gr_line
		(start 123.4694 -80.518)
		(end 136.23925 -80.518)
		(stroke
			(width 1.016)
			(type default)
		)
		(layer "In1.Cu")
	)
	(gr_line
		(start 136.23925 -80.518)
		(end 136.86663 -79.89062)
		(stroke
			(width 1.016)
			(type default)
		)
		(layer "In1.Cu")
	)
	(gr_line
		(start 136.86663 -79.89062)
		(end 136.86663 -68.303902)
		(stroke
			(width 1.016)
			(type default)
		)
		(layer "In1.Cu")
	)
	(gr_line
		(start 136.86663 -68.303902)
		(end 137.855706 -67.314826)
		(stroke
			(width 1.016)
			(type default)
		)
		(layer "In1.Cu")
	)
	(gr_line
		(start 137.855706 -67.314826)
		(end 148.668232 -67.314826)
		(stroke
			(width 1.016)
			(type default)
		)
		(layer "In1.Cu")
	)
	(gr_line
		(start 138.049 -38.862)
		(end 139.1666 -39.9796)
		(stroke
			(width 1.016)
			(type default)
		)
		(layer "In1.Cu")
	)
	(gr_line
		(start 138.049 -33.8328)
		(end 138.049 -38.862)
		(stroke
			(width 1.016)
			(type default)
		)
		(layer "In1.Cu")
	)
	(gr_line
		(start 138.2268 -38.2524)
		(end 147.066 -38.2524)
		(stroke
			(width 1.016)
			(type default)
		)
		(layer "In1.Cu")
	)
	(gr_line
		(start 138.2268 -37.6682)
		(end 147.066 -37.6682)
		(stroke
			(width 1.016)
			(type default)
		)
		(layer "In1.Cu")
	)
	(gr_line
		(start 138.2522 -37.0586)
		(end 147.0914 -37.0586)
		(stroke
			(width 1.016)
			(type default)
		)
		(layer "In1.Cu")
	)
	(gr_line
		(start 138.2522 -34.8742)
		(end 147.0914 -34.8742)
		(stroke
			(width 1.016)
			(type default)
		)
		(layer "In1.Cu")
	)
	(gr_line
		(start 138.2776 -36.3474)
		(end 147.1168 -36.3474)
		(stroke
			(width 1.016)
			(type default)
		)
		(layer "In1.Cu")
	)
	(gr_line
		(start 138.303 -35.6616)
		(end 147.1422 -35.6616)
		(stroke
			(width 1.016)
			(type default)
		)
		(layer "In1.Cu")
	)
	(gr_line
		(start 138.34872 -33.53308)
		(end 138.049 -33.8328)
		(stroke
			(width 1.016)
			(type default)
		)
		(layer "In1.Cu")
	)
	(gr_line
		(start 138.3538 -34.2392)
		(end 147.193 -34.2392)
		(stroke
			(width 1.016)
			(type default)
		)
		(layer "In1.Cu")
	)
	(gr_line
		(start 138.3792 -38.7604)
		(end 147.2184 -38.7604)
		(stroke
			(width 1.016)
			(type default)
		)
		(layer "In1.Cu")
	)
	(gr_line
		(start 138.6078 -34.2646)
		(end 138.6078 -39.2938)
		(stroke
			(width 1.016)
			(type default)
		)
		(layer "In1.Cu")
	)
	(gr_line
		(start 139.0904 -34.5694)
		(end 139.0904 -39.5986)
		(stroke
			(width 1.016)
			(type default)
		)
		(layer "In1.Cu")
	)
	(gr_line
		(start 139.1666 -39.9796)
		(end 141.7066 -39.9796)
		(stroke
			(width 1.016)
			(type default)
		)
		(layer "In1.Cu")
	)
	(gr_line
		(start 141.7066 -39.9796)
		(end 142.6464 -40.9194)
		(stroke
			(width 1.016)
			(type default)
		)
		(layer "In1.Cu")
	)
	(gr_line
		(start 141.8844 -12.446)
		(end 142.6464 -13.208)
		(stroke
			(width 1.016)
			(type default)
		)
		(layer "In1.Cu")
	)
	(gr_line
		(start 142.3924 -46.355)
		(end 123.3424 -46.355)
		(stroke
			(width 1.016)
			(type default)
		)
		(layer "In1.Cu")
	)
	(gr_line
		(start 142.3924 -46.355)
		(end 142.6464 -46.609)
		(stroke
			(width 1.016)
			(type default)
		)
		(layer "In1.Cu")
	)
	(gr_line
		(start 142.621 -32.6644)
		(end 141.5034 -33.782)
		(stroke
			(width 1.016)
			(type default)
		)
		(layer "In1.Cu")
	)
	(gr_line
		(start 142.621 -32.6644)
		(end 143.7386 -33.782)
		(stroke
			(width 1.016)
			(type default)
		)
		(layer "In1.Cu")
	)
	(gr_line
		(start 142.6464 -47.498)
		(end 141.5288 -46.3804)
		(stroke
			(width 1.016)
			(type default)
		)
		(layer "In1.Cu")
	)
	(gr_line
		(start 142.6464 -45.1612)
		(end 141.5288 -46.2788)
		(stroke
			(width 1.016)
			(type default)
		)
		(layer "In1.Cu")
	)
	(gr_line
		(start 142.6464 -40.9194)
		(end 142.6464 -67.437)
		(stroke
			(width 1.016)
			(type default)
		)
		(layer "In1.Cu")
	)
	(gr_line
		(start 142.6464 -33.53308)
		(end 138.34872 -33.53308)
		(stroke
			(width 1.016)
			(type default)
		)
		(layer "In1.Cu")
	)
	(gr_line
		(start 142.6464 -33.53308)
		(end 147.35048 -33.53308)
		(stroke
			(width 1.016)
			(type default)
		)
		(layer "In1.Cu")
	)
	(gr_line
		(start 142.6464 -13.208)
		(end 142.6464 -33.53308)
		(stroke
			(width 1.016)
			(type default)
		)
		(layer "In1.Cu")
	)
	(gr_line
		(start 143.4084 -12.446)
		(end 142.6464 -13.208)
		(stroke
			(width 1.016)
			(type default)
		)
		(layer "In1.Cu")
	)
	(gr_circle
		(center 143.533114 -76.858368)
		(end 144.422114 -76.858368)
		(stroke
			(width 0.2)
			(type default)
		)
		(fill no)
		(layer "In1.Cu")
	)
	(gr_line
		(start 143.5862 -39.9796)
		(end 142.6464 -40.9194)
		(stroke
			(width 1.016)
			(type default)
		)
		(layer "In1.Cu")
	)
	(gr_line
		(start 144.4244 -39.3192)
		(end 139.3952 -39.3192)
		(stroke
			(width 1.016)
			(type default)
		)
		(layer "In1.Cu")
	)
	(gr_circle
		(center 144.892522 -76.886308)
		(end 145.781522 -76.886308)
		(stroke
			(width 0.2)
			(type default)
		)
		(fill no)
		(layer "In1.Cu")
	)
	(gr_line
		(start 145.5928 -39.8272)
		(end 140.5636 -39.8272)
		(stroke
			(width 1.016)
			(type default)
		)
		(layer "In1.Cu")
	)
	(gr_line
		(start 146.05 -34.544)
		(end 146.05 -39.5732)
		(stroke
			(width 1.016)
			(type default)
		)
		(layer "In1.Cu")
	)
	(gr_line
		(start 146.2024 -39.4208)
		(end 141.1732 -39.4208)
		(stroke
			(width 1.016)
			(type default)
		)
		(layer "In1.Cu")
	)
	(gr_line
		(start 146.2532 -39.9796)
		(end 143.5862 -39.9796)
		(stroke
			(width 1.016)
			(type default)
		)
		(layer "In1.Cu")
	)
	(gr_line
		(start 146.6596 -34.1884)
		(end 146.6596 -39.2176)
		(stroke
			(width 1.016)
			(type default)
		)
		(layer "In1.Cu")
	)
	(gr_line
		(start 147.2692 -33.8582)
		(end 147.2692 -38.8874)
		(stroke
			(width 1.016)
			(type default)
		)
		(layer "In1.Cu")
	)
	(gr_line
		(start 147.35048 -33.53308)
		(end 147.8534 -34.036)
		(stroke
			(width 1.016)
			(type default)
		)
		(layer "In1.Cu")
	)
	(gr_line
		(start 147.8534 -38.3794)
		(end 146.2532 -39.9796)
		(stroke
			(width 1.016)
			(type default)
		)
		(layer "In1.Cu")
	)
	(gr_line
		(start 147.8534 -34.036)
		(end 147.8534 -38.3794)
		(stroke
			(width 1.016)
			(type default)
		)
		(layer "In1.Cu")
	)
	(gr_line
		(start 148.668232 -67.314826)
		(end 160.61309 -55.369968)
		(stroke
			(width 1.016)
			(type default)
		)
		(layer "In1.Cu")
	)
	(gr_circle
		(center 150.033736 -79.7052)
		(end 150.922736 -79.7052)
		(stroke
			(width 0.2)
			(type default)
		)
		(fill no)
		(layer "In1.Cu")
	)
	(gr_circle
		(center 150.033736 -78.9432)
		(end 150.922736 -78.9432)
		(stroke
			(width 0.2)
			(type default)
		)
		(fill no)
		(layer "In1.Cu")
	)
	(gr_circle
		(center 150.801832 -60.917582)
		(end 151.690832 -60.917582)
		(stroke
			(width 0.2)
			(type default)
		)
		(fill no)
		(layer "In1.Cu")
	)
	(gr_circle
		(center 151.563832 -60.917582)
		(end 152.452832 -60.917582)
		(stroke
			(width 0.2)
			(type default)
		)
		(fill no)
		(layer "In1.Cu")
	)
	(gr_line
		(start 156.980382 -12.446)
		(end 123.4694 -12.446)
		(stroke
			(width 1.016)
			(type default)
		)
		(layer "In1.Cu")
	)
	(gr_circle
		(center 158.369 -96.266)
		(end 159.258 -96.266)
		(stroke
			(width 0.2)
			(type default)
		)
		(fill no)
		(layer "In1.Cu")
	)
	(gr_circle
		(center 160.575244 -86.084918)
		(end 161.464244 -86.084918)
		(stroke
			(width 0.2)
			(type default)
		)
		(fill no)
		(layer "In1.Cu")
	)
	(gr_line
		(start 160.61309 -55.369968)
		(end 175.611282 -55.369968)
		(stroke
			(width 1.016)
			(type default)
		)
		(layer "In1.Cu")
	)
	(gr_line
		(start 160.6804 -27.182318)
		(end 161.946082 -28.448)
		(stroke
			(width 1.016)
			(type default)
		)
		(layer "In1.Cu")
	)
	(gr_line
		(start 160.6804 -16.146018)
		(end 156.980382 -12.446)
		(stroke
			(width 1.016)
			(type default)
		)
		(layer "In1.Cu")
	)
	(gr_line
		(start 160.6804 -16.146018)
		(end 160.6804 -27.182318)
		(stroke
			(width 1.016)
			(type default)
		)
		(layer "In1.Cu")
	)
	(gr_line
		(start 161.946082 -28.448)
		(end 209.1944 -28.448)
		(stroke
			(width 1.016)
			(type default)
		)
		(layer "In1.Cu")
	)
	(gr_circle
		(center 166.5224 -60.3758)
		(end 167.4114 -60.3758)
		(stroke
			(width 0.2)
			(type default)
		)
		(fill no)
		(layer "In1.Cu")
	)
	(gr_circle
		(center 167.2844 -60.3758)
		(end 168.1734 -60.3758)
		(stroke
			(width 0.2)
			(type default)
		)
		(fill no)
		(layer "In1.Cu")
	)
	(gr_line
		(start 172.174662 -50.696622)
		(end 172.174662 -43.570398)
		(stroke
			(width 1.016)
			(type default)
		)
		(layer "In1.Cu")
	)
	(gr_line
		(start 172.174662 -43.570398)
		(end 173.915832 -41.829228)
		(stroke
			(width 1.016)
			(type default)
		)
		(layer "In1.Cu")
	)
	(gr_line
		(start 172.583348 -51.105308)
		(end 172.174662 -50.696622)
		(stroke
			(width 1.016)
			(type default)
		)
		(layer "In1.Cu")
	)
	(gr_line
		(start 173.915832 -41.829228)
		(end 191.747394 -41.829228)
		(stroke
			(width 1.016)
			(type default)
		)
		(layer "In1.Cu")
	)
	(gr_line
		(start 173.980348 -51.105308)
		(end 172.583348 -51.105308)
		(stroke
			(width 1.016)
			(type default)
		)
		(layer "In1.Cu")
	)
	(gr_circle
		(center 174.9044 -82.296)
		(end 175.7934 -82.296)
		(stroke
			(width 0.2)
			(type default)
		)
		(fill no)
		(layer "In1.Cu")
	)
	(gr_line
		(start 175.611282 -55.369968)
		(end 176.302162 -54.679088)
		(stroke
			(width 1.016)
			(type default)
		)
		(layer "In1.Cu")
	)
	(gr_circle
		(center 175.6664 -82.296)
		(end 176.5554 -82.296)
		(stroke
			(width 0.2)
			(type default)
		)
		(fill no)
		(layer "In1.Cu")
	)
	(gr_line
		(start 176.302162 -54.679088)
		(end 176.302162 -53.427122)
		(stroke
			(width 1.016)
			(type default)
		)
		(layer "In1.Cu")
	)
	(gr_line
		(start 176.302162 -53.427122)
		(end 173.980348 -51.105308)
		(stroke
			(width 1.016)
			(type default)
		)
		(layer "In1.Cu")
	)
	(gr_circle
		(center 177.1904 -82.296)
		(end 178.0794 -82.296)
		(stroke
			(width 0.2)
			(type default)
		)
		(fill no)
		(layer "In1.Cu")
	)
	(gr_circle
		(center 177.9524 -82.296)
		(end 178.8414 -82.296)
		(stroke
			(width 0.2)
			(type default)
		)
		(fill no)
		(layer "In1.Cu")
	)
	(gr_circle
		(center 178.87696 -46.99)
		(end 179.76596 -46.99)
		(stroke
			(width 0.2)
			(type default)
		)
		(fill no)
		(layer "In1.Cu")
	)
	(gr_line
		(start 182.1434 -50.894996)
		(end 182.1434 -50.419)
		(stroke
			(width 1.016)
			(type default)
		)
		(layer "In1.Cu")
	)
	(gr_line
		(start 182.1434 -50.419)
		(end 182.1434 -47.879)
		(stroke
			(width 1.016)
			(type default)
		)
		(layer "In1.Cu")
	)
	(gr_line
		(start 182.1434 -47.879)
		(end 182.1434 -46.609)
		(stroke
			(width 1.016)
			(type default)
		)
		(layer "In1.Cu")
	)
	(gr_line
		(start 182.1434 -46.609)
		(end 185.8264 -42.926)
		(stroke
			(width 1.016)
			(type default)
		)
		(layer "In1.Cu")
	)
	(gr_circle
		(center 182.215536 -69.4436)
		(end 183.104536 -69.4436)
		(stroke
			(width 0.2)
			(type default)
		)
		(fill no)
		(layer "In1.Cu")
	)
	(gr_line
		(start 182.815484 -51.56708)
		(end 182.1434 -50.894996)
		(stroke
			(width 1.016)
			(type default)
		)
		(layer "In1.Cu")
	)
	(gr_circle
		(center 184.8104 -68.58)
		(end 185.6994 -68.58)
		(stroke
			(width 0.2)
			(type default)
		)
		(fill no)
		(layer "In1.Cu")
	)
	(gr_circle
		(center 185.5724 -68.58)
		(end 186.4614 -68.58)
		(stroke
			(width 0.2)
			(type default)
		)
		(fill no)
		(layer "In1.Cu")
	)
	(gr_line
		(start 185.8264 -42.926)
		(end 189.847982 -42.926)
		(stroke
			(width 1.016)
			(type default)
		)
		(layer "In1.Cu")
	)
	(gr_line
		(start 189.847982 -42.926)
		(end 193.576448 -46.654466)
		(stroke
			(width 1.016)
			(type default)
		)
		(layer "In1.Cu")
	)
	(gr_line
		(start 191.747394 -41.829228)
		(end 197.797166 -47.879)
		(stroke
			(width 1.016)
			(type default)
		)
		(layer "In1.Cu")
	)
	(gr_line
		(start 193.031618 -51.56708)
		(end 182.815484 -51.56708)
		(stroke
			(width 1.016)
			(type default)
		)
		(layer "In1.Cu")
	)
	(gr_line
		(start 193.576448 -51.02225)
		(end 193.031618 -51.56708)
		(stroke
			(width 1.016)
			(type default)
		)
		(layer "In1.Cu")
	)
	(gr_line
		(start 193.576448 -47.879)
		(end 193.576448 -51.02225)
		(stroke
			(width 1.016)
			(type default)
		)
		(layer "In1.Cu")
	)
	(gr_line
		(start 193.576448 -46.654466)
		(end 193.576448 -47.879)
		(stroke
			(width 1.016)
			(type default)
		)
		(layer "In1.Cu")
	)
	(gr_line
		(start 197.797166 -47.879)
		(end 210.0834 -47.879)
		(stroke
			(width 1.016)
			(type default)
		)
		(layer "In1.Cu")
	)
	(gr_circle
		(center 208.810098 -51.049936)
		(end 210.20913 -51.049936)
		(stroke
			(width 0.2)
			(type default)
		)
		(fill no)
		(layer "In1.Cu")
	)
	(gr_line
		(start 209.1944 -28.448)
		(end 210.9724 -30.226)
		(stroke
			(width 1.016)
			(type default)
		)
		(layer "In1.Cu")
	)
	(gr_line
		(start 210.9724 -46.99)
		(end 210.0834 -47.879)
		(stroke
			(width 1.016)
			(type default)
		)
		(layer "In1.Cu")
	)
	(gr_line
		(start 210.9724 -30.226)
		(end 210.9724 -46.99)
		(stroke
			(width 1.016)
			(type default)
		)
		(layer "In1.Cu")
	)
	(gr_line
		(start 229.362 -46.99)
		(end 230.251 -47.879)
		(stroke
			(width 1.016)
			(type default)
		)
		(layer "In1.Cu")
	)
	(gr_line
		(start 229.362 -30.226)
		(end 229.362 -46.99)
		(stroke
			(width 1.016)
			(type default)
		)
		(layer "In1.Cu")
	)
	(gr_line
		(start 230.251 -47.879)
		(end 242.963954 -47.879)
		(stroke
			(width 1.016)
			(type default)
		)
		(layer "In1.Cu")
	)
	(gr_line
		(start 231.14 -28.448)
		(end 229.362 -30.226)
		(stroke
			(width 1.016)
			(type default)
		)
		(layer "In1.Cu")
	)
	(gr_circle
		(center 238.810038 -51.049936)
		(end 240.20907 -51.049936)
		(stroke
			(width 0.2)
			(type default)
		)
		(fill no)
		(layer "In1.Cu")
	)
	(gr_line
		(start 242.963954 -47.879)
		(end 248.993406 -41.849548)
		(stroke
			(width 1.016)
			(type default)
		)
		(layer "In1.Cu")
	)
	(gr_line
		(start 246.757952 -51.02225)
		(end 247.302782 -51.56708)
		(stroke
			(width 1.016)
			(type default)
		)
		(layer "In1.Cu")
	)
	(gr_line
		(start 246.757952 -47.879)
		(end 246.757952 -51.02225)
		(stroke
			(width 1.016)
			(type default)
		)
		(layer "In1.Cu")
	)
	(gr_line
		(start 246.757952 -46.654466)
		(end 246.757952 -47.879)
		(stroke
			(width 1.016)
			(type default)
		)
		(layer "In1.Cu")
	)
	(gr_line
		(start 246.757952 -46.654466)
		(end 250.867418 -42.545)
		(stroke
			(width 1.016)
			(type default)
		)
		(layer "In1.Cu")
	)
	(gr_line
		(start 247.302782 -51.56708)
		(end 257.518916 -51.56708)
		(stroke
			(width 1.016)
			(type default)
		)
		(layer "In1.Cu")
	)
	(gr_line
		(start 248.993406 -41.849548)
		(end 255.891538 -41.849548)
		(stroke
			(width 1.016)
			(type default)
		)
		(layer "In1.Cu")
	)
	(gr_line
		(start 250.867418 -42.545)
		(end 256.07899 -42.545)
		(stroke
			(width 1.016)
			(type default)
		)
		(layer "In1.Cu")
	)
	(gr_line
		(start 254.508 -42.926)
		(end 258.191 -46.609)
		(stroke
			(width 1.016)
			(type default)
		)
		(layer "In1.Cu")
	)
	(gr_line
		(start 255.383538 -41.849548)
		(end 258.11099 -44.577)
		(stroke
			(width 1.016)
			(type default)
		)
		(layer "In1.Cu")
	)
	(gr_line
		(start 255.397 -42.926)
		(end 250.486418 -42.926)
		(stroke
			(width 1.016)
			(type default)
		)
		(layer "In1.Cu")
	)
	(gr_line
		(start 255.891538 -41.849548)
		(end 258.61899 -44.577)
		(stroke
			(width 1.016)
			(type default)
		)
		(layer "In1.Cu")
	)
	(gr_line
		(start 256.2352 -44.577)
		(end 256.1844 -44.5262)
		(stroke
			(width 1.016)
			(type default)
		)
		(layer "In1.Cu")
	)
	(gr_line
		(start 257.518916 -51.56708)
		(end 258.191 -50.894996)
		(stroke
			(width 1.016)
			(type default)
		)
		(layer "In1.Cu")
	)
	(gr_line
		(start 257.556 -45.085)
		(end 255.397 -42.926)
		(stroke
			(width 1.016)
			(type default)
		)
		(layer "In1.Cu")
	)
	(gr_line
		(start 257.823716 -45.426884)
		(end 258.4958 -44.7548)
		(stroke
			(width 1.016)
			(type default)
		)
		(layer "In1.Cu")
	)
	(gr_line
		(start 258.191 -50.894996)
		(end 258.191 -50.419)
		(stroke
			(width 1.016)
			(type default)
		)
		(layer "In1.Cu")
	)
	(gr_line
		(start 258.191 -50.419)
		(end 258.191 -47.879)
		(stroke
			(width 1.016)
			(type default)
		)
		(layer "In1.Cu")
	)
	(gr_line
		(start 258.191 -47.879)
		(end 258.191 -46.609)
		(stroke
			(width 1.016)
			(type default)
		)
		(layer "In1.Cu")
	)
	(gr_line
		(start 258.191 -46.609)
		(end 258.191 -45.72)
		(stroke
			(width 1.016)
			(type default)
		)
		(layer "In1.Cu")
	)
	(gr_line
		(start 258.191 -45.72)
		(end 257.556 -45.085)
		(stroke
			(width 1.016)
			(type default)
		)
		(layer "In1.Cu")
	)
	(gr_line
		(start 258.230116 -45.452284)
		(end 258.9022 -44.7802)
		(stroke
			(width 1.016)
			(type default)
		)
		(layer "In1.Cu")
	)
	(gr_line
		(start 258.61899 -44.577)
		(end 268.097 -44.577)
		(stroke
			(width 1.016)
			(type default)
		)
		(layer "In1.Cu")
	)
	(gr_line
		(start 260.011926 -44.577)
		(end 256.2352 -44.577)
		(stroke
			(width 1.016)
			(type default)
		)
		(layer "In1.Cu")
	)
	(gr_circle
		(center 260.2484 -46.99)
		(end 261.1374 -46.99)
		(stroke
			(width 0.2)
			(type default)
		)
		(fill no)
		(layer "In1.Cu")
	)
	(gr_circle
		(center 261.493 -71.5772)
		(end 262.382 -71.5772)
		(stroke
			(width 0.2)
			(type default)
		)
		(fill no)
		(layer "In1.Cu")
	)
	(gr_circle
		(center 262.255 -71.5772)
		(end 263.144 -71.5772)
		(stroke
			(width 0.2)
			(type default)
		)
		(fill no)
		(layer "In1.Cu")
	)
	(gr_circle
		(center 265.4046 -70.7644)
		(end 266.2936 -70.7644)
		(stroke
			(width 0.2)
			(type default)
		)
		(fill no)
		(layer "In1.Cu")
	)
	(gr_line
		(start 268.097 -44.577)
		(end 282.2448 -58.7248)
		(stroke
			(width 1.016)
			(type default)
		)
		(layer "In1.Cu")
	)
	(gr_circle
		(center 269.6464 -57.912)
		(end 270.5354 -57.912)
		(stroke
			(width 0.2)
			(type default)
		)
		(fill no)
		(layer "In1.Cu")
	)
	(gr_circle
		(center 270.0782 -86.233)
		(end 270.9672 -86.233)
		(stroke
			(width 0.2)
			(type default)
		)
		(fill no)
		(layer "In1.Cu")
	)
	(gr_circle
		(center 270.4084 -57.912)
		(end 271.2974 -57.912)
		(stroke
			(width 0.2)
			(type default)
		)
		(fill no)
		(layer "In1.Cu")
	)
	(gr_circle
		(center 270.7132 -86.233)
		(end 271.6022 -86.233)
		(stroke
			(width 0.2)
			(type default)
		)
		(fill no)
		(layer "In1.Cu")
	)
	(gr_circle
		(center 271.9324 -57.912)
		(end 272.8214 -57.912)
		(stroke
			(width 0.2)
			(type default)
		)
		(fill no)
		(layer "In1.Cu")
	)
	(gr_circle
		(center 272.1102 -86.233)
		(end 272.9992 -86.233)
		(stroke
			(width 0.2)
			(type default)
		)
		(fill no)
		(layer "In1.Cu")
	)
	(gr_circle
		(center 272.6944 -57.912)
		(end 273.5834 -57.912)
		(stroke
			(width 0.2)
			(type default)
		)
		(fill no)
		(layer "In1.Cu")
	)
	(gr_circle
		(center 272.7452 -86.233)
		(end 273.6342 -86.233)
		(stroke
			(width 0.2)
			(type default)
		)
		(fill no)
		(layer "In1.Cu")
	)
	(gr_circle
		(center 274.1422 -86.233)
		(end 275.0312 -86.233)
		(stroke
			(width 0.2)
			(type default)
		)
		(fill no)
		(layer "In1.Cu")
	)
	(gr_circle
		(center 274.7772 -86.233)
		(end 275.6662 -86.233)
		(stroke
			(width 0.2)
			(type default)
		)
		(fill no)
		(layer "In1.Cu")
	)
	(gr_circle
		(center 276.0472 -86.233)
		(end 276.9362 -86.233)
		(stroke
			(width 0.2)
			(type default)
		)
		(fill no)
		(layer "In1.Cu")
	)
	(gr_circle
		(center 276.6822 -86.233)
		(end 277.5712 -86.233)
		(stroke
			(width 0.2)
			(type default)
		)
		(fill no)
		(layer "In1.Cu")
	)
	(gr_line
		(start 278.388318 -28.448)
		(end 231.14 -28.448)
		(stroke
			(width 1.016)
			(type default)
		)
		(layer "In1.Cu")
	)
	(gr_line
		(start 279.654 -27.182318)
		(end 278.388318 -28.448)
		(stroke
			(width 1.016)
			(type default)
		)
		(layer "In1.Cu")
	)
	(gr_line
		(start 279.654 -16.146018)
		(end 279.654 -27.182318)
		(stroke
			(width 1.016)
			(type default)
		)
		(layer "In1.Cu")
	)
	(gr_circle
		(center 280.329894 -78.1558)
		(end 281.218894 -78.1558)
		(stroke
			(width 0.2)
			(type default)
		)
		(fill no)
		(layer "In1.Cu")
	)
	(gr_circle
		(center 281.091894 -78.1558)
		(end 281.980894 -78.1558)
		(stroke
			(width 0.2)
			(type default)
		)
		(fill no)
		(layer "In1.Cu")
	)
	(gr_line
		(start 282.2448 -58.7248)
		(end 293.4208 -58.7248)
		(stroke
			(width 1.016)
			(type default)
		)
		(layer "In1.Cu")
	)
	(gr_line
		(start 283.354018 -12.446)
		(end 279.654 -16.146018)
		(stroke
			(width 1.016)
			(type default)
		)
		(layer "In1.Cu")
	)
	(gr_line
		(start 293.4208 -58.7248)
		(end 296.7228 -62.0268)
		(stroke
			(width 1.016)
			(type default)
		)
		(layer "In1.Cu")
	)
	(gr_line
		(start 296.7228 -65.7098)
		(end 298.35729 -67.34429)
		(stroke
			(width 1.016)
			(type default)
		)
		(layer "In1.Cu")
	)
	(gr_line
		(start 296.7228 -62.0268)
		(end 296.7228 -65.7098)
		(stroke
			(width 1.016)
			(type default)
		)
		(layer "In1.Cu")
	)
	(gr_circle
		(center 297.9928 -80.391)
		(end 298.8818 -80.391)
		(stroke
			(width 0.2)
			(type default)
		)
		(fill no)
		(layer "In1.Cu")
	)
	(gr_circle
		(center 298.069 -75.819)
		(end 298.958 -75.819)
		(stroke
			(width 0.2)
			(type default)
		)
		(fill no)
		(layer "In1.Cu")
	)
	(gr_line
		(start 298.35729 -67.34429)
		(end 309.808372 -67.34429)
		(stroke
			(width 1.016)
			(type default)
		)
		(layer "In1.Cu")
	)
	(gr_circle
		(center 298.7548 -80.391)
		(end 299.6438 -80.391)
		(stroke
			(width 0.2)
			(type default)
		)
		(fill no)
		(layer "In1.Cu")
	)
	(gr_line
		(start 299.168312 -38.996112)
		(end 300.6852 -40.513)
		(stroke
			(width 1.016)
			(type default)
		)
		(layer "In1.Cu")
	)
	(gr_line
		(start 299.168312 -33.576768)
		(end 299.168312 -38.996112)
		(stroke
			(width 1.016)
			(type default)
		)
		(layer "In1.Cu")
	)
	(gr_line
		(start 299.265086 -33.479994)
		(end 299.168312 -33.576768)
		(stroke
			(width 1.016)
			(type default)
		)
		(layer "In1.Cu")
	)
	(gr_line
		(start 300.446694 -34.461958)
		(end 300.126654 -34.781998)
		(stroke
			(width 2.54)
			(type default)
		)
		(layer "In1.Cu")
	)
	(gr_line
		(start 300.6852 -40.513)
		(end 303.4792 -40.513)
		(stroke
			(width 1.016)
			(type default)
		)
		(layer "In1.Cu")
	)
	(gr_line
		(start 302.078136 -36.06165)
		(end 301.822104 -36.317682)
		(stroke
			(width 2.54)
			(type default)
		)
		(layer "In1.Cu")
	)
	(gr_line
		(start 303.101756 -37.821108)
		(end 303.069752 -37.853112)
		(stroke
			(width 2.54)
			(type default)
		)
		(layer "In1.Cu")
	)
	(gr_line
		(start 303.391316 -40.2844)
		(end 305.5366 -40.2844)
		(stroke
			(width 1.016)
			(type default)
		)
		(layer "In1.Cu")
	)
	(gr_line
		(start 303.4792 -40.513)
		(end 304.8 -41.8338)
		(stroke
			(width 1.016)
			(type default)
		)
		(layer "In1.Cu")
	)
	(gr_line
		(start 304.038 -12.446)
		(end 304.8 -13.208)
		(stroke
			(width 1.016)
			(type default)
		)
		(layer "In1.Cu")
	)
	(gr_circle
		(center 304.070258 -79.823056)
		(end 304.959258 -79.823056)
		(stroke
			(width 0.2)
			(type default)
		)
		(fill no)
		(layer "In1.Cu")
	)
	(gr_line
		(start 304.546 -39.053516)
		(end 304.546 -41.1988)
		(stroke
			(width 1.016)
			(type default)
		)
		(layer "In1.Cu")
	)
	(gr_line
		(start 304.779934 -32.938466)
		(end 303.7586 -33.9598)
		(stroke
			(width 1.016)
			(type default)
		)
		(layer "In1.Cu")
	)
	(gr_line
		(start 304.794666 -32.938466)
		(end 305.816 -33.9598)
		(stroke
			(width 1.016)
			(type default)
		)
		(layer "In1.Cu")
	)
	(gr_line
		(start 304.8 -67.065144)
		(end 305.079146 -67.34429)
		(stroke
			(width 1.016)
			(type default)
		)
		(layer "In1.Cu")
	)
	(gr_line
		(start 304.8 -47.5488)
		(end 305.9176 -46.4312)
		(stroke
			(width 1.016)
			(type default)
		)
		(layer "In1.Cu")
	)
	(gr_line
		(start 304.8 -45.212)
		(end 305.9176 -46.3296)
		(stroke
			(width 1.016)
			(type default)
		)
		(layer "In1.Cu")
	)
	(gr_line
		(start 304.8 -41.8338)
		(end 304.8 -67.065144)
		(stroke
			(width 1.016)
			(type default)
		)
		(layer "In1.Cu")
	)
	(gr_line
		(start 304.8 -41.3258)
		(end 304.8 -41.8338)
		(stroke
			(width 1.016)
			(type default)
		)
		(layer "In1.Cu")
	)
	(gr_line
		(start 304.8 -33.479994)
		(end 299.265086 -33.479994)
		(stroke
			(width 1.016)
			(type default)
		)
		(layer "In1.Cu")
	)
	(gr_line
		(start 304.8 -33.479994)
		(end 309.723028 -33.479994)
		(stroke
			(width 1.016)
			(type default)
		)
		(layer "In1.Cu")
	)
	(gr_line
		(start 304.8 -13.208)
		(end 304.8 -33.479994)
		(stroke
			(width 1.016)
			(type default)
		)
		(layer "In1.Cu")
	)
	(gr_line
		(start 304.850038 -66.421762)
		(end 303.9364 -67.3354)
		(stroke
			(width 1.016)
			(type default)
		)
		(layer "In1.Cu")
	)
	(gr_line
		(start 304.851562 -66.396362)
		(end 305.7652 -67.31)
		(stroke
			(width 1.016)
			(type default)
		)
		(layer "In1.Cu")
	)
	(gr_line
		(start 305.054 -46.355)
		(end 304.8 -46.101)
		(stroke
			(width 1.016)
			(type default)
		)
		(layer "In1.Cu")
	)
	(gr_line
		(start 305.054 -46.355)
		(end 324.104 -46.355)
		(stroke
			(width 1.016)
			(type default)
		)
		(layer "In1.Cu")
	)
	(gr_circle
		(center 305.063398 -81.003648)
		(end 305.952398 -81.003648)
		(stroke
			(width 0.2)
			(type default)
		)
		(fill no)
		(layer "In1.Cu")
	)
	(gr_line
		(start 305.562 -12.446)
		(end 304.8 -13.208)
		(stroke
			(width 1.016)
			(type default)
		)
		(layer "In1.Cu")
	)
	(gr_line
		(start 305.6128 -40.513)
		(end 304.8 -41.3258)
		(stroke
			(width 1.016)
			(type default)
		)
		(layer "In1.Cu")
	)
	(gr_line
		(start 306.076858 -37.821108)
		(end 303.101756 -37.821108)
		(stroke
			(width 2.54)
			(type default)
		)
		(layer "In1.Cu")
	)
	(gr_line
		(start 306.17287 -37.91712)
		(end 306.076858 -37.821108)
		(stroke
			(width 2.54)
			(type default)
		)
		(layer "In1.Cu")
	)
	(gr_line
		(start 307.388514 -36.06165)
		(end 302.078136 -36.06165)
		(stroke
			(width 2.54)
			(type default)
		)
		(layer "In1.Cu")
	)
	(gr_line
		(start 307.836316 -36.509452)
		(end 307.388514 -36.06165)
		(stroke
			(width 2.54)
			(type default)
		)
		(layer "In1.Cu")
	)
	(gr_line
		(start 308.3052 -37.5412)
		(end 300.083728 -37.5412)
		(stroke
			(width 2.54)
			(type default)
		)
		(layer "In1.Cu")
	)
	(gr_line
		(start 308.3306 -36.068)
		(end 300.109128 -36.068)
		(stroke
			(width 2.54)
			(type default)
		)
		(layer "In1.Cu")
	)
	(gr_line
		(start 308.5592 -38.7858)
		(end 300.337728 -38.7858)
		(stroke
			(width 2.54)
			(type default)
		)
		(layer "In1.Cu")
	)
	(gr_line
		(start 308.668166 -34.461958)
		(end 300.446694 -34.461958)
		(stroke
			(width 2.54)
			(type default)
		)
		(layer "In1.Cu")
	)
	(gr_line
		(start 309.1688 -39.2938)
		(end 300.947328 -39.2938)
		(stroke
			(width 2.54)
			(type default)
		)
		(layer "In1.Cu")
	)
	(gr_line
		(start 309.2704 -40.513)
		(end 305.6128 -40.513)
		(stroke
			(width 1.016)
			(type default)
		)
		(layer "In1.Cu")
	)
	(gr_line
		(start 309.448962 -34.323528)
		(end 309.448962 -38.861238)
		(stroke
			(width 1.016)
			(type default)
		)
		(layer "In1.Cu")
	)
	(gr_line
		(start 309.627778 -35.42157)
		(end 308.668166 -34.461958)
		(stroke
			(width 2.54)
			(type default)
		)
		(layer "In1.Cu")
	)
	(gr_line
		(start 309.723028 -33.479994)
		(end 310.744362 -34.501328)
		(stroke
			(width 1.016)
			(type default)
		)
		(layer "In1.Cu")
	)
	(gr_line
		(start 309.804562 -34.425128)
		(end 309.804562 -38.962838)
		(stroke
			(width 1.016)
			(type default)
		)
		(layer "In1.Cu")
	)
	(gr_line
		(start 309.808372 -67.34429)
		(end 310.72201 -68.257928)
		(stroke
			(width 1.016)
			(type default)
		)
		(layer "In1.Cu")
	)
	(gr_line
		(start 310.236362 -34.501328)
		(end 310.236362 -39.039038)
		(stroke
			(width 1.016)
			(type default)
		)
		(layer "In1.Cu")
	)
	(gr_line
		(start 310.72201 -79.844646)
		(end 311.395364 -80.518)
		(stroke
			(width 1.016)
			(type default)
		)
		(layer "In1.Cu")
	)
	(gr_line
		(start 310.72201 -68.257928)
		(end 310.72201 -79.844646)
		(stroke
			(width 1.016)
			(type default)
		)
		(layer "In1.Cu")
	)
	(gr_line
		(start 310.744362 -39.039038)
		(end 309.2704 -40.513)
		(stroke
			(width 1.016)
			(type default)
		)
		(layer "In1.Cu")
	)
	(gr_line
		(start 310.744362 -34.501328)
		(end 310.744362 -39.039038)
		(stroke
			(width 1.016)
			(type default)
		)
		(layer "In1.Cu")
	)
	(gr_line
		(start 311.395364 -80.518)
		(end 323.977 -80.518)
		(stroke
			(width 1.016)
			(type default)
		)
		(layer "In1.Cu")
	)
	(gr_line
		(start 323.977 -80.518)
		(end 324.612 -79.883)
		(stroke
			(width 1.016)
			(type default)
		)
		(layer "In1.Cu")
	)
	(gr_line
		(start 323.977 -12.446)
		(end 283.354018 -12.446)
		(stroke
			(width 1.016)
			(type default)
		)
		(layer "In1.Cu")
	)
	(gr_line
		(start 324.104 -46.355)
		(end 324.612 -45.847)
		(stroke
			(width 1.016)
			(type default)
		)
		(layer "In1.Cu")
	)
	(gr_line
		(start 324.612 -79.883)
		(end 324.612 -46.863)
		(stroke
			(width 1.016)
			(type default)
		)
		(layer "In1.Cu")
	)
	(gr_line
		(start 324.612 -46.863)
		(end 324.104 -46.355)
		(stroke
			(width 1.016)
			(type default)
		)
		(layer "In1.Cu")
	)
	(gr_line
		(start 324.612 -46.863)
		(end 324.612 -13.081)
		(stroke
			(width 1.016)
			(type default)
		)
		(layer "In1.Cu")
	)
	(gr_line
		(start 324.612 -13.081)
		(end 323.977 -12.446)
		(stroke
			(width 1.016)
			(type default)
		)
		(layer "In1.Cu")
	)
	(gr_circle
		(center 332.1558 -79.4766)
		(end 333.0448 -79.4766)
		(stroke
			(width 0.2)
			(type default)
		)
		(fill no)
		(layer "In1.Cu")
	)
	(gr_circle
		(center 332.1558 -78.7146)
		(end 333.0448 -78.7146)
		(stroke
			(width 0.2)
			(type default)
		)
		(fill no)
		(layer "In1.Cu")
	)
	(gr_circle
		(center 332.1558 -77.9526)
		(end 333.0448 -77.9526)
		(stroke
			(width 0.2)
			(type default)
		)
		(fill no)
		(layer "In1.Cu")
	)
	(gr_circle
		(center 332.1558 -77.1906)
		(end 333.0448 -77.1906)
		(stroke
			(width 0.2)
			(type default)
		)
		(fill no)
		(layer "In1.Cu")
	)
	(gr_circle
		(center 332.1558 -76.4286)
		(end 333.0448 -76.4286)
		(stroke
			(width 0.2)
			(type default)
		)
		(fill no)
		(layer "In1.Cu")
	)
	(gr_circle
		(center 332.1558 -68.199)
		(end 333.0448 -68.199)
		(stroke
			(width 0.2)
			(type default)
		)
		(fill no)
		(layer "In1.Cu")
	)
	(gr_circle
		(center 332.1558 -67.437)
		(end 333.0448 -67.437)
		(stroke
			(width 0.2)
			(type default)
		)
		(fill no)
		(layer "In1.Cu")
	)
	(gr_circle
		(center 332.1558 -66.675)
		(end 333.0448 -66.675)
		(stroke
			(width 0.2)
			(type default)
		)
		(fill no)
		(layer "In1.Cu")
	)
	(gr_circle
		(center 332.1558 -65.913)
		(end 333.0448 -65.913)
		(stroke
			(width 0.2)
			(type default)
		)
		(fill no)
		(layer "In1.Cu")
	)
	(gr_circle
		(center 332.1558 -65.151)
		(end 333.0448 -65.151)
		(stroke
			(width 0.2)
			(type default)
		)
		(fill no)
		(layer "In1.Cu")
	)
	(gr_circle
		(center 332.1558 -56.9214)
		(end 333.0448 -56.9214)
		(stroke
			(width 0.2)
			(type default)
		)
		(fill no)
		(layer "In1.Cu")
	)
	(gr_circle
		(center 332.1558 -56.1594)
		(end 333.0448 -56.1594)
		(stroke
			(width 0.2)
			(type default)
		)
		(fill no)
		(layer "In1.Cu")
	)
	(gr_circle
		(center 332.1558 -55.3974)
		(end 333.0448 -55.3974)
		(stroke
			(width 0.2)
			(type default)
		)
		(fill no)
		(layer "In1.Cu")
	)
	(gr_circle
		(center 332.1558 -54.6354)
		(end 333.0448 -54.6354)
		(stroke
			(width 0.2)
			(type default)
		)
		(fill no)
		(layer "In1.Cu")
	)
	(gr_circle
		(center 332.1558 -53.8734)
		(end 333.0448 -53.8734)
		(stroke
			(width 0.2)
			(type default)
		)
		(fill no)
		(layer "In1.Cu")
	)
	(gr_circle
		(center 332.1558 -45.6438)
		(end 333.0448 -45.6438)
		(stroke
			(width 0.2)
			(type default)
		)
		(fill no)
		(layer "In1.Cu")
	)
	(gr_circle
		(center 332.1558 -44.8818)
		(end 333.0448 -44.8818)
		(stroke
			(width 0.2)
			(type default)
		)
		(fill no)
		(layer "In1.Cu")
	)
	(gr_circle
		(center 332.1558 -44.1198)
		(end 333.0448 -44.1198)
		(stroke
			(width 0.2)
			(type default)
		)
		(fill no)
		(layer "In1.Cu")
	)
	(gr_circle
		(center 332.1558 -43.3578)
		(end 333.0448 -43.3578)
		(stroke
			(width 0.2)
			(type default)
		)
		(fill no)
		(layer "In1.Cu")
	)
	(gr_circle
		(center 332.1558 -42.5958)
		(end 333.0448 -42.5958)
		(stroke
			(width 0.2)
			(type default)
		)
		(fill no)
		(layer "In1.Cu")
	)
	(gr_circle
		(center 332.1558 -34.3662)
		(end 333.0448 -34.3662)
		(stroke
			(width 0.2)
			(type default)
		)
		(fill no)
		(layer "In1.Cu")
	)
	(gr_circle
		(center 332.1558 -33.6042)
		(end 333.0448 -33.6042)
		(stroke
			(width 0.2)
			(type default)
		)
		(fill no)
		(layer "In1.Cu")
	)
	(gr_circle
		(center 332.1558 -32.8422)
		(end 333.0448 -32.8422)
		(stroke
			(width 0.2)
			(type default)
		)
		(fill no)
		(layer "In1.Cu")
	)
	(gr_circle
		(center 332.1558 -32.0802)
		(end 333.0448 -32.0802)
		(stroke
			(width 0.2)
			(type default)
		)
		(fill no)
		(layer "In1.Cu")
	)
	(gr_circle
		(center 332.1558 -31.3182)
		(end 333.0448 -31.3182)
		(stroke
			(width 0.2)
			(type default)
		)
		(fill no)
		(layer "In1.Cu")
	)
	(gr_circle
		(center 332.1558 -23.0886)
		(end 333.0448 -23.0886)
		(stroke
			(width 0.2)
			(type default)
		)
		(fill no)
		(layer "In1.Cu")
	)
	(gr_circle
		(center 332.1558 -22.3266)
		(end 333.0448 -22.3266)
		(stroke
			(width 0.2)
			(type default)
		)
		(fill no)
		(layer "In1.Cu")
	)
	(gr_circle
		(center 332.1558 -21.5646)
		(end 333.0448 -21.5646)
		(stroke
			(width 0.2)
			(type default)
		)
		(fill no)
		(layer "In1.Cu")
	)
	(gr_circle
		(center 332.1558 -20.8026)
		(end 333.0448 -20.8026)
		(stroke
			(width 0.2)
			(type default)
		)
		(fill no)
		(layer "In1.Cu")
	)
	(gr_circle
		(center 332.1558 -20.0406)
		(end 333.0448 -20.0406)
		(stroke
			(width 0.2)
			(type default)
		)
		(fill no)
		(layer "In1.Cu")
	)
	(gr_circle
		(center 332.9178 -79.4766)
		(end 333.8068 -79.4766)
		(stroke
			(width 0.2)
			(type default)
		)
		(fill no)
		(layer "In1.Cu")
	)
	(gr_circle
		(center 332.9178 -78.7146)
		(end 333.8068 -78.7146)
		(stroke
			(width 0.2)
			(type default)
		)
		(fill no)
		(layer "In1.Cu")
	)
	(gr_circle
		(center 332.9178 -77.9526)
		(end 333.8068 -77.9526)
		(stroke
			(width 0.2)
			(type default)
		)
		(fill no)
		(layer "In1.Cu")
	)
	(gr_circle
		(center 332.9178 -77.1906)
		(end 333.8068 -77.1906)
		(stroke
			(width 0.2)
			(type default)
		)
		(fill no)
		(layer "In1.Cu")
	)
	(gr_circle
		(center 332.9178 -76.4286)
		(end 333.8068 -76.4286)
		(stroke
			(width 0.2)
			(type default)
		)
		(fill no)
		(layer "In1.Cu")
	)
	(gr_circle
		(center 332.9178 -68.199)
		(end 333.8068 -68.199)
		(stroke
			(width 0.2)
			(type default)
		)
		(fill no)
		(layer "In1.Cu")
	)
	(gr_circle
		(center 332.9178 -67.437)
		(end 333.8068 -67.437)
		(stroke
			(width 0.2)
			(type default)
		)
		(fill no)
		(layer "In1.Cu")
	)
	(gr_circle
		(center 332.9178 -66.675)
		(end 333.8068 -66.675)
		(stroke
			(width 0.2)
			(type default)
		)
		(fill no)
		(layer "In1.Cu")
	)
	(gr_circle
		(center 332.9178 -65.913)
		(end 333.8068 -65.913)
		(stroke
			(width 0.2)
			(type default)
		)
		(fill no)
		(layer "In1.Cu")
	)
	(gr_circle
		(center 332.9178 -65.151)
		(end 333.8068 -65.151)
		(stroke
			(width 0.2)
			(type default)
		)
		(fill no)
		(layer "In1.Cu")
	)
	(gr_circle
		(center 332.9178 -56.9214)
		(end 333.8068 -56.9214)
		(stroke
			(width 0.2)
			(type default)
		)
		(fill no)
		(layer "In1.Cu")
	)
	(gr_circle
		(center 332.9178 -56.1594)
		(end 333.8068 -56.1594)
		(stroke
			(width 0.2)
			(type default)
		)
		(fill no)
		(layer "In1.Cu")
	)
	(gr_circle
		(center 332.9178 -55.3974)
		(end 333.8068 -55.3974)
		(stroke
			(width 0.2)
			(type default)
		)
		(fill no)
		(layer "In1.Cu")
	)
	(gr_circle
		(center 332.9178 -54.6354)
		(end 333.8068 -54.6354)
		(stroke
			(width 0.2)
			(type default)
		)
		(fill no)
		(layer "In1.Cu")
	)
	(gr_circle
		(center 332.9178 -53.8734)
		(end 333.8068 -53.8734)
		(stroke
			(width 0.2)
			(type default)
		)
		(fill no)
		(layer "In1.Cu")
	)
	(gr_circle
		(center 332.9178 -45.6438)
		(end 333.8068 -45.6438)
		(stroke
			(width 0.2)
			(type default)
		)
		(fill no)
		(layer "In1.Cu")
	)
	(gr_circle
		(center 332.9178 -44.8818)
		(end 333.8068 -44.8818)
		(stroke
			(width 0.2)
			(type default)
		)
		(fill no)
		(layer "In1.Cu")
	)
	(gr_circle
		(center 332.9178 -44.1198)
		(end 333.8068 -44.1198)
		(stroke
			(width 0.2)
			(type default)
		)
		(fill no)
		(layer "In1.Cu")
	)
	(gr_circle
		(center 332.9178 -43.3578)
		(end 333.8068 -43.3578)
		(stroke
			(width 0.2)
			(type default)
		)
		(fill no)
		(layer "In1.Cu")
	)
	(gr_circle
		(center 332.9178 -42.5958)
		(end 333.8068 -42.5958)
		(stroke
			(width 0.2)
			(type default)
		)
		(fill no)
		(layer "In1.Cu")
	)
	(gr_circle
		(center 332.9178 -34.3662)
		(end 333.8068 -34.3662)
		(stroke
			(width 0.2)
			(type default)
		)
		(fill no)
		(layer "In1.Cu")
	)
	(gr_circle
		(center 332.9178 -33.6042)
		(end 333.8068 -33.6042)
		(stroke
			(width 0.2)
			(type default)
		)
		(fill no)
		(layer "In1.Cu")
	)
	(gr_circle
		(center 332.9178 -32.8422)
		(end 333.8068 -32.8422)
		(stroke
			(width 0.2)
			(type default)
		)
		(fill no)
		(layer "In1.Cu")
	)
	(gr_circle
		(center 332.9178 -32.0802)
		(end 333.8068 -32.0802)
		(stroke
			(width 0.2)
			(type default)
		)
		(fill no)
		(layer "In1.Cu")
	)
	(gr_circle
		(center 332.9178 -31.3182)
		(end 333.8068 -31.3182)
		(stroke
			(width 0.2)
			(type default)
		)
		(fill no)
		(layer "In1.Cu")
	)
	(gr_circle
		(center 332.9178 -23.0886)
		(end 333.8068 -23.0886)
		(stroke
			(width 0.2)
			(type default)
		)
		(fill no)
		(layer "In1.Cu")
	)
	(gr_circle
		(center 332.9178 -22.3266)
		(end 333.8068 -22.3266)
		(stroke
			(width 0.2)
			(type default)
		)
		(fill no)
		(layer "In1.Cu")
	)
	(gr_circle
		(center 332.9178 -21.5646)
		(end 333.8068 -21.5646)
		(stroke
			(width 0.2)
			(type default)
		)
		(fill no)
		(layer "In1.Cu")
	)
	(gr_circle
		(center 332.9178 -20.8026)
		(end 333.8068 -20.8026)
		(stroke
			(width 0.2)
			(type default)
		)
		(fill no)
		(layer "In1.Cu")
	)
	(gr_circle
		(center 332.9178 -20.0406)
		(end 333.8068 -20.0406)
		(stroke
			(width 0.2)
			(type default)
		)
		(fill no)
		(layer "In1.Cu")
	)
	(gr_circle
		(center 333.6798 -78.7146)
		(end 334.5688 -78.7146)
		(stroke
			(width 0.2)
			(type default)
		)
		(fill no)
		(layer "In1.Cu")
	)
	(gr_circle
		(center 333.6798 -77.9526)
		(end 334.5688 -77.9526)
		(stroke
			(width 0.2)
			(type default)
		)
		(fill no)
		(layer "In1.Cu")
	)
	(gr_circle
		(center 333.6798 -77.1906)
		(end 334.5688 -77.1906)
		(stroke
			(width 0.2)
			(type default)
		)
		(fill no)
		(layer "In1.Cu")
	)
	(gr_circle
		(center 333.6798 -76.4286)
		(end 334.5688 -76.4286)
		(stroke
			(width 0.2)
			(type default)
		)
		(fill no)
		(layer "In1.Cu")
	)
	(gr_circle
		(center 333.6798 -68.199)
		(end 334.5688 -68.199)
		(stroke
			(width 0.2)
			(type default)
		)
		(fill no)
		(layer "In1.Cu")
	)
	(gr_circle
		(center 333.6798 -67.437)
		(end 334.5688 -67.437)
		(stroke
			(width 0.2)
			(type default)
		)
		(fill no)
		(layer "In1.Cu")
	)
	(gr_circle
		(center 333.6798 -66.675)
		(end 334.5688 -66.675)
		(stroke
			(width 0.2)
			(type default)
		)
		(fill no)
		(layer "In1.Cu")
	)
	(gr_circle
		(center 333.6798 -65.913)
		(end 334.5688 -65.913)
		(stroke
			(width 0.2)
			(type default)
		)
		(fill no)
		(layer "In1.Cu")
	)
	(gr_circle
		(center 333.6798 -65.151)
		(end 334.5688 -65.151)
		(stroke
			(width 0.2)
			(type default)
		)
		(fill no)
		(layer "In1.Cu")
	)
	(gr_circle
		(center 333.6798 -56.9214)
		(end 334.5688 -56.9214)
		(stroke
			(width 0.2)
			(type default)
		)
		(fill no)
		(layer "In1.Cu")
	)
	(gr_circle
		(center 333.6798 -56.1594)
		(end 334.5688 -56.1594)
		(stroke
			(width 0.2)
			(type default)
		)
		(fill no)
		(layer "In1.Cu")
	)
	(gr_circle
		(center 333.6798 -55.3974)
		(end 334.5688 -55.3974)
		(stroke
			(width 0.2)
			(type default)
		)
		(fill no)
		(layer "In1.Cu")
	)
	(gr_circle
		(center 333.6798 -54.6354)
		(end 334.5688 -54.6354)
		(stroke
			(width 0.2)
			(type default)
		)
		(fill no)
		(layer "In1.Cu")
	)
	(gr_circle
		(center 333.6798 -53.8734)
		(end 334.5688 -53.8734)
		(stroke
			(width 0.2)
			(type default)
		)
		(fill no)
		(layer "In1.Cu")
	)
	(gr_circle
		(center 333.6798 -45.6438)
		(end 334.5688 -45.6438)
		(stroke
			(width 0.2)
			(type default)
		)
		(fill no)
		(layer "In1.Cu")
	)
	(gr_circle
		(center 333.6798 -44.8818)
		(end 334.5688 -44.8818)
		(stroke
			(width 0.2)
			(type default)
		)
		(fill no)
		(layer "In1.Cu")
	)
	(gr_circle
		(center 333.6798 -44.1198)
		(end 334.5688 -44.1198)
		(stroke
			(width 0.2)
			(type default)
		)
		(fill no)
		(layer "In1.Cu")
	)
	(gr_circle
		(center 333.6798 -43.3578)
		(end 334.5688 -43.3578)
		(stroke
			(width 0.2)
			(type default)
		)
		(fill no)
		(layer "In1.Cu")
	)
	(gr_circle
		(center 333.6798 -42.5958)
		(end 334.5688 -42.5958)
		(stroke
			(width 0.2)
			(type default)
		)
		(fill no)
		(layer "In1.Cu")
	)
	(gr_circle
		(center 333.6798 -34.3662)
		(end 334.5688 -34.3662)
		(stroke
			(width 0.2)
			(type default)
		)
		(fill no)
		(layer "In1.Cu")
	)
	(gr_circle
		(center 333.6798 -33.6042)
		(end 334.5688 -33.6042)
		(stroke
			(width 0.2)
			(type default)
		)
		(fill no)
		(layer "In1.Cu")
	)
	(gr_circle
		(center 333.6798 -32.8422)
		(end 334.5688 -32.8422)
		(stroke
			(width 0.2)
			(type default)
		)
		(fill no)
		(layer "In1.Cu")
	)
	(gr_circle
		(center 333.6798 -32.0802)
		(end 334.5688 -32.0802)
		(stroke
			(width 0.2)
			(type default)
		)
		(fill no)
		(layer "In1.Cu")
	)
	(gr_circle
		(center 333.6798 -31.3182)
		(end 334.5688 -31.3182)
		(stroke
			(width 0.2)
			(type default)
		)
		(fill no)
		(layer "In1.Cu")
	)
	(gr_circle
		(center 333.6798 -23.0886)
		(end 334.5688 -23.0886)
		(stroke
			(width 0.2)
			(type default)
		)
		(fill no)
		(layer "In1.Cu")
	)
	(gr_circle
		(center 333.6798 -22.3266)
		(end 334.5688 -22.3266)
		(stroke
			(width 0.2)
			(type default)
		)
		(fill no)
		(layer "In1.Cu")
	)
	(gr_circle
		(center 333.6798 -21.5646)
		(end 334.5688 -21.5646)
		(stroke
			(width 0.2)
			(type default)
		)
		(fill no)
		(layer "In1.Cu")
	)
	(gr_circle
		(center 333.6798 -20.8026)
		(end 334.5688 -20.8026)
		(stroke
			(width 0.2)
			(type default)
		)
		(fill no)
		(layer "In1.Cu")
	)
	(gr_circle
		(center 333.6798 -20.0406)
		(end 334.5688 -20.0406)
		(stroke
			(width 0.2)
			(type default)
		)
		(fill no)
		(layer "In1.Cu")
	)
	(gr_circle
		(center 334.4418 -77.9526)
		(end 335.3308 -77.9526)
		(stroke
			(width 0.2)
			(type default)
		)
		(fill no)
		(layer "In1.Cu")
	)
	(gr_circle
		(center 334.4418 -77.1906)
		(end 335.3308 -77.1906)
		(stroke
			(width 0.2)
			(type default)
		)
		(fill no)
		(layer "In1.Cu")
	)
	(gr_circle
		(center 334.4418 -76.4286)
		(end 335.3308 -76.4286)
		(stroke
			(width 0.2)
			(type default)
		)
		(fill no)
		(layer "In1.Cu")
	)
	(gr_circle
		(center 334.4418 -68.199)
		(end 335.3308 -68.199)
		(stroke
			(width 0.2)
			(type default)
		)
		(fill no)
		(layer "In1.Cu")
	)
	(gr_circle
		(center 334.4418 -67.437)
		(end 335.3308 -67.437)
		(stroke
			(width 0.2)
			(type default)
		)
		(fill no)
		(layer "In1.Cu")
	)
	(gr_circle
		(center 334.4418 -66.675)
		(end 335.3308 -66.675)
		(stroke
			(width 0.2)
			(type default)
		)
		(fill no)
		(layer "In1.Cu")
	)
	(gr_circle
		(center 334.4418 -65.913)
		(end 335.3308 -65.913)
		(stroke
			(width 0.2)
			(type default)
		)
		(fill no)
		(layer "In1.Cu")
	)
	(gr_circle
		(center 334.4418 -65.151)
		(end 335.3308 -65.151)
		(stroke
			(width 0.2)
			(type default)
		)
		(fill no)
		(layer "In1.Cu")
	)
	(gr_circle
		(center 334.4418 -56.9214)
		(end 335.3308 -56.9214)
		(stroke
			(width 0.2)
			(type default)
		)
		(fill no)
		(layer "In1.Cu")
	)
	(gr_circle
		(center 334.4418 -56.1594)
		(end 335.3308 -56.1594)
		(stroke
			(width 0.2)
			(type default)
		)
		(fill no)
		(layer "In1.Cu")
	)
	(gr_circle
		(center 334.4418 -55.3974)
		(end 335.3308 -55.3974)
		(stroke
			(width 0.2)
			(type default)
		)
		(fill no)
		(layer "In1.Cu")
	)
	(gr_circle
		(center 334.4418 -54.6354)
		(end 335.3308 -54.6354)
		(stroke
			(width 0.2)
			(type default)
		)
		(fill no)
		(layer "In1.Cu")
	)
	(gr_circle
		(center 334.4418 -53.8734)
		(end 335.3308 -53.8734)
		(stroke
			(width 0.2)
			(type default)
		)
		(fill no)
		(layer "In1.Cu")
	)
	(gr_circle
		(center 334.4418 -44.8818)
		(end 335.3308 -44.8818)
		(stroke
			(width 0.2)
			(type default)
		)
		(fill no)
		(layer "In1.Cu")
	)
	(gr_circle
		(center 334.4418 -44.1198)
		(end 335.3308 -44.1198)
		(stroke
			(width 0.2)
			(type default)
		)
		(fill no)
		(layer "In1.Cu")
	)
	(gr_circle
		(center 334.4418 -43.3578)
		(end 335.3308 -43.3578)
		(stroke
			(width 0.2)
			(type default)
		)
		(fill no)
		(layer "In1.Cu")
	)
	(gr_circle
		(center 334.4418 -42.5958)
		(end 335.3308 -42.5958)
		(stroke
			(width 0.2)
			(type default)
		)
		(fill no)
		(layer "In1.Cu")
	)
	(gr_circle
		(center 334.4418 -34.3662)
		(end 335.3308 -34.3662)
		(stroke
			(width 0.2)
			(type default)
		)
		(fill no)
		(layer "In1.Cu")
	)
	(gr_circle
		(center 334.4418 -33.6042)
		(end 335.3308 -33.6042)
		(stroke
			(width 0.2)
			(type default)
		)
		(fill no)
		(layer "In1.Cu")
	)
	(gr_circle
		(center 334.4418 -32.8422)
		(end 335.3308 -32.8422)
		(stroke
			(width 0.2)
			(type default)
		)
		(fill no)
		(layer "In1.Cu")
	)
	(gr_circle
		(center 334.4418 -32.0802)
		(end 335.3308 -32.0802)
		(stroke
			(width 0.2)
			(type default)
		)
		(fill no)
		(layer "In1.Cu")
	)
	(gr_circle
		(center 334.4418 -31.3182)
		(end 335.3308 -31.3182)
		(stroke
			(width 0.2)
			(type default)
		)
		(fill no)
		(layer "In1.Cu")
	)
	(gr_circle
		(center 334.4418 -23.0886)
		(end 335.3308 -23.0886)
		(stroke
			(width 0.2)
			(type default)
		)
		(fill no)
		(layer "In1.Cu")
	)
	(gr_circle
		(center 334.4418 -22.3266)
		(end 335.3308 -22.3266)
		(stroke
			(width 0.2)
			(type default)
		)
		(fill no)
		(layer "In1.Cu")
	)
	(gr_circle
		(center 334.4418 -21.5646)
		(end 335.3308 -21.5646)
		(stroke
			(width 0.2)
			(type default)
		)
		(fill no)
		(layer "In1.Cu")
	)
	(gr_circle
		(center 334.4418 -20.8026)
		(end 335.3308 -20.8026)
		(stroke
			(width 0.2)
			(type default)
		)
		(fill no)
		(layer "In1.Cu")
	)
	(gr_circle
		(center 334.4418 -20.0406)
		(end 335.3308 -20.0406)
		(stroke
			(width 0.2)
			(type default)
		)
		(fill no)
		(layer "In1.Cu")
	)
	(gr_circle
		(center 335.2038 -77.1906)
		(end 336.0928 -77.1906)
		(stroke
			(width 0.2)
			(type default)
		)
		(fill no)
		(layer "In1.Cu")
	)
	(gr_circle
		(center 335.2038 -76.4286)
		(end 336.0928 -76.4286)
		(stroke
			(width 0.2)
			(type default)
		)
		(fill no)
		(layer "In1.Cu")
	)
	(gr_circle
		(center 335.2038 -68.199)
		(end 336.0928 -68.199)
		(stroke
			(width 0.2)
			(type default)
		)
		(fill no)
		(layer "In1.Cu")
	)
	(gr_circle
		(center 335.2038 -67.437)
		(end 336.0928 -67.437)
		(stroke
			(width 0.2)
			(type default)
		)
		(fill no)
		(layer "In1.Cu")
	)
	(gr_circle
		(center 335.2038 -66.675)
		(end 336.0928 -66.675)
		(stroke
			(width 0.2)
			(type default)
		)
		(fill no)
		(layer "In1.Cu")
	)
	(gr_circle
		(center 335.2038 -65.913)
		(end 336.0928 -65.913)
		(stroke
			(width 0.2)
			(type default)
		)
		(fill no)
		(layer "In1.Cu")
	)
	(gr_circle
		(center 335.2038 -65.151)
		(end 336.0928 -65.151)
		(stroke
			(width 0.2)
			(type default)
		)
		(fill no)
		(layer "In1.Cu")
	)
	(gr_circle
		(center 335.2038 -56.9214)
		(end 336.0928 -56.9214)
		(stroke
			(width 0.2)
			(type default)
		)
		(fill no)
		(layer "In1.Cu")
	)
	(gr_circle
		(center 335.2038 -56.1594)
		(end 336.0928 -56.1594)
		(stroke
			(width 0.2)
			(type default)
		)
		(fill no)
		(layer "In1.Cu")
	)
	(gr_circle
		(center 335.2038 -55.3974)
		(end 336.0928 -55.3974)
		(stroke
			(width 0.2)
			(type default)
		)
		(fill no)
		(layer "In1.Cu")
	)
	(gr_circle
		(center 335.2038 -54.6354)
		(end 336.0928 -54.6354)
		(stroke
			(width 0.2)
			(type default)
		)
		(fill no)
		(layer "In1.Cu")
	)
	(gr_circle
		(center 335.2038 -53.8734)
		(end 336.0928 -53.8734)
		(stroke
			(width 0.2)
			(type default)
		)
		(fill no)
		(layer "In1.Cu")
	)
	(gr_circle
		(center 335.2038 -44.8818)
		(end 336.0928 -44.8818)
		(stroke
			(width 0.2)
			(type default)
		)
		(fill no)
		(layer "In1.Cu")
	)
	(gr_circle
		(center 335.2038 -44.1198)
		(end 336.0928 -44.1198)
		(stroke
			(width 0.2)
			(type default)
		)
		(fill no)
		(layer "In1.Cu")
	)
	(gr_circle
		(center 335.2038 -43.3578)
		(end 336.0928 -43.3578)
		(stroke
			(width 0.2)
			(type default)
		)
		(fill no)
		(layer "In1.Cu")
	)
	(gr_circle
		(center 335.2038 -42.5958)
		(end 336.0928 -42.5958)
		(stroke
			(width 0.2)
			(type default)
		)
		(fill no)
		(layer "In1.Cu")
	)
	(gr_circle
		(center 335.2038 -34.3662)
		(end 336.0928 -34.3662)
		(stroke
			(width 0.2)
			(type default)
		)
		(fill no)
		(layer "In1.Cu")
	)
	(gr_circle
		(center 335.2038 -33.6042)
		(end 336.0928 -33.6042)
		(stroke
			(width 0.2)
			(type default)
		)
		(fill no)
		(layer "In1.Cu")
	)
	(gr_circle
		(center 335.2038 -32.8422)
		(end 336.0928 -32.8422)
		(stroke
			(width 0.2)
			(type default)
		)
		(fill no)
		(layer "In1.Cu")
	)
	(gr_circle
		(center 335.2038 -32.0802)
		(end 336.0928 -32.0802)
		(stroke
			(width 0.2)
			(type default)
		)
		(fill no)
		(layer "In1.Cu")
	)
	(gr_circle
		(center 335.2038 -31.3182)
		(end 336.0928 -31.3182)
		(stroke
			(width 0.2)
			(type default)
		)
		(fill no)
		(layer "In1.Cu")
	)
	(gr_circle
		(center 335.2038 -23.0886)
		(end 336.0928 -23.0886)
		(stroke
			(width 0.2)
			(type default)
		)
		(fill no)
		(layer "In1.Cu")
	)
	(gr_circle
		(center 335.2038 -22.3266)
		(end 336.0928 -22.3266)
		(stroke
			(width 0.2)
			(type default)
		)
		(fill no)
		(layer "In1.Cu")
	)
	(gr_circle
		(center 335.2038 -21.5646)
		(end 336.0928 -21.5646)
		(stroke
			(width 0.2)
			(type default)
		)
		(fill no)
		(layer "In1.Cu")
	)
	(gr_circle
		(center 335.2038 -20.8026)
		(end 336.0928 -20.8026)
		(stroke
			(width 0.2)
			(type default)
		)
		(fill no)
		(layer "In1.Cu")
	)
	(gr_circle
		(center 335.2038 -20.0406)
		(end 336.0928 -20.0406)
		(stroke
			(width 0.2)
			(type default)
		)
		(fill no)
		(layer "In1.Cu")
	)
	(gr_circle
		(center 335.367884 -73.6346)
		(end 336.256884 -73.6346)
		(stroke
			(width 0.2)
			(type default)
		)
		(fill no)
		(layer "In1.Cu")
	)
	(gr_circle
		(center 335.367884 -62.357)
		(end 336.256884 -62.357)
		(stroke
			(width 0.2)
			(type default)
		)
		(fill no)
		(layer "In1.Cu")
	)
	(gr_circle
		(center 335.367884 -51.0794)
		(end 336.256884 -51.0794)
		(stroke
			(width 0.2)
			(type default)
		)
		(fill no)
		(layer "In1.Cu")
	)
	(gr_circle
		(center 335.367884 -39.8018)
		(end 336.256884 -39.8018)
		(stroke
			(width 0.2)
			(type default)
		)
		(fill no)
		(layer "In1.Cu")
	)
	(gr_circle
		(center 335.367884 -28.5242)
		(end 336.256884 -28.5242)
		(stroke
			(width 0.2)
			(type default)
		)
		(fill no)
		(layer "In1.Cu")
	)
	(gr_circle
		(center 335.367884 -17.2466)
		(end 336.256884 -17.2466)
		(stroke
			(width 0.2)
			(type default)
		)
		(fill no)
		(layer "In1.Cu")
	)
	(gr_circle
		(center 336.3214 -49.5046)
		(end 337.2104 -49.5046)
		(stroke
			(width 0.2)
			(type default)
		)
		(fill no)
		(layer "In1.Cu")
	)
	(gr_circle
		(center 336.3214 -38.227)
		(end 337.2104 -38.227)
		(stroke
			(width 0.2)
			(type default)
		)
		(fill no)
		(layer "In1.Cu")
	)
	(gr_circle
		(center 338.498434 -48.423576)
		(end 339.387434 -48.423576)
		(stroke
			(width 0.2)
			(type default)
		)
		(fill no)
		(layer "In1.Cu")
	)
	(gr_circle
		(center 338.87156 -37.247068)
		(end 339.76056 -37.247068)
		(stroke
			(width 0.2)
			(type default)
		)
		(fill no)
		(layer "In1.Cu")
	)
	(gr_circle
		(center 354.89642 -5.353304)
		(end 355.78542 -5.353304)
		(stroke
			(width 0.2)
			(type default)
		)
		(fill no)
		(layer "In1.Cu")
	)
	(gr_circle
		(center 354.89642 -4.591304)
		(end 355.78542 -4.591304)
		(stroke
			(width 0.2)
			(type default)
		)
		(fill no)
		(layer "In1.Cu")
	)
	(gr_circle
		(center 354.89642 -3.829304)
		(end 355.78542 -3.829304)
		(stroke
			(width 0.2)
			(type default)
		)
		(fill no)
		(layer "In1.Cu")
	)
	(gr_circle
		(center 355.65842 -5.353304)
		(end 356.54742 -5.353304)
		(stroke
			(width 0.2)
			(type default)
		)
		(fill no)
		(layer "In1.Cu")
	)
	(gr_circle
		(center 355.65842 -4.591304)
		(end 356.54742 -4.591304)
		(stroke
			(width 0.2)
			(type default)
		)
		(fill no)
		(layer "In1.Cu")
	)
	(gr_circle
		(center 355.65842 -3.829304)
		(end 356.54742 -3.829304)
		(stroke
			(width 0.2)
			(type default)
		)
		(fill no)
		(layer "In1.Cu")
	)
	(gr_circle
		(center 356.42042 -5.353304)
		(end 357.30942 -5.353304)
		(stroke
			(width 0.2)
			(type default)
		)
		(fill no)
		(layer "In1.Cu")
	)
	(gr_circle
		(center 356.42042 -4.591304)
		(end 357.30942 -4.591304)
		(stroke
			(width 0.2)
			(type default)
		)
		(fill no)
		(layer "In1.Cu")
	)
	(gr_circle
		(center 356.42042 -3.829304)
		(end 357.30942 -3.829304)
		(stroke
			(width 0.2)
			(type default)
		)
		(fill no)
		(layer "In1.Cu")
	)
	(gr_circle
		(center 357.18242 -5.353304)
		(end 358.07142 -5.353304)
		(stroke
			(width 0.2)
			(type default)
		)
		(fill no)
		(layer "In1.Cu")
	)
	(gr_circle
		(center 357.18242 -4.591304)
		(end 358.07142 -4.591304)
		(stroke
			(width 0.2)
			(type default)
		)
		(fill no)
		(layer "In1.Cu")
	)
	(gr_circle
		(center 357.18242 -3.829304)
		(end 358.07142 -3.829304)
		(stroke
			(width 0.2)
			(type default)
		)
		(fill no)
		(layer "In1.Cu")
	)
	(gr_circle
		(center 357.94442 -5.353304)
		(end 358.83342 -5.353304)
		(stroke
			(width 0.2)
			(type default)
		)
		(fill no)
		(layer "In1.Cu")
	)
	(gr_circle
		(center 357.94442 -4.591304)
		(end 358.83342 -4.591304)
		(stroke
			(width 0.2)
			(type default)
		)
		(fill no)
		(layer "In1.Cu")
	)
	(gr_circle
		(center 357.94442 -3.829304)
		(end 358.83342 -3.829304)
		(stroke
			(width 0.2)
			(type default)
		)
		(fill no)
		(layer "In1.Cu")
	)
	(gr_circle
		(center 358.70642 -5.353304)
		(end 359.59542 -5.353304)
		(stroke
			(width 0.2)
			(type default)
		)
		(fill no)
		(layer "In1.Cu")
	)
	(gr_circle
		(center 358.70642 -4.591304)
		(end 359.59542 -4.591304)
		(stroke
			(width 0.2)
			(type default)
		)
		(fill no)
		(layer "In1.Cu")
	)
	(gr_circle
		(center 358.70642 -3.829304)
		(end 359.59542 -3.829304)
		(stroke
			(width 0.2)
			(type default)
		)
		(fill no)
		(layer "In1.Cu")
	)
	(gr_circle
		(center 363.000036 -160.830006)
		(end 364.21314 -160.830006)
		(stroke
			(width 0.2)
			(type default)
		)
		(fill no)
		(layer "In1.Cu")
	)
	(gr_circle
		(center 363.000036 -158.83001)
		(end 364.21314 -158.83001)
		(stroke
			(width 0.2)
			(type default)
		)
		(fill no)
		(layer "In1.Cu")
	)
	(gr_circle
		(center 363.000036 -156.830014)
		(end 364.21314 -156.830014)
		(stroke
			(width 0.2)
			(type default)
		)
		(fill no)
		(layer "In1.Cu")
	)
	(gr_circle
		(center 363.996478 -159.89681)
		(end 365.209582 -159.89681)
		(stroke
			(width 0.2)
			(type default)
		)
		(fill no)
		(layer "In1.Cu")
	)
	(gr_circle
		(center 363.996478 -157.896814)
		(end 365.209582 -157.896814)
		(stroke
			(width 0.2)
			(type default)
		)
		(fill no)
		(layer "In1.Cu")
	)
	(gr_circle
		(center 365.000032 -160.830006)
		(end 366.213136 -160.830006)
		(stroke
			(width 0.2)
			(type default)
		)
		(fill no)
		(layer "In1.Cu")
	)
	(gr_circle
		(center 365.000032 -158.83001)
		(end 366.213136 -158.83001)
		(stroke
			(width 0.2)
			(type default)
		)
		(fill no)
		(layer "In1.Cu")
	)
	(gr_circle
		(center 365.000032 -156.830014)
		(end 366.213136 -156.830014)
		(stroke
			(width 0.2)
			(type default)
		)
		(fill no)
		(layer "In1.Cu")
	)
	(gr_circle
		(center 366.119918 -2.590038)
		(end 367.333022 -2.590038)
		(stroke
			(width 0.2)
			(type default)
		)
		(fill no)
		(layer "In1.Cu")
	)
	(gr_circle
		(center 368.659918 -2.590038)
		(end 369.873022 -2.590038)
		(stroke
			(width 0.2)
			(type default)
		)
		(fill no)
		(layer "In1.Cu")
	)
	(gr_circle
		(center 369.000024 -160.830006)
		(end 370.213128 -160.830006)
		(stroke
			(width 0.2)
			(type default)
		)
		(fill no)
		(layer "In1.Cu")
	)
	(gr_circle
		(center 369.000024 -158.83001)
		(end 370.213128 -158.83001)
		(stroke
			(width 0.2)
			(type default)
		)
		(fill no)
		(layer "In1.Cu")
	)
	(gr_circle
		(center 369.000024 -156.830014)
		(end 370.213128 -156.830014)
		(stroke
			(width 0.2)
			(type default)
		)
		(fill no)
		(layer "In1.Cu")
	)
	(gr_circle
		(center 370.041678 -159.84601)
		(end 371.254782 -159.84601)
		(stroke
			(width 0.2)
			(type default)
		)
		(fill no)
		(layer "In1.Cu")
	)
	(gr_circle
		(center 370.041678 -157.846014)
		(end 371.254782 -157.846014)
		(stroke
			(width 0.2)
			(type default)
		)
		(fill no)
		(layer "In1.Cu")
	)
	(gr_circle
		(center 371.00002 -160.830006)
		(end 372.213124 -160.830006)
		(stroke
			(width 0.2)
			(type default)
		)
		(fill no)
		(layer "In1.Cu")
	)
	(gr_circle
		(center 371.00002 -158.83001)
		(end 372.213124 -158.83001)
		(stroke
			(width 0.2)
			(type default)
		)
		(fill no)
		(layer "In1.Cu")
	)
	(gr_circle
		(center 371.00002 -156.830014)
		(end 372.213124 -156.830014)
		(stroke
			(width 0.2)
			(type default)
		)
		(fill no)
		(layer "In1.Cu")
	)
	(gr_circle
		(center 375.000012 -160.830006)
		(end 376.213116 -160.830006)
		(stroke
			(width 0.2)
			(type default)
		)
		(fill no)
		(layer "In1.Cu")
	)
	(gr_circle
		(center 375.000012 -158.83001)
		(end 376.213116 -158.83001)
		(stroke
			(width 0.2)
			(type default)
		)
		(fill no)
		(layer "In1.Cu")
	)
	(gr_circle
		(center 375.000012 -156.830014)
		(end 376.213116 -156.830014)
		(stroke
			(width 0.2)
			(type default)
		)
		(fill no)
		(layer "In1.Cu")
	)
	(gr_circle
		(center 375.832878 -159.89681)
		(end 377.045982 -159.89681)
		(stroke
			(width 0.2)
			(type default)
		)
		(fill no)
		(layer "In1.Cu")
	)
	(gr_circle
		(center 375.832878 -157.896814)
		(end 377.045982 -157.896814)
		(stroke
			(width 0.2)
			(type default)
		)
		(fill no)
		(layer "In1.Cu")
	)
	(gr_circle
		(center 377.000008 -160.830006)
		(end 378.213112 -160.830006)
		(stroke
			(width 0.2)
			(type default)
		)
		(fill no)
		(layer "In1.Cu")
	)
	(gr_circle
		(center 377.000008 -158.83001)
		(end 378.213112 -158.83001)
		(stroke
			(width 0.2)
			(type default)
		)
		(fill no)
		(layer "In1.Cu")
	)
	(gr_circle
		(center 377.000008 -156.830014)
		(end 378.213112 -156.830014)
		(stroke
			(width 0.2)
			(type default)
		)
		(fill no)
		(layer "In1.Cu")
	)
	(gr_circle
		(center 378.079 -139.7)
		(end 379.603 -139.7)
		(stroke
			(width 0.2)
			(type default)
		)
		(fill no)
		(layer "In1.Cu")
	)
	(gr_circle
		(center 378.079 -119.38)
		(end 379.603 -119.38)
		(stroke
			(width 0.2)
			(type default)
		)
		(fill no)
		(layer "In1.Cu")
	)
	(gr_circle
		(center 378.079 -99.06)
		(end 379.603 -99.06)
		(stroke
			(width 0.2)
			(type default)
		)
		(fill no)
		(layer "In1.Cu")
	)
	(gr_circle
		(center 378.079 -78.74)
		(end 379.603 -78.74)
		(stroke
			(width 0.2)
			(type default)
		)
		(fill no)
		(layer "In1.Cu")
	)
	(gr_circle
		(center 378.079 -58.42)
		(end 379.603 -58.42)
		(stroke
			(width 0.2)
			(type default)
		)
		(fill no)
		(layer "In1.Cu")
	)
	(gr_circle
		(center 383.199894 -160.830006)
		(end 384.412998 -160.830006)
		(stroke
			(width 0.2)
			(type default)
		)
		(fill no)
		(layer "In1.Cu")
	)
	(gr_circle
		(center 383.199894 -158.83001)
		(end 384.412998 -158.83001)
		(stroke
			(width 0.2)
			(type default)
		)
		(fill no)
		(layer "In1.Cu")
	)
	(gr_circle
		(center 383.199894 -156.830014)
		(end 384.412998 -156.830014)
		(stroke
			(width 0.2)
			(type default)
		)
		(fill no)
		(layer "In1.Cu")
	)
	(gr_circle
		(center 384.113278 -159.97301)
		(end 385.326382 -159.97301)
		(stroke
			(width 0.2)
			(type default)
		)
		(fill no)
		(layer "In1.Cu")
	)
	(gr_circle
		(center 384.113278 -157.973014)
		(end 385.326382 -157.973014)
		(stroke
			(width 0.2)
			(type default)
		)
		(fill no)
		(layer "In1.Cu")
	)
	(gr_circle
		(center 385.19989 -160.830006)
		(end 386.412994 -160.830006)
		(stroke
			(width 0.2)
			(type default)
		)
		(fill no)
		(layer "In1.Cu")
	)
	(gr_circle
		(center 385.19989 -158.83001)
		(end 386.412994 -158.83001)
		(stroke
			(width 0.2)
			(type default)
		)
		(fill no)
		(layer "In1.Cu")
	)
	(gr_circle
		(center 385.19989 -156.830014)
		(end 386.412994 -156.830014)
		(stroke
			(width 0.2)
			(type default)
		)
		(fill no)
		(layer "In1.Cu")
	)
	(gr_circle
		(center 389.199882 -160.830006)
		(end 390.412986 -160.830006)
		(stroke
			(width 0.2)
			(type default)
		)
		(fill no)
		(layer "In1.Cu")
	)
	(gr_circle
		(center 389.199882 -158.83001)
		(end 390.412986 -158.83001)
		(stroke
			(width 0.2)
			(type default)
		)
		(fill no)
		(layer "In1.Cu")
	)
	(gr_circle
		(center 389.199882 -156.830014)
		(end 390.412986 -156.830014)
		(stroke
			(width 0.2)
			(type default)
		)
		(fill no)
		(layer "In1.Cu")
	)
	(gr_circle
		(center 390.082278 -159.74441)
		(end 391.295382 -159.74441)
		(stroke
			(width 0.2)
			(type default)
		)
		(fill no)
		(layer "In1.Cu")
	)
	(gr_circle
		(center 390.082278 -157.744414)
		(end 391.295382 -157.744414)
		(stroke
			(width 0.2)
			(type default)
		)
		(fill no)
		(layer "In1.Cu")
	)
	(gr_circle
		(center 391.199878 -160.830006)
		(end 392.412982 -160.830006)
		(stroke
			(width 0.2)
			(type default)
		)
		(fill no)
		(layer "In1.Cu")
	)
	(gr_circle
		(center 391.199878 -158.83001)
		(end 392.412982 -158.83001)
		(stroke
			(width 0.2)
			(type default)
		)
		(fill no)
		(layer "In1.Cu")
	)
	(gr_circle
		(center 391.199878 -156.830014)
		(end 392.412982 -156.830014)
		(stroke
			(width 0.2)
			(type default)
		)
		(fill no)
		(layer "In1.Cu")
	)
	(gr_circle
		(center 397.637 -139.7)
		(end 399.161 -139.7)
		(stroke
			(width 0.2)
			(type default)
		)
		(fill no)
		(layer "In1.Cu")
	)
	(gr_circle
		(center 397.637 -119.38)
		(end 399.161 -119.38)
		(stroke
			(width 0.2)
			(type default)
		)
		(fill no)
		(layer "In1.Cu")
	)
	(gr_circle
		(center 397.637 -99.06)
		(end 399.161 -99.06)
		(stroke
			(width 0.2)
			(type default)
		)
		(fill no)
		(layer "In1.Cu")
	)
	(gr_circle
		(center 397.637 -78.74)
		(end 399.161 -78.74)
		(stroke
			(width 0.2)
			(type default)
		)
		(fill no)
		(layer "In1.Cu")
	)
	(gr_circle
		(center 397.637 -58.42)
		(end 399.161 -58.42)
		(stroke
			(width 0.2)
			(type default)
		)
		(fill no)
		(layer "In1.Cu")
	)
	(gr_circle
		(center 398.375124 -168.82999)
		(end 399.588228 -168.82999)
		(stroke
			(width 0.2)
			(type default)
		)
		(fill no)
		(layer "In1.Cu")
	)
	(gr_circle
		(center 398.375124 -166.829994)
		(end 399.588228 -166.829994)
		(stroke
			(width 0.2)
			(type default)
		)
		(fill no)
		(layer "In1.Cu")
	)
	(gr_circle
		(center 398.375124 -164.829998)
		(end 399.588228 -164.829998)
		(stroke
			(width 0.2)
			(type default)
		)
		(fill no)
		(layer "In1.Cu")
	)
	(gr_circle
		(center 398.375124 -162.830002)
		(end 399.588228 -162.830002)
		(stroke
			(width 0.2)
			(type default)
		)
		(fill no)
		(layer "In1.Cu")
	)
	(gr_circle
		(center 398.375124 -160.830006)
		(end 399.588228 -160.830006)
		(stroke
			(width 0.2)
			(type default)
		)
		(fill no)
		(layer "In1.Cu")
	)
	(gr_circle
		(center 398.375124 -158.83001)
		(end 399.588228 -158.83001)
		(stroke
			(width 0.2)
			(type default)
		)
		(fill no)
		(layer "In1.Cu")
	)
	(gr_circle
		(center 398.375124 -156.830014)
		(end 399.588228 -156.830014)
		(stroke
			(width 0.2)
			(type default)
		)
		(fill no)
		(layer "In1.Cu")
	)
	(gr_circle
		(center 398.375124 -154.830018)
		(end 399.588228 -154.830018)
		(stroke
			(width 0.2)
			(type default)
		)
		(fill no)
		(layer "In1.Cu")
	)
	(gr_circle
		(center 398.375124 -152.830022)
		(end 399.588228 -152.830022)
		(stroke
			(width 0.2)
			(type default)
		)
		(fill no)
		(layer "In1.Cu")
	)
	(gr_circle
		(center 399.33372 -167.871394)
		(end 400.546824 -167.871394)
		(stroke
			(width 0.2)
			(type default)
		)
		(fill no)
		(layer "In1.Cu")
	)
	(gr_circle
		(center 399.33372 -165.871398)
		(end 400.546824 -165.871398)
		(stroke
			(width 0.2)
			(type default)
		)
		(fill no)
		(layer "In1.Cu")
	)
	(gr_circle
		(center 399.33372 -163.871402)
		(end 400.546824 -163.871402)
		(stroke
			(width 0.2)
			(type default)
		)
		(fill no)
		(layer "In1.Cu")
	)
	(gr_circle
		(center 399.33372 -161.871406)
		(end 400.546824 -161.871406)
		(stroke
			(width 0.2)
			(type default)
		)
		(fill no)
		(layer "In1.Cu")
	)
	(gr_circle
		(center 399.33372 -159.87141)
		(end 400.546824 -159.87141)
		(stroke
			(width 0.2)
			(type default)
		)
		(fill no)
		(layer "In1.Cu")
	)
	(gr_circle
		(center 399.33372 -157.871414)
		(end 400.546824 -157.871414)
		(stroke
			(width 0.2)
			(type default)
		)
		(fill no)
		(layer "In1.Cu")
	)
	(gr_circle
		(center 399.33372 -155.871418)
		(end 400.546824 -155.871418)
		(stroke
			(width 0.2)
			(type default)
		)
		(fill no)
		(layer "In1.Cu")
	)
	(gr_circle
		(center 399.33372 -153.871422)
		(end 400.546824 -153.871422)
		(stroke
			(width 0.2)
			(type default)
		)
		(fill no)
		(layer "In1.Cu")
	)
	(gr_circle
		(center 400.37512 -168.82999)
		(end 401.588224 -168.82999)
		(stroke
			(width 0.2)
			(type default)
		)
		(fill no)
		(layer "In1.Cu")
	)
	(gr_circle
		(center 400.37512 -166.829994)
		(end 401.588224 -166.829994)
		(stroke
			(width 0.2)
			(type default)
		)
		(fill no)
		(layer "In1.Cu")
	)
	(gr_circle
		(center 400.37512 -164.829998)
		(end 401.588224 -164.829998)
		(stroke
			(width 0.2)
			(type default)
		)
		(fill no)
		(layer "In1.Cu")
	)
	(gr_circle
		(center 400.37512 -162.830002)
		(end 401.588224 -162.830002)
		(stroke
			(width 0.2)
			(type default)
		)
		(fill no)
		(layer "In1.Cu")
	)
	(gr_circle
		(center 400.37512 -160.830006)
		(end 401.588224 -160.830006)
		(stroke
			(width 0.2)
			(type default)
		)
		(fill no)
		(layer "In1.Cu")
	)
	(gr_circle
		(center 400.37512 -158.83001)
		(end 401.588224 -158.83001)
		(stroke
			(width 0.2)
			(type default)
		)
		(fill no)
		(layer "In1.Cu")
	)
	(gr_circle
		(center 400.37512 -156.830014)
		(end 401.588224 -156.830014)
		(stroke
			(width 0.2)
			(type default)
		)
		(fill no)
		(layer "In1.Cu")
	)
	(gr_circle
		(center 400.37512 -154.830018)
		(end 401.588224 -154.830018)
		(stroke
			(width 0.2)
			(type default)
		)
		(fill no)
		(layer "In1.Cu")
	)
	(gr_circle
		(center 400.37512 -152.830022)
		(end 401.588224 -152.830022)
		(stroke
			(width 0.2)
			(type default)
		)
		(fill no)
		(layer "In1.Cu")
	)
	(gr_circle
		(center 468.920068 -76.309982)
		(end 470.329768 -76.309982)
		(stroke
			(width 0.2)
			(type default)
		)
		(fill no)
		(layer "In1.Cu")
	)
	(gr_circle
		(center 468.920068 -73.769982)
		(end 470.329768 -73.769982)
		(stroke
			(width 0.2)
			(type default)
		)
		(fill no)
		(layer "In1.Cu")
	)
	(gr_circle
		(center 468.920068 -71.229982)
		(end 470.329768 -71.229982)
		(stroke
			(width 0.2)
			(type default)
		)
		(fill no)
		(layer "In1.Cu")
	)
	(gr_circle
		(center 468.920068 -68.689982)
		(end 470.329768 -68.689982)
		(stroke
			(width 0.2)
			(type default)
		)
		(fill no)
		(layer "In1.Cu")
	)
	(gr_circle
		(center 470.324688 -75.065382)
		(end 471.734388 -75.065382)
		(stroke
			(width 0.2)
			(type default)
		)
		(fill no)
		(layer "In1.Cu")
	)
	(gr_circle
		(center 470.324688 -72.525382)
		(end 471.734388 -72.525382)
		(stroke
			(width 0.2)
			(type default)
		)
		(fill no)
		(layer "In1.Cu")
	)
	(gr_circle
		(center 470.324688 -69.985382)
		(end 471.734388 -69.985382)
		(stroke
			(width 0.2)
			(type default)
		)
		(fill no)
		(layer "In1.Cu")
	)
	(gr_circle
		(center 471.620088 -76.309982)
		(end 473.029788 -76.309982)
		(stroke
			(width 0.2)
			(type default)
		)
		(fill no)
		(layer "In1.Cu")
	)
	(gr_circle
		(center 471.620088 -73.769982)
		(end 473.029788 -73.769982)
		(stroke
			(width 0.2)
			(type default)
		)
		(fill no)
		(layer "In1.Cu")
	)
	(gr_circle
		(center 471.620088 -71.229982)
		(end 473.029788 -71.229982)
		(stroke
			(width 0.2)
			(type default)
		)
		(fill no)
		(layer "In1.Cu")
	)
	(gr_circle
		(center 471.620088 -68.689982)
		(end 473.029788 -68.689982)
		(stroke
			(width 0.2)
			(type default)
		)
		(fill no)
		(layer "In1.Cu")
	)
	(gr_poly
		(pts
			(xy 193.11239 -50.557684) (xy 193.11239 -46.692312) (xy 189.727078 -43.307) (xy 186.12612 -43.307)
			(xy 182.695342 -46.737778) (xy 182.695342 -50.684938) (xy 182.942484 -50.93208) (xy 192.737994 -50.93208)
		)
		(stroke
			(width 0)
			(type solid)
		)
		(fill yes)
		(layer "In2.Cu")
		(net "P52V_2_FUSE_1")
	)
	(gr_poly
		(pts
			(xy 257.683 -50.557684) (xy 257.683 -46.692312) (xy 254.297688 -43.307) (xy 250.69673 -43.307) (xy 247.265952 -46.737778)
			(xy 247.265952 -50.684938) (xy 247.513094 -50.93208) (xy 257.308604 -50.93208)
		)
		(stroke
			(width 0)
			(type solid)
		)
		(fill yes)
		(layer "In2.Cu")
		(net "P52V_1_FUSE_1")
	)
	(gr_poly
		(pts
			(xy 136.368536 -79.629) (xy 136.368536 -68.0466) (xy 136.368536 -63.596012) (xy 142.354046 -57.610502)
			(xy 142.354046 -46.90491) (xy 142.185136 -46.736) (xy 132.025136 -46.736) (xy 123.846336 -46.736)
			(xy 123.516136 -47.0662) (xy 123.516136 -79.7052) (xy 123.795536 -79.9846) (xy 132.050536 -79.9846)
			(xy 134.565136 -79.9846) (xy 136.012936 -79.9846)
		)
		(stroke
			(width 0)
			(type solid)
		)
		(fill yes)
		(layer "In2.Cu")
		(net "P52V_HS2_DRAIN_1")
	)
	(gr_poly
		(pts
			(xy 324.104 -79.7052) (xy 324.104 -47.0662) (xy 323.7738 -46.736) (xy 305.773328 -46.736) (xy 305.6382 -46.871128)
			(xy 305.6382 -62.431422) (xy 306.004214 -62.797436) (xy 306.004214 -66.561208) (xy 306.270406 -66.8274)
			(xy 310.0324 -66.8274) (xy 311.2516 -68.0466) (xy 311.2516 -79.629) (xy 311.6072 -79.9846) (xy 323.8246 -79.9846)
		)
		(stroke
			(width 0)
			(type solid)
		)
		(fill yes)
		(layer "In2.Cu")
		(net "P52V_HS1_DRAIN_1")
	)
	(gr_poly
		(pts
			(xy 324.104 -45.8724) (xy 324.104 -13.2334) (xy 323.7738 -12.9032) (xy 305.767486 -12.9032) (xy 305.6382 -13.032486)
			(xy 305.6382 -28.882086) (xy 306.082192 -29.326078) (xy 306.082192 -32.64408) (xy 306.432712 -32.9946)
			(xy 310.0324 -32.9946) (xy 311.2516 -34.2138) (xy 311.2516 -45.7962) (xy 311.6072 -46.1518) (xy 323.8246 -46.1518)
		)
		(stroke
			(width 0)
			(type solid)
		)
		(fill yes)
		(layer "In2.Cu")
		(net "P52V_HS1_DRAIN_2")
	)
	(gr_poly
		(pts
			(xy 142.24 -45.847) (xy 142.367 -45.847) (xy 142.367 -42.0878) (xy 140.7922 -40.513) (xy 138.938 -40.513)
			(xy 137.541 -39.116) (xy 137.541 -33.3756) (xy 137.922 -32.9946) (xy 141.736826 -32.9946) (xy 141.981936 -32.74949)
			(xy 141.981936 -13.434822) (xy 141.450314 -12.9032) (xy 123.846336 -12.9032) (xy 123.516136 -13.2334)
			(xy 123.516136 -45.8724) (xy 123.795536 -46.1518) (xy 136.012936 -46.1518) (xy 141.9352 -46.1518)
		)
		(stroke
			(width 0)
			(type solid)
		)
		(fill yes)
		(layer "In2.Cu")
		(net "P52V_HS2_DRAIN_2")
	)
	(gr_poly
		(pts
			(xy 301.490126 -66.378582) (xy 303.257204 -66.378582) (xy 303.572672 -66.063114) (xy 303.572672 -44.111672)
			(xy 300.482 -41.021) (xy 298.631864 -39.170864) (xy 298.631864 -33.31337) (xy 298.984162 -32.961072)
			(xy 301.084996 -32.961072) (xy 301.408338 -32.63773) (xy 303.245774 -32.63773) (xy 303.572672 -32.310832)
			(xy 303.572672 -12.999212) (xy 303.379632 -12.806172) (xy 282.954222 -12.806172) (xy 279.484836 -16.275558)
			(xy 279.484836 -26.865072) (xy 277.128478 -29.22143)
			(arc
				(start 230.533956 -29.22143)
				(mid 230.514433 -29.225331)
				(end 230.497888 -29.236416)
			)
			(arc
				(start 230.011986 -29.722318)
				(mid 230.000875 -29.738852)
				(end 229.997 -29.758386)
			)
			(arc
				(start 229.997 -46.841918)
				(mid 230.000901 -46.861441)
				(end 230.011986 -46.877986)
			)
			(arc
				(start 230.363014 -47.229014)
				(mid 230.379548 -47.240125)
				(end 230.399082 -47.244)
			)
			(xy 242.8494 -47.244) (xy 248.777252 -41.316148) (xy 256.0066 -41.316148) (xy 258.759452 -44.069)
			(xy 268.4018 -44.069) (xy 282.4861 -58.1533) (xy 293.6621 -58.1533) (xy 297.125136 -61.616336) (xy 297.125136 -65.302892)
			(xy 298.616116 -66.793872) (xy 301.074836 -66.793872)
		)
		(stroke
			(width 0)
			(type solid)
		)
		(fill yes)
		(layer "In2.Cu")
		(net "P52V_1")
	)
	(gr_poly
		(pts
			(xy 148.673312 -66.54673) (xy 148.673312 -60.590176) (xy 154.438604 -54.824884) (xy 167.249348 -54.824884)
			(xy 167.270176 -54.845712) (xy 175.383698 -54.845712) (xy 175.768762 -54.460648) (xy 175.768762 -53.66639)
			(xy 173.769782 -51.66741) (xy 172.350938 -51.66741) (xy 171.671488 -50.98796) (xy 171.671488 -43.334686)
			(xy 173.690026 -41.316148) (xy 192.0113 -41.316148) (xy 197.939152 -47.244)
			(arc
				(start 209.601054 -47.244)
				(mid 209.620577 -47.240099)
				(end 209.637122 -47.229014)
			)
			(arc
				(start 209.98815 -46.877986)
				(mid 209.999261 -46.861452)
				(end 210.003136 -46.841918)
			)
			(xy 210.003136 -30.415484) (xy 209.995516 -30.407864)
			(arc
				(start 209.995516 -30.311598)
				(mid 209.991615 -30.292075)
				(end 209.98053 -30.27553)
			)
			(xy 208.92643 -29.22143) (xy 161.90595 -29.22143) (xy 160.253426 -27.568906) (xy 160.253426 -15.386304)
			(xy 157.673294 -12.806172) (xy 144.399508 -12.806172) (xy 144.047464 -13.158216) (xy 144.047464 -28.727654)
			(xy 144.56156 -29.24175) (xy 144.56156 -32.50692) (xy 144.756632 -32.701992) (xy 147.447 -32.701992)
			(xy 147.828 -33.082992) (xy 147.828 -39.243) (xy 147.193 -39.878) (xy 145.8468 -39.878) (xy 143.637 -42.0878)
			(xy 143.637 -46.863) (xy 143.650716 -46.876716) (xy 143.650716 -46.886622) (xy 143.650716 -62.167008)
			(xy 144.600676 -63.116968) (xy 144.600676 -63.81877) (xy 147.575778 -66.793872) (xy 148.42617 -66.793872)
		)
		(stroke
			(width 0)
			(type solid)
		)
		(fill yes)
		(layer "In2.Cu")
		(net "P52V_2")
	)
	(gr_poly
		(pts
			(xy 391.88644 -169.87266) (xy 391.896506 -169.872228) (xy 391.915096 -169.864499) (xy 391.922508 -169.857674)
			(xy 392.292332 -169.48785) (xy 392.299178 -169.480452) (xy 392.306905 -169.461853) (xy 392.307318 -169.451782)
			(xy 392.307318 -164.263578) (xy 392.306891 -164.253509) (xy 392.299173 -164.234909) (xy 392.292332 -164.22751)
			(xy 391.858246 -163.793424) (xy 391.850846 -163.786584) (xy 391.832247 -163.778865) (xy 391.822178 -163.778438)
			(xy 387.392164 -163.778438) (xy 387.388862 -163.778946) (xy 387.34183 -163.784701) (xy 387.247267 -163.790842)
			(xy 387.152505 -163.790842) (xy 387.057942 -163.784701) (xy 387.01091 -163.778946) (xy 387.007608 -163.778438)
			(xy 362.849922 -163.778438) (xy 362.839859 -163.778876) (xy 362.821279 -163.786615) (xy 362.813854 -163.793424)
			(xy 362.332016 -164.275262) (xy 362.325178 -164.282663) (xy 362.317463 -164.301262) (xy 362.31703 -164.31133)
			(xy 362.31703 -167.684408) (xy 365.513862 -167.684408) (xy 365.513862 -167.57578) (xy 365.521791 -167.467442)
			(xy 365.537608 -167.359971) (xy 365.561227 -167.253942) (xy 365.592523 -167.14992) (xy 365.631328 -167.048459)
			(xy 365.677436 -166.950102) (xy 365.7306 -166.855373) (xy 365.790538 -166.764778) (xy 365.856928 -166.678799)
			(xy 365.929418 -166.597896) (xy 366.007619 -166.5225) (xy 366.091116 -166.453014) (xy 366.179462 -166.389807)
			(xy 366.272186 -166.333219) (xy 366.368794 -166.283549) (xy 366.468769 -166.241064) (xy 366.571579 -166.205991)
			(xy 366.676675 -166.178515) (xy 366.783496 -166.158784) (xy 366.891472 -166.146903) (xy 367.000028 -166.142936)
			(xy 367.108584 -166.146903) (xy 367.21656 -166.158784) (xy 367.323381 -166.178515) (xy 367.428477 -166.205991)
			(xy 367.531287 -166.241064) (xy 367.631262 -166.283549) (xy 367.72787 -166.333219) (xy 367.820594 -166.389807)
			(xy 367.90894 -166.453014) (xy 367.992437 -166.5225) (xy 368.070638 -166.597896) (xy 368.143128 -166.678799)
			(xy 368.209518 -166.764778) (xy 368.269456 -166.855373) (xy 368.32262 -166.950102) (xy 368.368728 -167.048459)
			(xy 368.407533 -167.14992) (xy 368.438829 -167.253942) (xy 368.462448 -167.359971) (xy 368.478265 -167.467442)
			(xy 368.486194 -167.57578) (xy 368.48669 -167.630094) (xy 368.486194 -167.684408) (xy 368.478265 -167.792746)
			(xy 368.462448 -167.900217) (xy 368.438829 -168.006246) (xy 368.407533 -168.110268) (xy 368.368728 -168.211729)
			(xy 368.32262 -168.310086) (xy 368.269456 -168.404815) (xy 368.209518 -168.49541) (xy 368.143128 -168.581389)
			(xy 368.070638 -168.662292) (xy 367.992437 -168.737688) (xy 367.90894 -168.807174) (xy 367.820594 -168.870381)
			(xy 367.72787 -168.926969) (xy 367.631262 -168.976639) (xy 367.531287 -169.019124) (xy 367.428477 -169.054197)
			(xy 367.323381 -169.081673) (xy 367.21656 -169.101404) (xy 367.108584 -169.113285) (xy 367.000028 -169.117252)
			(xy 366.891472 -169.113285) (xy 366.783496 -169.101404) (xy 366.676675 -169.081673) (xy 366.571579 -169.054197)
			(xy 366.468769 -169.019124) (xy 366.368794 -168.976639) (xy 366.272186 -168.926969) (xy 366.179462 -168.870381)
			(xy 366.091116 -168.807174) (xy 366.007619 -168.737688) (xy 365.929418 -168.662292) (xy 365.856928 -168.581389)
			(xy 365.790538 -168.49541) (xy 365.7306 -168.404815) (xy 365.677436 -168.310086) (xy 365.631328 -168.211729)
			(xy 365.592523 -168.110268) (xy 365.561227 -168.006246) (xy 365.537608 -167.900217) (xy 365.521791 -167.792746)
			(xy 365.513862 -167.684408) (xy 362.31703 -167.684408) (xy 362.31703 -169.02557) (xy 362.317467 -169.035634)
			(xy 362.325202 -169.054217) (xy 362.332016 -169.061638) (xy 363.128052 -169.857674) (xy 363.135452 -169.864515)
			(xy 363.154051 -169.872234) (xy 363.16412 -169.87266)
		)
		(stroke
			(width 0)
			(type solid)
		)
		(fill yes)
		(layer "In2.Cu")
		(net "GND")
	)
	(gr_poly
		(pts
			(xy 77.314298 -170.113198) (xy 77.324368 -170.112775) (xy 77.342973 -170.105061) (xy 77.350366 -170.098212)
			(xy 77.64018 -169.808398) (xy 77.647028 -169.801) (xy 77.654765 -169.782402) (xy 77.655166 -169.77233)
			(xy 77.655166 -164.344096) (xy 77.654741 -164.334027) (xy 77.647022 -164.315427) (xy 77.64018 -164.308028)
			(xy 77.286358 -163.954206) (xy 77.278957 -163.947365) (xy 77.260359 -163.939645) (xy 77.25029 -163.93922)
			(xy 48.277018 -163.93922) (xy 48.266968 -163.938714) (xy 48.248408 -163.930991) (xy 48.24095 -163.924234)
			(xy 46.27245 -161.955734) (xy 46.265608 -161.948334) (xy 46.25789 -161.929736) (xy 46.257464 -161.919666)
			(xy 46.257464 -152.206198) (xy 46.25704 -152.196129) (xy 46.249321 -152.177528) (xy 46.242478 -152.17013)
			(xy 45.903896 -151.831548) (xy 45.8965 -151.824697) (xy 45.877901 -151.816956) (xy 45.867828 -151.816562)
			(xy 39.319962 -151.816562) (xy 39.309896 -151.816994) (xy 39.291308 -151.824725) (xy 39.283894 -151.831548)
			(xy 38.834314 -152.281128) (xy 38.82747 -152.288527) (xy 38.819744 -152.307126) (xy 38.819328 -152.317196)
			(xy 38.819328 -167.684408) (xy 65.513954 -167.684408) (xy 65.513954 -167.57578) (xy 65.521883 -167.467442)
			(xy 65.5377 -167.359971) (xy 65.561319 -167.253942) (xy 65.592615 -167.14992) (xy 65.63142 -167.048459)
			(xy 65.677528 -166.950102) (xy 65.730692 -166.855373) (xy 65.79063 -166.764778) (xy 65.85702 -166.678799)
			(xy 65.92951 -166.597896) (xy 66.007711 -166.5225) (xy 66.091208 -166.453014) (xy 66.179554 -166.389807)
			(xy 66.272278 -166.333219) (xy 66.368886 -166.283549) (xy 66.468861 -166.241064) (xy 66.571671 -166.205991)
			(xy 66.676767 -166.178515) (xy 66.783588 -166.158784) (xy 66.891564 -166.146903) (xy 67.00012 -166.142936)
			(xy 67.108676 -166.146903) (xy 67.216652 -166.158784) (xy 67.323473 -166.178515) (xy 67.428569 -166.205991)
			(xy 67.531379 -166.241064) (xy 67.631354 -166.283549) (xy 67.727962 -166.333219) (xy 67.820686 -166.389807)
			(xy 67.909032 -166.453014) (xy 67.992529 -166.5225) (xy 68.07073 -166.597896) (xy 68.14322 -166.678799)
			(xy 68.20961 -166.764778) (xy 68.269548 -166.855373) (xy 68.322712 -166.950102) (xy 68.36882 -167.048459)
			(xy 68.407625 -167.14992) (xy 68.438921 -167.253942) (xy 68.46254 -167.359971) (xy 68.478357 -167.467442)
			(xy 68.486286 -167.57578) (xy 68.486782 -167.630094) (xy 68.486286 -167.684408) (xy 68.478357 -167.792746)
			(xy 68.46254 -167.900217) (xy 68.438921 -168.006246) (xy 68.407625 -168.110268) (xy 68.36882 -168.211729)
			(xy 68.322712 -168.310086) (xy 68.269548 -168.404815) (xy 68.20961 -168.49541) (xy 68.14322 -168.581389)
			(xy 68.07073 -168.662292) (xy 67.992529 -168.737688) (xy 67.909032 -168.807174) (xy 67.820686 -168.870381)
			(xy 67.727962 -168.926969) (xy 67.631354 -168.976639) (xy 67.531379 -169.019124) (xy 67.428569 -169.054197)
			(xy 67.323473 -169.081673) (xy 67.216652 -169.101404) (xy 67.108676 -169.113285) (xy 67.00012 -169.117252)
			(xy 66.891564 -169.113285) (xy 66.783588 -169.101404) (xy 66.676767 -169.081673) (xy 66.571671 -169.054197)
			(xy 66.468861 -169.019124) (xy 66.368886 -168.976639) (xy 66.272278 -168.926969) (xy 66.179554 -168.870381)
			(xy 66.091208 -168.807174) (xy 66.007711 -168.737688) (xy 65.92951 -168.662292) (xy 65.85702 -168.581389)
			(xy 65.79063 -168.49541) (xy 65.730692 -168.404815) (xy 65.677528 -168.310086) (xy 65.63142 -168.211729)
			(xy 65.592615 -168.110268) (xy 65.561319 -168.006246) (xy 65.5377 -167.900217) (xy 65.521883 -167.792746)
			(xy 65.513954 -167.684408) (xy 38.819328 -167.684408) (xy 38.819328 -169.581576) (xy 38.819766 -169.591639)
			(xy 38.827503 -169.610221) (xy 38.834314 -169.617644) (xy 39.299896 -170.083226) (xy 39.307291 -170.090081)
			(xy 39.325889 -170.097829) (xy 39.335964 -170.098212) (xy 48.668432 -170.098212) (xy 48.678499 -170.098641)
			(xy 48.697094 -170.106365) (xy 48.7045 -170.113198)
		)
		(stroke
			(width 0)
			(type solid)
		)
		(fill yes)
		(layer "In2.Cu")
		(net "GND")
	)
	(gr_poly
		(pts
			(arc
				(start 460.896208 -109.093)
				(mid 460.915731 -109.089099)
				(end 460.932276 -109.078014)
			)
			(arc
				(start 467.560914 -102.449376)
				(mid 467.572025 -102.432842)
				(end 467.5759 -102.413308)
			)
			(arc
				(start 467.5759 -90.889582)
				(mid 467.579801 -90.870059)
				(end 467.590886 -90.853514)
			)
			(xy 469.504014 -88.940386) (xy 469.511634 -88.917526)
			(arc
				(start 469.509856 -88.905588)
				(mid 469.49861 -88.803119)
				(end 469.49487 -88.700102)
			)
			(arc
				(start 469.49487 -88.700102)
				(mid 469.636547 -88.084111)
				(end 470.033096 -87.5919)
			)
			(xy 470.04224 -87.584534) (xy 470.0524 -87.563706) (xy 470.0524 -87.296498) (xy 470.04224 -87.27567)
			(arc
				(start 470.033096 -87.268304)
				(mid 469.862528 -87.109692)
				(end 469.720422 -86.92515)
			)
			(xy 469.71331 -86.913974) (xy 469.690958 -86.901782) (xy 469.579198 -86.901782) (xy 469.556846 -86.913974)
			(arc
				(start 469.549734 -86.92515)
				(mid 469.03955 -87.398567)
				(end 468.365078 -87.57031)
			)
			(arc
				(start 468.365078 -87.57031)
				(mid 467.36791 -87.15727)
				(end 466.95487 -86.160102)
			)
			(arc
				(start 466.95487 -86.160102)
				(mid 467.308272 -85.226374)
				(end 468.191342 -84.760562)
			)
			(arc
				(start 468.191342 -84.760562)
				(mid 468.221068 -84.746092)
				(end 468.235538 -84.716366)
			)
			(arc
				(start 468.235538 -84.716366)
				(mid 468.440541 -84.14045)
				(end 468.87003 -83.705446)
			)
			(xy 468.881206 -83.698334) (xy 468.893398 -83.675982) (xy 468.893398 -83.564222) (xy 468.881206 -83.54187)
			(arc
				(start 468.87003 -83.534758)
				(mid 468.534167 -83.231409)
				(end 468.311738 -82.837274)
			)
			(arc
				(start 468.311738 -82.837274)
				(mid 468.293106 -82.813093)
				(end 468.263986 -82.804)
			)
			(arc
				(start 459.786482 -82.804)
				(mid 459.766959 -82.807901)
				(end 459.750414 -82.818986)
			)
			(arc
				(start 456.986386 -85.583014)
				(mid 456.975275 -85.599548)
				(end 456.9714 -85.619082)
			)
			(arc
				(start 456.9714 -95.67672)
				(mid 456.967499 -95.696243)
				(end 456.956414 -95.712788)
			)
			(arc
				(start 455.407014 -97.262188)
				(mid 455.39048 -97.273299)
				(end 455.370946 -97.277174)
			)
			(arc
				(start 452.156068 -97.277174)
				(mid 452.136545 -97.281075)
				(end 452.12 -97.29216)
			)
			(arc
				(start 451.231762 -98.180398)
				(mid 451.220651 -98.196932)
				(end 451.216776 -98.216466)
			)
			(arc
				(start 451.216776 -108.605066)
				(mid 451.220677 -108.624589)
				(end 451.231762 -108.641134)
			)
			(arc
				(start 451.668642 -109.078014)
				(mid 451.685176 -109.089125)
				(end 451.70471 -109.093)
			)
		)
		(stroke
			(width 0)
			(type solid)
		)
		(fill yes)
		(layer "In2.Cu")
		(net "P12V_HPDB")
	)
	(gr_poly
		(pts
			(xy 29.601414 -155.435808) (xy 29.611483 -155.435383) (xy 29.630085 -155.427666) (xy 29.637482 -155.420822)
			(xy 31.015178 -154.043126) (xy 31.022015 -154.035724) (xy 31.029726 -154.017126) (xy 31.030164 -154.007058)
			(xy 31.030164 -39.205408) (xy 31.030587 -39.195339) (xy 31.038307 -39.176738) (xy 31.04515 -39.16934)
			(xy 41.12387 -29.09062) (xy 41.131271 -29.083783) (xy 41.14987 -29.07607) (xy 41.159938 -29.075634)
			(xy 41.23055 -29.075634) (xy 41.240615 -29.0752) (xy 41.2592 -29.067465) (xy 41.266618 -29.060648)
			(xy 44.541948 -25.785318) (xy 44.545758 -25.774904) (xy 44.549281 -25.765712) (xy 44.557157 -25.747667)
			(xy 44.561506 -25.738836) (xy 44.567348 -25.726898) (xy 44.566078 -25.700736) (xy 44.5135 -25.616154)
			(xy 44.508665 -25.608997) (xy 44.495222 -25.59817) (xy 44.47895 -25.592411) (xy 44.47032 -25.592024)
			(xy 40.429942 -25.592024) (xy 40.419952 -25.592554) (xy 40.401511 -25.60026) (xy 40.394128 -25.60701)
			(xy 40.202358 -25.79878) (xy 40.1955 -25.810718) (xy 40.193722 -25.817576) (xy 40.186508 -25.844828)
			(xy 40.165148 -25.896997) (xy 40.136337 -25.945451) (xy 40.100702 -25.989132) (xy 40.059022 -26.027088)
			(xy 40.012205 -26.05849) (xy 39.961274 -26.082653) (xy 39.907339 -26.09905) (xy 39.851577 -26.107323)
			(xy 39.82339 -26.107898) (xy 39.79614 -26.107411) (xy 39.742193 -26.099653) (xy 39.689901 -26.084297)
			(xy 39.640325 -26.061655) (xy 39.594477 -26.032189) (xy 39.553289 -25.996497) (xy 39.517599 -25.955307)
			(xy 39.488135 -25.909457) (xy 39.465496 -25.859881) (xy 39.450142 -25.807587) (xy 39.442388 -25.753641)
			(xy 39.441882 -25.72639) (xy 39.442396 -25.698207) (xy 39.450708 -25.642456) (xy 39.467134 -25.588536)
			(xy 39.491317 -25.537621) (xy 39.52273 -25.490819) (xy 39.560689 -25.449149) (xy 39.604366 -25.41352)
			(xy 39.652812 -25.384708) (xy 39.704971 -25.363338) (xy 39.732204 -25.356058) (xy 39.739062 -25.35428)
			(xy 39.751 -25.347422) (xy 40.041068 -25.057608) (xy 40.04767 -25.051039) (xy 40.061524 -25.038587)
			(xy 40.068754 -25.032716) (xy 40.079676 -25.02408) (xy 40.103122 -25.006405) (xy 40.155063 -24.97904)
			(xy 40.211129 -24.961626) (xy 40.240204 -24.957532) (xy 40.253158 -24.956008) (xy 40.26246 -24.955015)
			(xy 40.281141 -24.953996) (xy 40.290496 -24.953976) (xy 45.8724 -24.953976) (xy 45.89747 -24.954442)
			(xy 45.946993 -24.962288) (xy 45.994678 -24.977787) (xy 46.039351 -25.000556) (xy 46.07991 -25.030035)
			(xy 46.097952 -25.047448) (xy 46.424342 -25.373584) (xy 46.431742 -25.380426) (xy 46.45034 -25.388147)
			(xy 46.46041 -25.38857) (xy 73.570592 -25.38857) (xy 73.580662 -25.388148) (xy 73.599266 -25.380432)
			(xy 73.60666 -25.373584) (xy 78.597252 -20.383246) (xy 78.615316 -20.365846) (xy 78.655861 -20.336329)
			(xy 78.700524 -20.313515) (xy 78.748204 -20.297966) (xy 78.797729 -20.290062) (xy 78.822804 -20.28952)
			(xy 85.989414 -20.28952) (xy 85.999381 -20.289044) (xy 86.017821 -20.281472) (xy 86.025228 -20.274788)
			(xy 86.06663 -20.233386) (xy 86.073447 -20.226021) (xy 86.081171 -20.207513) (xy 86.081205 -20.187459)
			(xy 86.077806 -20.178014) (xy 86.07171 -20.163536) (xy 86.04631 -20.146772) (xy 83.688174 -20.146772)
			(xy 83.663094 -20.146286) (xy 83.613558 -20.138395) (xy 83.565869 -20.122843) (xy 83.521204 -20.100015)
			(xy 83.480666 -20.070472) (xy 83.462622 -20.053046) (xy 82.690716 -19.281394) (xy 82.67954 -19.277584)
			(xy 82.655514 -19.268828) (xy 82.609861 -19.245792) (xy 82.567688 -19.216872) (xy 82.529749 -19.182585)
			(xy 82.496724 -19.143543) (xy 82.469202 -19.100445) (xy 82.458052 -19.077432) (xy 82.452718 -19.066256)
			(xy 82.43316 -19.051016) (xy 82.338672 -19.034252) (xy 82.326481 -19.03289) (xy 82.303149 -19.040337)
			(xy 82.293968 -19.048476) (xy 82.199988 -19.142202) (xy 82.181927 -19.159607) (xy 82.141383 -19.189133)
			(xy 82.096722 -19.211957) (xy 82.049041 -19.227515) (xy 81.999513 -19.235426) (xy 81.974436 -19.235928)
			(xy 81.877662 -19.235928) (xy 81.864454 -19.239484) (xy 81.858358 -19.24304) (xy 81.835941 -19.256105)
			(xy 81.788323 -19.276714) (xy 81.738349 -19.290668) (xy 81.686943 -19.29771) (xy 81.661 -19.298158)
			(xy 81.633745 -19.297672) (xy 81.57979 -19.289915) (xy 81.527489 -19.274557) (xy 81.477905 -19.251913)
			(xy 81.432049 -19.222443) (xy 81.390853 -19.186747) (xy 81.355157 -19.145551) (xy 81.325687 -19.099695)
			(xy 81.303043 -19.050111) (xy 81.287685 -18.99781) (xy 81.279928 -18.943855) (xy 81.279928 -18.889345)
			(xy 81.287685 -18.83539) (xy 81.303043 -18.783089) (xy 81.325687 -18.733505) (xy 81.355157 -18.687649)
			(xy 81.390853 -18.646453) (xy 81.432049 -18.610757) (xy 81.477905 -18.581287) (xy 81.527489 -18.558643)
			(xy 81.57979 -18.543285) (xy 81.633745 -18.535528) (xy 81.661 -18.535142) (xy 81.688675 -18.535636)
			(xy 81.743444 -18.54364) (xy 81.796479 -18.55948) (xy 81.821782 -18.570702) (xy 81.836514 -18.57756)
			(xy 81.867756 -18.571972) (xy 82.530442 -17.909286) (xy 82.537258 -17.90192) (xy 82.544979 -17.883413)
			(xy 82.545014 -17.86336) (xy 82.541618 -17.853914) (xy 82.535522 -17.839436) (xy 82.510376 -17.822672)
			(xy 81.964022 -17.822672) (xy 81.95406 -17.823159) (xy 81.935636 -17.830747) (xy 81.928208 -17.837404)
			(xy 80.905604 -18.860008) (xy 80.897984 -18.880328) (xy 80.898746 -18.891504) (xy 80.899508 -18.91665)
			(xy 80.899022 -18.943901) (xy 80.891266 -18.997849) (xy 80.875911 -19.050144) (xy 80.853269 -19.099721)
			(xy 80.823803 -19.145571) (xy 80.788112 -19.186762) (xy 80.746921 -19.222453) (xy 80.701071 -19.251919)
			(xy 80.651494 -19.274561) (xy 80.599199 -19.289916) (xy 80.545251 -19.297672) (xy 80.490749 -19.297672)
			(xy 80.436801 -19.289916) (xy 80.384506 -19.274561) (xy 80.334929 -19.251919) (xy 80.289079 -19.222453)
			(xy 80.247888 -19.186762) (xy 80.212197 -19.145571) (xy 80.182731 -19.099721) (xy 80.160089 -19.050144)
			(xy 80.144734 -18.997849) (xy 80.136978 -18.943901) (xy 80.136492 -18.91665) (xy 80.13692 -18.89114)
			(xy 80.14372 -18.840574) (xy 80.157192 -18.791364) (xy 80.177096 -18.744386) (xy 80.203078 -18.700476)
			(xy 80.218534 -18.680176) (xy 80.225392 -18.669) (xy 80.237978 -18.641817) (xy 80.271734 -18.592341)
			(xy 80.292448 -18.570702) (xy 81.485232 -17.377664) (xy 81.493039 -17.369051) (xy 81.500589 -17.34709)
			(xy 81.49971 -17.3355) (xy 81.48828 -17.24406) (xy 81.47558 -17.224756) (xy 81.46542 -17.21866) (xy 81.463642 -17.21739)
			(xy 81.457587 -17.213955) (xy 81.444184 -17.210214) (xy 81.437226 -17.210024) (xy 80.264254 -17.210024)
			(xy 80.239185 -17.209554) (xy 80.189666 -17.201702) (xy 80.141985 -17.186198) (xy 80.097318 -17.163425)
			(xy 80.056764 -17.133943) (xy 80.038702 -17.116552) (xy 79.657448 -16.735298) (xy 79.640042 -16.71725)
			(xy 79.610558 -16.676696) (xy 79.587789 -16.632025) (xy 79.572299 -16.584339) (xy 79.564469 -16.534816)
			(xy 79.563976 -16.509746) (xy 79.563976 -15.139162) (xy 79.563431 -15.129178) (xy 79.555705 -15.110758)
			(xy 79.54899 -15.103348) (xy 75.110848 -10.665206) (xy 75.103447 -10.658367) (xy 75.084849 -10.650651)
			(xy 75.07478 -10.65022) (xy 74.143108 -10.65022) (xy 74.133037 -10.649799) (xy 74.114428 -10.642089)
			(xy 74.10704 -10.635234) (xy 68.084954 -4.613148) (xy 68.07811 -4.605749) (xy 68.070386 -4.58715)
			(xy 68.069968 -4.57708) (xy 68.069968 -2.583434) (xy 68.069532 -2.57337) (xy 68.061797 -2.554786)
			(xy 68.054982 -2.547366) (xy 67.56273 -2.055114) (xy 67.554167 -2.047368) (xy 67.53235 -2.039881)
			(xy 67.509455 -2.042689) (xy 67.499484 -2.04851) (xy 67.400678 -2.11201) (xy 67.389502 -2.145792)
			(xy 67.395852 -2.16281) (xy 67.414504 -2.214111) (xy 67.443599 -2.319328) (xy 67.463136 -2.426732)
			(xy 67.472955 -2.535455) (xy 67.473576 -2.590038) (xy 67.473084 -2.638925) (xy 67.465216 -2.736382)
			(xy 67.449532 -2.83289) (xy 67.426133 -2.927823) (xy 67.395171 -3.020565) (xy 67.356847 -3.110516)
			(xy 67.311409 -3.19709) (xy 67.259152 -3.279728) (xy 67.200415 -3.357893) (xy 67.135579 -3.431078)
			(xy 67.065064 -3.498808) (xy 66.989328 -3.560645) (xy 66.908861 -3.616187) (xy 66.824186 -3.665074)
			(xy 66.735852 -3.706989) (xy 66.644432 -3.74166) (xy 66.550518 -3.768863) (xy 66.45472 -3.78842)
			(xy 66.357659 -3.800206) (xy 66.259964 -3.804143) (xy 66.162269 -3.800206) (xy 66.065208 -3.78842)
			(xy 65.96941 -3.768863) (xy 65.875496 -3.74166) (xy 65.784076 -3.706989) (xy 65.695742 -3.665074)
			(xy 65.611067 -3.616187) (xy 65.5306 -3.560645) (xy 65.454864 -3.498808) (xy 65.384349 -3.431078)
			(xy 65.319513 -3.357893) (xy 65.260776 -3.279728) (xy 65.208519 -3.19709) (xy 65.163081 -3.110516)
			(xy 65.124757 -3.020565) (xy 65.093795 -2.927823) (xy 65.070396 -2.83289) (xy 65.054712 -2.736382)
			(xy 65.046844 -2.638925) (xy 65.046352 -2.590038) (xy 65.046879 -2.538956) (xy 65.055466 -2.437153)
			(xy 65.072584 -2.336433) (xy 65.09811 -2.23751) (xy 65.131864 -2.141083) (xy 65.173607 -2.047835)
			(xy 65.223043 -1.958428) (xy 65.279822 -1.873495) (xy 65.343541 -1.793637) (xy 65.41375 -1.71942)
			(xy 65.489951 -1.651369) (xy 65.530476 -1.620266) (xy 65.543684 -1.61036) (xy 65.553336 -1.579118)
			(xy 65.517522 -1.472184) (xy 65.513661 -1.46226) (xy 65.499359 -1.446517) (xy 65.479898 -1.437935)
			(xy 65.469262 -1.437386) (xy 64.510666 -1.437386) (xy 64.500035 -1.437934) (xy 64.480591 -1.44654)
			(xy 64.466283 -1.46227) (xy 64.462406 -1.472184) (xy 64.426592 -1.579118) (xy 64.436244 -1.61036)
			(xy 64.449452 -1.620266) (xy 64.48996 -1.651389) (xy 64.566158 -1.719439) (xy 64.636364 -1.793656)
			(xy 64.70008 -1.873512) (xy 64.756857 -1.958444) (xy 64.806291 -2.047849) (xy 64.848031 -2.141094)
			(xy 64.881784 -2.237519) (xy 64.907309 -2.33644) (xy 64.924426 -2.437157) (xy 64.933013 -2.538957)
			(xy 64.933576 -2.590038) (xy 64.933056 -2.64021) (xy 64.924767 -2.740212) (xy 64.908247 -2.839188)
			(xy 64.883611 -2.936461) (xy 64.851026 -3.031368) (xy 64.810716 -3.12326) (xy 64.762954 -3.211509)
			(xy 64.708068 -3.295513) (xy 64.646433 -3.374697) (xy 64.578469 -3.448521) (xy 64.504641 -3.51648)
			(xy 64.425453 -3.578111) (xy 64.341446 -3.632992) (xy 64.253194 -3.680748) (xy 64.161299 -3.721053)
			(xy 64.06639 -3.753632) (xy 63.969115 -3.778263) (xy 63.870139 -3.794776) (xy 63.770136 -3.803059)
			(xy 63.719964 -3.80365) (xy 63.667937 -3.803103) (xy 63.564265 -3.794202) (xy 63.461737 -3.77645)
			(xy 63.361107 -3.74998) (xy 63.263115 -3.714984) (xy 63.168482 -3.671721) (xy 63.077904 -3.620509)
			(xy 63.034672 -3.59156) (xy 63.022226 -3.583178) (xy 62.992 -3.582416) (xy 62.887352 -3.647948) (xy 62.874652 -3.67538)
			(xy 62.876938 -3.690366) (xy 62.884976 -3.748364) (xy 62.894099 -3.865108) (xy 62.895235 -3.982203)
			(xy 62.888381 -4.099103) (xy 62.873569 -4.215262) (xy 62.850866 -4.330141) (xy 62.82038 -4.443203)
			(xy 62.782252 -4.553922) (xy 62.736659 -4.661782) (xy 62.683815 -4.766281) (xy 62.623965 -4.866931)
			(xy 62.557388 -4.963264) (xy 62.484395 -5.054831) (xy 62.405325 -5.141204) (xy 62.320547 -5.221983)
			(xy 62.230456 -5.29679) (xy 62.135471 -5.365277) (xy 62.036036 -5.427124) (xy 61.932613 -5.482045)
			(xy 61.825685 -5.529781) (xy 61.715749 -5.570113) (xy 61.603318 -5.60285) (xy 61.488916 -5.627842)
			(xy 61.373075 -5.64497) (xy 61.256336 -5.654157) (xy 61.139242 -5.655358) (xy 61.022338 -5.648569)
			(xy 60.90617 -5.63382) (xy 60.791279 -5.611181) (xy 60.6782 -5.580757) (xy 60.56746 -5.54269) (xy 60.459575 -5.497156)
			(xy 60.355047 -5.44437) (xy 60.254364 -5.384575) (xy 60.157995 -5.318051) (xy 60.066388 -5.245108)
			(xy 59.979971 -5.166086) (xy 59.899145 -5.081353) (xy 59.824289 -4.991303) (xy 59.75575 -4.896356)
			(xy 59.693847 -4.796955) (xy 59.63887 -4.693563) (xy 59.591074 -4.58666) (xy 59.550683 -4.476747)
			(xy 59.517883 -4.364334) (xy 59.492829 -4.249945) (xy 59.475636 -4.134114) (xy 59.466385 -4.01738)
			(xy 59.46512 -3.900286) (xy 59.471845 -3.783379) (xy 59.486529 -3.667203) (xy 59.509105 -3.5523)
			(xy 59.539467 -3.439204) (xy 59.577473 -3.328443) (xy 59.622947 -3.220533) (xy 59.675676 -3.115976)
			(xy 59.735415 -3.01526) (xy 59.801886 -2.918854) (xy 59.874778 -2.827207) (xy 59.953753 -2.740746)
			(xy 60.038442 -2.659874) (xy 60.128451 -2.584968) (xy 60.223359 -2.516376) (xy 60.322727 -2.454419)
			(xy 60.426089 -2.399385) (xy 60.532964 -2.351531) (xy 60.642856 -2.311078) (xy 60.755251 -2.278217)
			(xy 60.869625 -2.253099) (xy 60.985447 -2.235843) (xy 61.102176 -2.226528) (xy 61.219269 -2.225198)
			(xy 61.33618 -2.231858) (xy 61.452364 -2.246479) (xy 61.56728 -2.268992) (xy 61.680392 -2.299291)
			(xy 61.791174 -2.337236) (xy 61.899109 -2.382651) (xy 62.003695 -2.435322) (xy 62.104444 -2.495006)
			(xy 62.200887 -2.561423) (xy 62.292574 -2.634265) (xy 62.336172 -2.67335) (xy 62.347602 -2.68351)
			(xy 62.37732 -2.688336) (xy 62.490096 -2.638298) (xy 62.506352 -2.612898) (xy 62.506352 -2.597658)
			(xy 62.506352 -2.590038) (xy 62.506879 -2.538956) (xy 62.515466 -2.437153) (xy 62.532584 -2.336433)
			(xy 62.55811 -2.23751) (xy 62.591864 -2.141083) (xy 62.633607 -2.047835) (xy 62.683043 -1.958428)
			(xy 62.739822 -1.873495) (xy 62.803541 -1.793637) (xy 62.87375 -1.71942) (xy 62.949951 -1.651369)
			(xy 62.990476 -1.620266) (xy 63.003684 -1.61036) (xy 63.013336 -1.579118) (xy 62.977522 -1.472184)
			(xy 62.973661 -1.46226) (xy 62.959359 -1.446517) (xy 62.939898 -1.437935) (xy 62.929262 -1.437386)
			(xy 4.084574 -1.437386) (xy 4.074506 -1.437813) (xy 4.055907 -1.445533) (xy 4.048506 -1.452372) (xy 1.710944 -3.789934)
			(xy 1.704098 -3.797332) (xy 1.696369 -3.815931) (xy 1.695958 -3.826002) (xy 1.695958 -20.63857) (xy 56.730635 -20.63857)
			(xy 56.730635 -20.50943) (xy 56.738585 -20.380535) (xy 56.754455 -20.252375) (xy 56.778184 -20.125434)
			(xy 56.809683 -20.000195) (xy 56.848832 -19.877132) (xy 56.895483 -19.756713) (xy 56.949458 -19.639394)
			(xy 57.010553 -19.52562) (xy 57.078536 -19.415823) (xy 57.15315 -19.31042) (xy 57.234111 -19.20981)
			(xy 57.321111 -19.114375) (xy 57.413822 -19.024476) (xy 57.511892 -18.940455) (xy 57.614947 -18.862631)
			(xy 57.722598 -18.791299) (xy 57.834437 -18.726729) (xy 57.950038 -18.669167) (xy 58.068963 -18.61883)
			(xy 58.190762 -18.57591) (xy 58.314972 -18.540569) (xy 58.441121 -18.512942) (xy 58.568733 -18.493133)
			(xy 58.697322 -18.481217) (xy 58.8264 -18.477241) (xy 58.955478 -18.481217) (xy 59.084067 -18.493133)
			(xy 59.211679 -18.512942) (xy 59.337828 -18.540569) (xy 59.462038 -18.57591) (xy 59.583837 -18.61883)
			(xy 59.702762 -18.669167) (xy 59.818363 -18.726729) (xy 59.930202 -18.791299) (xy 60.037853 -18.862631)
			(xy 60.140908 -18.940455) (xy 60.238978 -19.024476) (xy 60.331689 -19.114375) (xy 60.418689 -19.20981)
			(xy 60.49965 -19.31042) (xy 60.574264 -19.415823) (xy 60.642247 -19.52562) (xy 60.703342 -19.639394)
			(xy 60.757317 -19.756713) (xy 60.803968 -19.877132) (xy 60.843117 -20.000195) (xy 60.874616 -20.125434)
			(xy 60.898345 -20.252375) (xy 60.914215 -20.380535) (xy 60.922165 -20.50943) (xy 60.922662 -20.574)
			(xy 60.922165 -20.63857) (xy 60.914215 -20.767465) (xy 60.898345 -20.895625) (xy 60.874616 -21.022566)
			(xy 60.843117 -21.147805) (xy 60.803968 -21.270868) (xy 60.757317 -21.391287) (xy 60.703342 -21.508606)
			(xy 60.642247 -21.62238) (xy 60.574264 -21.732177) (xy 60.49965 -21.83758) (xy 60.418689 -21.93819)
			(xy 60.331689 -22.033625) (xy 60.238978 -22.123524) (xy 60.140908 -22.207545) (xy 60.037853 -22.285369)
			(xy 59.930202 -22.356701) (xy 59.818363 -22.421271) (xy 59.702762 -22.478833) (xy 59.583837 -22.52917)
			(xy 59.462038 -22.57209) (xy 59.337828 -22.607431) (xy 59.211679 -22.635058) (xy 59.084067 -22.654867)
			(xy 58.955478 -22.666783) (xy 58.8264 -22.67076) (xy 58.697322 -22.666783) (xy 58.568733 -22.654867)
			(xy 58.441121 -22.635058) (xy 58.314972 -22.607431) (xy 58.190762 -22.57209) (xy 58.068963 -22.52917)
			(xy 57.950038 -22.478833) (xy 57.834437 -22.421271) (xy 57.722598 -22.356701) (xy 57.614947 -22.285369)
			(xy 57.511892 -22.207545) (xy 57.413822 -22.123524) (xy 57.321111 -22.033625) (xy 57.234111 -21.93819)
			(xy 57.15315 -21.83758) (xy 57.078536 -21.732177) (xy 57.010553 -21.62238) (xy 56.949458 -21.508606)
			(xy 56.895483 -21.391287) (xy 56.848832 -21.270868) (xy 56.809683 -21.147805) (xy 56.778184 -21.022566)
			(xy 56.754455 -20.895625) (xy 56.738585 -20.767465) (xy 56.730635 -20.63857) (xy 1.695958 -20.63857)
			(xy 1.695958 -34.036) (xy 33.806382 -34.036) (xy 33.810453 -33.980378) (xy 33.822579 -33.925941)
			(xy 33.842502 -33.87385) (xy 33.869798 -33.825215) (xy 33.903884 -33.781072) (xy 33.944033 -33.742363)
			(xy 33.989391 -33.709912) (xy 34.038991 -33.684411) (xy 34.091775 -33.666404) (xy 34.146618 -33.656274)
			(xy 34.202352 -33.654237) (xy 34.257789 -33.660337) (xy 34.311746 -33.674443) (xy 34.363075 -33.696255)
			(xy 34.410681 -33.725309) (xy 34.453549 -33.760984) (xy 34.490766 -33.802521) (xy 34.521539 -33.849034)
			(xy 34.545211 -33.899531) (xy 34.561279 -33.952938) (xy 34.569399 -34.008114) (xy 34.569908 -34.036)
			(xy 34.569399 -34.063886) (xy 34.561279 -34.119062) (xy 34.545211 -34.172469) (xy 34.521539 -34.222966)
			(xy 34.490766 -34.269479) (xy 34.453549 -34.311016) (xy 34.410681 -34.346691) (xy 34.363075 -34.375745)
			(xy 34.311746 -34.397557) (xy 34.257789 -34.411663) (xy 34.202352 -34.417763) (xy 34.146618 -34.415726)
			(xy 34.091775 -34.405596) (xy 34.038991 -34.387589) (xy 33.989391 -34.362088) (xy 33.944033 -34.329637)
			(xy 33.903884 -34.290928) (xy 33.869798 -34.246785) (xy 33.842502 -34.19815) (xy 33.822579 -34.146059)
			(xy 33.810453 -34.091622) (xy 33.806382 -34.036) (xy 1.695958 -34.036) (xy 1.695958 -60.099956) (xy 12.484104 -60.099956)
			(xy 12.488134 -59.957621) (xy 12.500209 -59.815741) (xy 12.520292 -59.674773) (xy 12.548319 -59.535166)
			(xy 12.584199 -59.397368) (xy 12.627817 -59.261821) (xy 12.679034 -59.128959) (xy 12.737685 -58.999207)
			(xy 12.803583 -58.872981) (xy 12.876517 -58.750685) (xy 12.956254 -58.632712) (xy 13.042536 -58.519439)
			(xy 13.135089 -58.411228) (xy 13.233616 -58.308427) (xy 13.337801 -58.211365) (xy 13.44731 -58.120353)
			(xy 13.561793 -58.035681) (xy 13.680883 -57.957623) (xy 13.804198 -57.886427) (xy 13.931344 -57.822321)
			(xy 14.061913 -57.765512) (xy 14.195487 -57.71618) (xy 14.331638 -57.674484) (xy 14.469929 -57.640558)
			(xy 14.609919 -57.61451) (xy 14.751158 -57.596424) (xy 14.893194 -57.586357) (xy 15.035572 -57.584342)
			(xy 15.177836 -57.590385) (xy 15.31953 -57.604467) (xy 15.4602 -57.626543) (xy 15.599397 -57.656543)
			(xy 15.736673 -57.694369) (xy 15.871589 -57.739901) (xy 16.003713 -57.792992) (xy 16.132622 -57.853474)
			(xy 16.257903 -57.921152) (xy 16.379154 -57.995809) (xy 16.495987 -58.077207) (xy 16.608028 -58.165084)
			(xy 16.714918 -58.259159) (xy 16.816315 -58.359131) (xy 16.911893 -58.464679) (xy 17.001347 -58.575465)
			(xy 17.084389 -58.691134) (xy 17.160755 -58.811317) (xy 17.230199 -58.935627) (xy 17.292499 -59.063668)
			(xy 17.347455 -59.195027) (xy 17.394892 -59.329286) (xy 17.434656 -59.466013) (xy 17.466622 -59.604771)
			(xy 17.490687 -59.745115) (xy 17.506773 -59.886596) (xy 17.514828 -60.02876) (xy 17.515332 -60.099956)
			(xy 17.514828 -60.171152) (xy 17.506773 -60.313316) (xy 17.490687 -60.454797) (xy 17.466622 -60.595141)
			(xy 17.434656 -60.733899) (xy 17.394892 -60.870626) (xy 17.347455 -61.004885) (xy 17.292499 -61.136244)
			(xy 17.230199 -61.264285) (xy 17.160755 -61.388595) (xy 17.084389 -61.508778) (xy 17.001347 -61.624447)
			(xy 16.911893 -61.735233) (xy 16.816315 -61.840781) (xy 16.714918 -61.940753) (xy 16.608028 -62.034828)
			(xy 16.495987 -62.122705) (xy 16.379154 -62.204103) (xy 16.257903 -62.27876) (xy 16.132622 -62.346438)
			(xy 16.003713 -62.40692) (xy 15.871589 -62.460011) (xy 15.736673 -62.505543) (xy 15.599397 -62.543369)
			(xy 15.4602 -62.573369) (xy 15.31953 -62.595445) (xy 15.177836 -62.609527) (xy 15.035572 -62.61557)
			(xy 14.893194 -62.613555) (xy 14.751158 -62.603488) (xy 14.609919 -62.585402) (xy 14.469929 -62.559354)
			(xy 14.331638 -62.525428) (xy 14.195487 -62.483732) (xy 14.061913 -62.4344) (xy 13.931344 -62.377591)
			(xy 13.804198 -62.313485) (xy 13.680883 -62.242289) (xy 13.561793 -62.164231) (xy 13.44731 -62.079559)
			(xy 13.337801 -61.988547) (xy 13.233616 -61.891485) (xy 13.135089 -61.788684) (xy 13.042536 -61.680473)
			(xy 12.956254 -61.5672) (xy 12.876517 -61.449227) (xy 12.803583 -61.326931) (xy 12.737685 -61.200705)
			(xy 12.679034 -61.070953) (xy 12.627817 -60.938091) (xy 12.584199 -60.802544) (xy 12.548319 -60.664746)
			(xy 12.520292 -60.525139) (xy 12.500209 -60.384171) (xy 12.488134 -60.242291) (xy 12.484104 -60.099956)
			(xy 1.695958 -60.099956) (xy 1.695958 -104.544876) (xy 12.484104 -104.544876) (xy 12.488134 -104.402541)
			(xy 12.500209 -104.260661) (xy 12.520292 -104.119693) (xy 12.548319 -103.980086) (xy 12.584199 -103.842288)
			(xy 12.627817 -103.706741) (xy 12.679034 -103.573879) (xy 12.737685 -103.444127) (xy 12.803583 -103.317901)
			(xy 12.876517 -103.195605) (xy 12.956254 -103.077632) (xy 13.042536 -102.964359) (xy 13.135089 -102.856148)
			(xy 13.233616 -102.753347) (xy 13.337801 -102.656285) (xy 13.44731 -102.565273) (xy 13.561793 -102.480601)
			(xy 13.680883 -102.402543) (xy 13.804198 -102.331347) (xy 13.931344 -102.267241) (xy 14.061913 -102.210432)
			(xy 14.195487 -102.1611) (xy 14.331638 -102.119404) (xy 14.469929 -102.085478) (xy 14.609919 -102.05943)
			(xy 14.751158 -102.041344) (xy 14.893194 -102.031277) (xy 15.035572 -102.029262) (xy 15.177836 -102.035305)
			(xy 15.31953 -102.049387) (xy 15.4602 -102.071463) (xy 15.599397 -102.101463) (xy 15.736673 -102.139289)
			(xy 15.871589 -102.184821) (xy 16.003713 -102.237912) (xy 16.132622 -102.298394) (xy 16.257903 -102.366072)
			(xy 16.379154 -102.440729) (xy 16.495987 -102.522127) (xy 16.608028 -102.610004) (xy 16.714918 -102.704079)
			(xy 16.816315 -102.804051) (xy 16.911893 -102.909599) (xy 17.001347 -103.020385) (xy 17.084389 -103.136054)
			(xy 17.160755 -103.256237) (xy 17.230199 -103.380547) (xy 17.292499 -103.508588) (xy 17.347455 -103.639947)
			(xy 17.394892 -103.774206) (xy 17.434656 -103.910933) (xy 17.466622 -104.049691) (xy 17.490687 -104.190035)
			(xy 17.506773 -104.331516) (xy 17.514828 -104.47368) (xy 17.515332 -104.544876) (xy 17.514828 -104.616072)
			(xy 17.506773 -104.758236) (xy 17.490687 -104.899717) (xy 17.466622 -105.040061) (xy 17.434656 -105.178819)
			(xy 17.394892 -105.315546) (xy 17.347455 -105.449805) (xy 17.292499 -105.581164) (xy 17.230199 -105.709205)
			(xy 17.160755 -105.833515) (xy 17.084389 -105.953698) (xy 17.001347 -106.069367) (xy 16.911893 -106.180153)
			(xy 16.816315 -106.285701) (xy 16.714918 -106.385673) (xy 16.608028 -106.479748) (xy 16.495987 -106.567625)
			(xy 16.379154 -106.649023) (xy 16.257903 -106.72368) (xy 16.132622 -106.791358) (xy 16.003713 -106.85184)
			(xy 15.871589 -106.904931) (xy 15.736673 -106.950463) (xy 15.599397 -106.988289) (xy 15.4602 -107.018289)
			(xy 15.31953 -107.040365) (xy 15.177836 -107.054447) (xy 15.035572 -107.06049) (xy 14.893194 -107.058475)
			(xy 14.751158 -107.048408) (xy 14.609919 -107.030322) (xy 14.469929 -107.004274) (xy 14.331638 -106.970348)
			(xy 14.195487 -106.928652) (xy 14.061913 -106.87932) (xy 13.931344 -106.822511) (xy 13.804198 -106.758405)
			(xy 13.680883 -106.687209) (xy 13.561793 -106.609151) (xy 13.44731 -106.524479) (xy 13.337801 -106.433467)
			(xy 13.233616 -106.336405) (xy 13.135089 -106.233604) (xy 13.042536 -106.125393) (xy 12.956254 -106.01212)
			(xy 12.876517 -105.894147) (xy 12.803583 -105.771851) (xy 12.737685 -105.645625) (xy 12.679034 -105.515873)
			(xy 12.627817 -105.383011) (xy 12.584199 -105.247464) (xy 12.548319 -105.109666) (xy 12.520292 -104.970059)
			(xy 12.500209 -104.829091) (xy 12.488134 -104.687211) (xy 12.484104 -104.544876) (xy 1.695958 -104.544876)
			(xy 1.695958 -154.473148) (xy 1.696391 -154.483213) (xy 1.704125 -154.501799) (xy 1.710944 -154.509216)
			(xy 2.62255 -155.420822) (xy 2.629947 -155.427669) (xy 2.648547 -155.435398) (xy 2.658618 -155.435808)
		)
		(stroke
			(width 0)
			(type solid)
		)
		(fill yes)
		(layer "In2.Cu")
		(net "GND")
	)
	(gr_poly
		(pts
			(xy 336.368898 -77.000354) (xy 355.413818 -77.000354) (xy 372.639082 -59.775344) (xy 398.229836 -59.775344)
			(xy 406.794462 -51.210718) (xy 406.8013 -51.203317) (xy 406.80901 -51.184718) (xy 406.809448 -51.17465)
			(xy 406.809448 -45.885354) (xy 406.805638 -45.872146) (xy 406.802082 -45.86605) (xy 406.798575 -45.859945)
			(xy 406.7947 -45.846416) (xy 406.794462 -45.83938) (xy 406.794462 -43.214544) (xy 406.794028 -43.204479)
			(xy 406.786295 -43.185893) (xy 406.779476 -43.178476) (xy 405.017986 -41.416986) (xy 405.011132 -41.409591)
			(xy 405.00339 -41.390992) (xy 405.003 -41.380918) (xy 405.003 -39.358824) (xy 405.002563 -39.34876)
			(xy 404.994829 -39.330176) (xy 404.988014 -39.322756) (xy 404.917148 -39.25189) (xy 404.909751 -39.245042)
			(xy 404.891152 -39.237312) (xy 404.88108 -39.236904) (xy 403.745192 -39.236904) (xy 403.735122 -39.236479)
			(xy 403.71652 -39.228763) (xy 403.709124 -39.221918) (xy 403.1107 -38.623494) (xy 403.103854 -38.616095)
			(xy 403.096122 -38.597497) (xy 403.095714 -38.587426) (xy 403.095714 -32.696912) (xy 403.095294 -32.68684)
			(xy 403.087584 -32.668231) (xy 403.080728 -32.660844) (xy 402.934932 -32.515048) (xy 402.927532 -32.508207)
			(xy 402.908933 -32.50049) (xy 402.898864 -32.500062) (xy 392.466576 -32.500062) (xy 392.456509 -32.500491)
			(xy 392.437917 -32.508219) (xy 392.430508 -32.515048) (xy 392.149838 -32.795718) (xy 392.14244 -32.802563)
			(xy 392.123841 -32.810288) (xy 392.11377 -32.810704) (xy 367.491772 -32.810704) (xy 367.481704 -32.810276)
			(xy 367.463107 -32.802555) (xy 367.455704 -32.795718) (xy 355.549454 -20.889468) (xy 355.546406 -20.886674)
			(xy 354.344732 -19.685) (xy 328.682096 -19.685) (xy 328.5744 -19.792696) (xy 328.5744 -28.566548)
			(xy 334.47888 -28.566548) (xy 334.47888 -28.481852) (xy 334.486931 -28.397538) (xy 334.50296 -28.314372)
			(xy 334.526821 -28.233105) (xy 334.5583 -28.154475) (xy 334.597111 -28.079194) (xy 334.642901 -28.007942)
			(xy 334.695257 -27.941366) (xy 334.753705 -27.880068) (xy 334.817715 -27.824603) (xy 334.886707 -27.775474)
			(xy 334.960057 -27.733125) (xy 335.0371 -27.697941) (xy 335.117139 -27.670239) (xy 335.199448 -27.650271)
			(xy 335.283283 -27.638218) (xy 335.367884 -27.634188) (xy 335.452485 -27.638218) (xy 335.53632 -27.650271)
			(xy 335.618629 -27.670239) (xy 335.698668 -27.697941) (xy 335.775711 -27.733125) (xy 335.849061 -27.775474)
			(xy 335.918053 -27.824603) (xy 335.982063 -27.880068) (xy 336.040511 -27.941366) (xy 336.092867 -28.007942)
			(xy 336.138657 -28.079194) (xy 336.177468 -28.154475) (xy 336.208947 -28.233105) (xy 336.232808 -28.314372)
			(xy 336.248837 -28.397538) (xy 336.256888 -28.481852) (xy 336.257392 -28.5242) (xy 336.256888 -28.566548)
			(xy 336.248837 -28.650862) (xy 336.232808 -28.734028) (xy 336.208947 -28.815295) (xy 336.177468 -28.893925)
			(xy 336.138657 -28.969206) (xy 336.092867 -29.040458) (xy 336.040511 -29.107034) (xy 335.982063 -29.168332)
			(xy 335.918053 -29.223797) (xy 335.849061 -29.272926) (xy 335.775711 -29.315275) (xy 335.698668 -29.350459)
			(xy 335.618629 -29.378161) (xy 335.53632 -29.398129) (xy 335.452485 -29.410182) (xy 335.367884 -29.414213)
			(xy 335.283283 -29.410182) (xy 335.199448 -29.398129) (xy 335.117139 -29.378161) (xy 335.0371 -29.350459)
			(xy 334.960057 -29.315275) (xy 334.886707 -29.272926) (xy 334.817715 -29.223797) (xy 334.753705 -29.168332)
			(xy 334.695257 -29.107034) (xy 334.642901 -29.040458) (xy 334.597111 -28.969206) (xy 334.5583 -28.893925)
			(xy 334.526821 -28.815295) (xy 334.50296 -28.734028) (xy 334.486931 -28.650862) (xy 334.47888 -28.566548)
			(xy 328.5744 -28.566548) (xy 328.5744 -36.611814) (xy 338.249006 -36.611814) (xy 338.280145 -36.581995)
			(xy 338.347266 -36.527874) (xy 338.419309 -36.480504) (xy 338.4956 -36.44033) (xy 338.575422 -36.40773)
			(xy 338.658024 -36.38301) (xy 338.742631 -36.366402) (xy 338.828449 -36.358061) (xy 338.87156 -36.35756)
			(xy 338.913912 -36.358046) (xy 338.998233 -36.366094) (xy 339.081407 -36.382121) (xy 339.16268 -36.405982)
			(xy 339.241318 -36.437461) (xy 339.316607 -36.476272) (xy 339.387866 -36.522064) (xy 339.454449 -36.574423)
			(xy 339.515753 -36.632874) (xy 339.571224 -36.696888) (xy 339.620358 -36.765885) (xy 339.662711 -36.83924)
			(xy 339.6979 -36.916289) (xy 339.725604 -36.996334) (xy 339.745575 -37.07865) (xy 339.75763 -37.162492)
			(xy 339.76166 -37.2471) (xy 339.75763 -37.331708) (xy 339.745575 -37.41555) (xy 339.725604 -37.497866)
			(xy 339.6979 -37.577911) (xy 339.662711 -37.65496) (xy 339.620358 -37.728315) (xy 339.571224 -37.797312)
			(xy 339.515753 -37.861326) (xy 339.454449 -37.919777) (xy 339.387866 -37.972136) (xy 339.316607 -38.017928)
			(xy 339.241318 -38.056739) (xy 339.16268 -38.088218) (xy 339.081407 -38.112079) (xy 338.998233 -38.128106)
			(xy 338.913912 -38.136154) (xy 338.87156 -38.136576) (xy 338.82845 -38.136066) (xy 338.742635 -38.127718)
			(xy 338.65803 -38.111105) (xy 338.57543 -38.086383) (xy 338.495611 -38.053783) (xy 338.41932 -38.013612)
			(xy 338.347276 -37.966247) (xy 338.280153 -37.912132) (xy 338.249006 -37.882322) (xy 337.141312 -37.882322)
			(xy 337.157968 -37.923327) (xy 337.184015 -38.007917) (xy 337.201531 -38.094676) (xy 337.210343 -38.182745)
			(xy 337.210908 -38.227) (xy 337.210433 -38.268102) (xy 337.202848 -38.349957) (xy 337.187743 -38.430762)
			(xy 337.165247 -38.509829) (xy 337.135551 -38.586483) (xy 337.098909 -38.66007) (xy 337.055634 -38.729962)
			(xy 337.006094 -38.795563) (xy 336.950713 -38.856313) (xy 336.889963 -38.911694) (xy 336.824362 -38.961234)
			(xy 336.75447 -39.004509) (xy 336.680883 -39.041151) (xy 336.604229 -39.070847) (xy 336.525162 -39.093343)
			(xy 336.444357 -39.108448) (xy 336.362502 -39.116033) (xy 336.3214 -39.116508) (xy 336.320384 -39.116508)
			(xy 336.28402 -39.116125) (xy 336.211539 -39.110152) (xy 336.175604 -39.10457) (xy 336.160575 -39.102626)
			(xy 336.130552 -39.106628) (xy 336.103024 -39.119262) (xy 336.080415 -39.139416) (xy 336.064715 -39.165318)
			(xy 336.057305 -39.194686) (xy 336.058838 -39.224935) (xy 336.06918 -39.253404) (xy 336.077814 -39.26586)
			(xy 336.102195 -39.298942) (xy 336.145451 -39.368823) (xy 336.182077 -39.442397) (xy 336.211759 -39.519035)
			(xy 336.234246 -39.598085) (xy 336.249344 -39.678872) (xy 336.256925 -39.760707) (xy 336.257392 -39.8018)
			(xy 336.256909 -39.843724) (xy 336.249018 -39.927201) (xy 336.233306 -40.009565) (xy 336.209913 -40.090084)
			(xy 336.179046 -40.168045) (xy 336.14098 -40.242755) (xy 336.096052 -40.313551) (xy 336.04466 -40.379805)
			(xy 335.987262 -40.440928) (xy 335.924366 -40.496378) (xy 335.856531 -40.545664) (xy 335.784359 -40.588347)
			(xy 335.708491 -40.624048) (xy 335.629599 -40.652451) (xy 335.548385 -40.673304) (xy 335.491284 -40.682348)
			(xy 343.306396 -40.682348) (xy 343.306396 -40.597652) (xy 343.314447 -40.513338) (xy 343.330476 -40.430172)
			(xy 343.354337 -40.348905) (xy 343.385816 -40.270275) (xy 343.424627 -40.194994) (xy 343.470417 -40.123742)
			(xy 343.522773 -40.057166) (xy 343.581221 -39.995868) (xy 343.645231 -39.940403) (xy 343.714223 -39.891274)
			(xy 343.787573 -39.848925) (xy 343.864616 -39.813741) (xy 343.944655 -39.786039) (xy 344.026964 -39.766071)
			(xy 344.110799 -39.754018) (xy 344.1954 -39.749988) (xy 344.280001 -39.754018) (xy 344.363836 -39.766071)
			(xy 344.446145 -39.786039) (xy 344.526184 -39.813741) (xy 344.603227 -39.848925) (xy 344.676577 -39.891274)
			(xy 344.745569 -39.940403) (xy 344.809579 -39.995868) (xy 344.868027 -40.057166) (xy 344.920383 -40.123742)
			(xy 344.966173 -40.194994) (xy 345.004984 -40.270275) (xy 345.036463 -40.348905) (xy 345.060324 -40.430172)
			(xy 345.076353 -40.513338) (xy 345.084404 -40.597652) (xy 345.084908 -40.64) (xy 345.084404 -40.682348)
			(xy 345.076353 -40.766662) (xy 345.060324 -40.849828) (xy 345.036463 -40.931095) (xy 345.004984 -41.009725)
			(xy 344.966173 -41.085006) (xy 344.920383 -41.156258) (xy 344.868027 -41.222834) (xy 344.809579 -41.284132)
			(xy 344.745569 -41.339597) (xy 344.676577 -41.388726) (xy 344.603227 -41.431075) (xy 344.526184 -41.466259)
			(xy 344.446145 -41.493961) (xy 344.363836 -41.513929) (xy 344.280001 -41.525982) (xy 344.1954 -41.530013)
			(xy 344.110799 -41.525982) (xy 344.026964 -41.513929) (xy 343.944655 -41.493961) (xy 343.864616 -41.466259)
			(xy 343.787573 -41.431075) (xy 343.714223 -41.388726) (xy 343.645231 -41.339597) (xy 343.581221 -41.284132)
			(xy 343.522773 -41.222834) (xy 343.470417 -41.156258) (xy 343.424627 -41.085006) (xy 343.385816 -41.009725)
			(xy 343.354337 -40.931095) (xy 343.330476 -40.849828) (xy 343.314447 -40.766662) (xy 343.306396 -40.682348)
			(xy 335.491284 -40.682348) (xy 335.465568 -40.686421) (xy 335.381885 -40.691687) (xy 335.298077 -40.689053)
			(xy 335.21489 -40.678545) (xy 335.13306 -40.660254) (xy 335.053315 -40.634344) (xy 334.976362 -40.601044)
			(xy 334.902884 -40.560651) (xy 334.833534 -40.513521) (xy 334.768927 -40.460074) (xy 334.709636 -40.400785)
			(xy 334.656189 -40.336179) (xy 334.609058 -40.266829) (xy 334.568663 -40.193353) (xy 334.535361 -40.1164)
			(xy 334.50945 -40.036656) (xy 334.491158 -39.954826) (xy 334.480648 -39.871639) (xy 334.478013 -39.787831)
			(xy 334.483277 -39.704148) (xy 334.496393 -39.621331) (xy 334.517244 -39.540116) (xy 334.545646 -39.461224)
			(xy 334.581346 -39.385355) (xy 334.624027 -39.313182) (xy 334.673312 -39.245346) (xy 334.728761 -39.18245)
			(xy 334.789883 -39.12505) (xy 334.856136 -39.073658) (xy 334.926931 -39.028728) (xy 335.00164 -38.99066)
			(xy 335.079601 -38.959792) (xy 335.16012 -38.936398) (xy 335.242483 -38.920685) (xy 335.32596 -38.912792)
			(xy 335.367884 -38.912292) (xy 335.3689 -38.912292) (xy 335.405263 -38.912678) (xy 335.477744 -38.918659)
			(xy 335.51368 -38.92423) (xy 335.528711 -38.926176) (xy 335.558738 -38.922178) (xy 335.586271 -38.909545)
			(xy 335.608884 -38.889389) (xy 335.624587 -38.863485) (xy 335.631998 -38.834113) (xy 335.630463 -38.803859)
			(xy 335.620119 -38.775388) (xy 335.61147 -38.76294) (xy 335.58709 -38.729858) (xy 335.543834 -38.659976)
			(xy 335.507209 -38.586403) (xy 335.477527 -38.509764) (xy 335.455041 -38.430715) (xy 335.439943 -38.349928)
			(xy 335.432362 -38.268093) (xy 335.431892 -38.227) (xy 335.432454 -38.182746) (xy 335.441273 -38.094677)
			(xy 335.458795 -38.00792) (xy 335.484845 -37.923332) (xy 335.501488 -37.882322) (xy 328.5744 -37.882322)
			(xy 328.5744 -47.788322) (xy 337.87588 -47.788322) (xy 337.907019 -47.758502) (xy 337.974138 -47.704378)
			(xy 338.046182 -47.657006) (xy 338.122472 -47.61683) (xy 338.202294 -47.584227) (xy 338.284896 -47.559504)
			(xy 338.369504 -47.542893) (xy 338.455323 -47.53455) (xy 338.498434 -47.534068) (xy 338.540783 -47.534573)
			(xy 338.625096 -47.542627) (xy 338.708262 -47.558659) (xy 338.789528 -47.582524) (xy 338.868157 -47.614005)
			(xy 338.943438 -47.652817) (xy 339.014689 -47.69861) (xy 339.081264 -47.750967) (xy 339.142561 -47.809416)
			(xy 339.198025 -47.873427) (xy 339.247153 -47.94242) (xy 339.289501 -48.015771) (xy 339.324684 -48.092815)
			(xy 339.352386 -48.172854) (xy 339.372353 -48.255164) (xy 339.384407 -48.338999) (xy 339.388437 -48.4236)
			(xy 339.384407 -48.508201) (xy 339.372353 -48.592036) (xy 339.352386 -48.674346) (xy 339.324684 -48.754385)
			(xy 339.289501 -48.831429) (xy 339.247153 -48.90478) (xy 339.198025 -48.973773) (xy 339.142561 -49.037784)
			(xy 339.081264 -49.096233) (xy 339.014689 -49.14859) (xy 338.943438 -49.194383) (xy 338.868157 -49.233195)
			(xy 338.789528 -49.264676) (xy 338.708262 -49.288541) (xy 338.625096 -49.304573) (xy 338.540783 -49.312627)
			(xy 338.498434 -49.313084) (xy 338.455324 -49.312573) (xy 338.36951 -49.304223) (xy 338.284907 -49.287608)
			(xy 338.202309 -49.262884) (xy 338.12249 -49.230282) (xy 338.046202 -49.19011) (xy 337.974159 -49.142744)
			(xy 337.907037 -49.088629) (xy 337.87588 -49.05883) (xy 337.091274 -49.05883) (xy 337.110385 -49.092681)
			(xy 337.143304 -49.163111) (xy 337.169953 -49.236144) (xy 337.190128 -49.311224) (xy 337.203677 -49.387777)
			(xy 337.210495 -49.465221) (xy 337.210908 -49.504092) (xy 337.210908 -49.5046) (xy 337.210433 -49.545702)
			(xy 337.202848 -49.627557) (xy 337.187743 -49.708362) (xy 337.165247 -49.787429) (xy 337.135551 -49.864083)
			(xy 337.098909 -49.93767) (xy 337.055634 -50.007562) (xy 337.006094 -50.073163) (xy 336.950713 -50.133913)
			(xy 336.889963 -50.189294) (xy 336.824362 -50.238834) (xy 336.75447 -50.282109) (xy 336.680883 -50.318751)
			(xy 336.604229 -50.348447) (xy 336.525162 -50.370943) (xy 336.444357 -50.386048) (xy 336.362502 -50.393633)
			(xy 336.3214 -50.394108) (xy 336.320384 -50.394108) (xy 336.28402 -50.393725) (xy 336.211539 -50.387752)
			(xy 336.175604 -50.38217) (xy 336.160575 -50.380226) (xy 336.130552 -50.384228) (xy 336.103024 -50.396862)
			(xy 336.080415 -50.417016) (xy 336.064715 -50.442918) (xy 336.057305 -50.472286) (xy 336.058838 -50.502535)
			(xy 336.06918 -50.531004) (xy 336.077814 -50.54346) (xy 336.102195 -50.576542) (xy 336.145451 -50.646423)
			(xy 336.182077 -50.719997) (xy 336.211759 -50.796635) (xy 336.234246 -50.875685) (xy 336.242507 -50.919888)
			(xy 376.553995 -50.919888) (xy 376.55797 -50.809847) (xy 376.569876 -50.70038) (xy 376.589649 -50.592057)
			(xy 376.617187 -50.485443) (xy 376.652346 -50.381095) (xy 376.694943 -50.279555) (xy 376.744756 -50.181354)
			(xy 376.801525 -50.087003) (xy 376.864954 -49.996994) (xy 376.934713 -49.911797) (xy 377.010437 -49.831856)
			(xy 377.091733 -49.757587) (xy 377.178175 -49.689378) (xy 377.269314 -49.627584) (xy 377.364675 -49.572528)
			(xy 377.463759 -49.524496) (xy 377.566052 -49.483739) (xy 377.671018 -49.450469) (xy 377.778111 -49.424861)
			(xy 377.886774 -49.407047) (xy 377.996438 -49.39712) (xy 378.106533 -49.395132) (xy 378.216484 -49.401093)
			(xy 378.325718 -49.414973) (xy 378.433667 -49.436698) (xy 378.539766 -49.466157) (xy 378.643463 -49.503194)
			(xy 378.744217 -49.547617) (xy 378.841503 -49.599195) (xy 378.934813 -49.657658) (xy 379.023662 -49.722702)
			(xy 379.107586 -49.793987) (xy 379.186147 -49.871143) (xy 379.258936 -49.953766) (xy 379.325573 -50.041426)
			(xy 379.385711 -50.133666) (xy 379.439037 -50.230005) (xy 379.485272 -50.32994) (xy 379.524176 -50.432952)
			(xy 379.555545 -50.538502) (xy 379.579216 -50.64604) (xy 379.595065 -50.755006) (xy 379.603011 -50.864832)
			(xy 379.603508 -50.919888) (xy 396.111995 -50.919888) (xy 396.11597 -50.809847) (xy 396.127876 -50.70038)
			(xy 396.147649 -50.592057) (xy 396.175187 -50.485443) (xy 396.210346 -50.381095) (xy 396.252943 -50.279555)
			(xy 396.302756 -50.181354) (xy 396.359525 -50.087003) (xy 396.422954 -49.996994) (xy 396.492713 -49.911797)
			(xy 396.568437 -49.831856) (xy 396.649733 -49.757587) (xy 396.736175 -49.689378) (xy 396.827314 -49.627584)
			(xy 396.922675 -49.572528) (xy 397.021759 -49.524496) (xy 397.124052 -49.483739) (xy 397.229018 -49.450469)
			(xy 397.336111 -49.424861) (xy 397.444774 -49.407047) (xy 397.554438 -49.39712) (xy 397.664533 -49.395132)
			(xy 397.774484 -49.401093) (xy 397.883718 -49.414973) (xy 397.991667 -49.436698) (xy 398.097766 -49.466157)
			(xy 398.201463 -49.503194) (xy 398.302217 -49.547617) (xy 398.399503 -49.599195) (xy 398.492813 -49.657658)
			(xy 398.581662 -49.722702) (xy 398.665586 -49.793987) (xy 398.744147 -49.871143) (xy 398.816936 -49.953766)
			(xy 398.883573 -50.041426) (xy 398.943711 -50.133666) (xy 398.997037 -50.230005) (xy 399.043272 -50.32994)
			(xy 399.082176 -50.432952) (xy 399.113545 -50.538502) (xy 399.137216 -50.64604) (xy 399.153065 -50.755006)
			(xy 399.161011 -50.864832) (xy 399.161508 -50.919888) (xy 399.161011 -50.974944) (xy 399.153065 -51.08477)
			(xy 399.137216 -51.193736) (xy 399.113545 -51.301274) (xy 399.082176 -51.406824) (xy 399.043272 -51.509836)
			(xy 398.997037 -51.609771) (xy 398.943711 -51.70611) (xy 398.883573 -51.79835) (xy 398.816936 -51.88601)
			(xy 398.744147 -51.968633) (xy 398.665586 -52.045789) (xy 398.581662 -52.117074) (xy 398.492813 -52.182118)
			(xy 398.399503 -52.240581) (xy 398.302217 -52.292159) (xy 398.201463 -52.336582) (xy 398.097766 -52.373619)
			(xy 397.991667 -52.403078) (xy 397.883718 -52.424803) (xy 397.774484 -52.438683) (xy 397.664533 -52.444644)
			(xy 397.554438 -52.442656) (xy 397.444774 -52.432729) (xy 397.336111 -52.414915) (xy 397.229018 -52.389307)
			(xy 397.124052 -52.356037) (xy 397.021759 -52.31528) (xy 396.922675 -52.267248) (xy 396.827314 -52.212192)
			(xy 396.736175 -52.150398) (xy 396.649733 -52.082189) (xy 396.568437 -52.00792) (xy 396.492713 -51.927979)
			(xy 396.422954 -51.842782) (xy 396.359525 -51.752773) (xy 396.302756 -51.658422) (xy 396.252943 -51.560221)
			(xy 396.210346 -51.458681) (xy 396.175187 -51.354333) (xy 396.147649 -51.247719) (xy 396.127876 -51.139396)
			(xy 396.11597 -51.029929) (xy 396.111995 -50.919888) (xy 379.603508 -50.919888) (xy 379.603011 -50.974944)
			(xy 379.595065 -51.08477) (xy 379.579216 -51.193736) (xy 379.555545 -51.301274) (xy 379.524176 -51.406824)
			(xy 379.485272 -51.509836) (xy 379.439037 -51.609771) (xy 379.385711 -51.70611) (xy 379.325573 -51.79835)
			(xy 379.258936 -51.88601) (xy 379.186147 -51.968633) (xy 379.107586 -52.045789) (xy 379.023662 -52.117074)
			(xy 378.934813 -52.182118) (xy 378.841503 -52.240581) (xy 378.744217 -52.292159) (xy 378.643463 -52.336582)
			(xy 378.539766 -52.373619) (xy 378.433667 -52.403078) (xy 378.325718 -52.424803) (xy 378.216484 -52.438683)
			(xy 378.106533 -52.444644) (xy 377.996438 -52.442656) (xy 377.886774 -52.432729) (xy 377.778111 -52.414915)
			(xy 377.671018 -52.389307) (xy 377.566052 -52.356037) (xy 377.463759 -52.31528) (xy 377.364675 -52.267248)
			(xy 377.269314 -52.212192) (xy 377.178175 -52.150398) (xy 377.091733 -52.082189) (xy 377.010437 -52.00792)
			(xy 376.934713 -51.927979) (xy 376.864954 -51.842782) (xy 376.801525 -51.752773) (xy 376.744756 -51.658422)
			(xy 376.694943 -51.560221) (xy 376.652346 -51.458681) (xy 376.617187 -51.354333) (xy 376.589649 -51.247719)
			(xy 376.569876 -51.139396) (xy 376.55797 -51.029929) (xy 376.553995 -50.919888) (xy 336.242507 -50.919888)
			(xy 336.249344 -50.956472) (xy 336.256925 -51.038307) (xy 336.257392 -51.0794) (xy 336.256909 -51.121324)
			(xy 336.249018 -51.204801) (xy 336.233306 -51.287165) (xy 336.209913 -51.367684) (xy 336.179046 -51.445645)
			(xy 336.14098 -51.520355) (xy 336.096052 -51.591151) (xy 336.04466 -51.657405) (xy 335.987262 -51.718528)
			(xy 335.924366 -51.773978) (xy 335.856531 -51.823264) (xy 335.784359 -51.865947) (xy 335.708491 -51.901648)
			(xy 335.629599 -51.930051) (xy 335.548385 -51.950904) (xy 335.491284 -51.959948) (xy 343.280996 -51.959948)
			(xy 343.280996 -51.875252) (xy 343.289047 -51.790938) (xy 343.305076 -51.707772) (xy 343.328937 -51.626505)
			(xy 343.360416 -51.547875) (xy 343.399227 -51.472594) (xy 343.445017 -51.401342) (xy 343.497373 -51.334766)
			(xy 343.555821 -51.273468) (xy 343.619831 -51.218003) (xy 343.688823 -51.168874) (xy 343.762173 -51.126525)
			(xy 343.839216 -51.091341) (xy 343.919255 -51.063639) (xy 344.001564 -51.043671) (xy 344.085399 -51.031618)
			(xy 344.17 -51.027588) (xy 344.254601 -51.031618) (xy 344.338436 -51.043671) (xy 344.420745 -51.063639)
			(xy 344.500784 -51.091341) (xy 344.577827 -51.126525) (xy 344.651177 -51.168874) (xy 344.720169 -51.218003)
			(xy 344.784179 -51.273468) (xy 344.842627 -51.334766) (xy 344.894983 -51.401342) (xy 344.940773 -51.472594)
			(xy 344.979584 -51.547875) (xy 345.011063 -51.626505) (xy 345.034924 -51.707772) (xy 345.050953 -51.790938)
			(xy 345.059004 -51.875252) (xy 345.059508 -51.9176) (xy 345.059004 -51.959948) (xy 345.050953 -52.044262)
			(xy 345.034924 -52.127428) (xy 345.011063 -52.208695) (xy 344.979584 -52.287325) (xy 344.940773 -52.362606)
			(xy 344.894983 -52.433858) (xy 344.842627 -52.500434) (xy 344.784179 -52.561732) (xy 344.720169 -52.617197)
			(xy 344.651177 -52.666326) (xy 344.577827 -52.708675) (xy 344.500784 -52.743859) (xy 344.420745 -52.771561)
			(xy 344.338436 -52.791529) (xy 344.254601 -52.803582) (xy 344.17 -52.807613) (xy 344.085399 -52.803582)
			(xy 344.001564 -52.791529) (xy 343.919255 -52.771561) (xy 343.839216 -52.743859) (xy 343.762173 -52.708675)
			(xy 343.688823 -52.666326) (xy 343.619831 -52.617197) (xy 343.555821 -52.561732) (xy 343.497373 -52.500434)
			(xy 343.445017 -52.433858) (xy 343.399227 -52.362606) (xy 343.360416 -52.287325) (xy 343.328937 -52.208695)
			(xy 343.305076 -52.127428) (xy 343.289047 -52.044262) (xy 343.280996 -51.959948) (xy 335.491284 -51.959948)
			(xy 335.465568 -51.964021) (xy 335.381885 -51.969287) (xy 335.298077 -51.966653) (xy 335.21489 -51.956145)
			(xy 335.13306 -51.937854) (xy 335.053315 -51.911944) (xy 334.976362 -51.878644) (xy 334.902884 -51.838251)
			(xy 334.833534 -51.791121) (xy 334.768927 -51.737674) (xy 334.709636 -51.678385) (xy 334.656189 -51.613779)
			(xy 334.609058 -51.544429) (xy 334.568663 -51.470953) (xy 334.535361 -51.394) (xy 334.50945 -51.314256)
			(xy 334.491158 -51.232426) (xy 334.480648 -51.149239) (xy 334.478013 -51.065431) (xy 334.483277 -50.981748)
			(xy 334.496393 -50.898931) (xy 334.517244 -50.817716) (xy 334.545646 -50.738824) (xy 334.581346 -50.662955)
			(xy 334.624027 -50.590782) (xy 334.673312 -50.522946) (xy 334.728761 -50.46005) (xy 334.789883 -50.40265)
			(xy 334.856136 -50.351258) (xy 334.926931 -50.306328) (xy 335.00164 -50.26826) (xy 335.079601 -50.237392)
			(xy 335.16012 -50.213998) (xy 335.242483 -50.198285) (xy 335.32596 -50.190392) (xy 335.367884 -50.189892)
			(xy 335.3689 -50.189892) (xy 335.405263 -50.190278) (xy 335.477744 -50.196259) (xy 335.51368 -50.20183)
			(xy 335.528711 -50.203776) (xy 335.558738 -50.199778) (xy 335.586271 -50.187145) (xy 335.608884 -50.166989)
			(xy 335.624587 -50.141085) (xy 335.631998 -50.111713) (xy 335.630463 -50.081459) (xy 335.620119 -50.052988)
			(xy 335.61147 -50.04054) (xy 335.58709 -50.007458) (xy 335.543834 -49.937576) (xy 335.507209 -49.864003)
			(xy 335.477527 -49.787364) (xy 335.455041 -49.708315) (xy 335.439943 -49.627528) (xy 335.432362 -49.545693)
			(xy 335.431892 -49.5046) (xy 335.431892 -49.504092) (xy 335.432315 -49.46522) (xy 335.439121 -49.387775)
			(xy 335.452661 -49.31122) (xy 335.472834 -49.236139) (xy 335.499484 -49.163106) (xy 335.532409 -49.092679)
			(xy 335.551526 -49.05883) (xy 328.67854 -49.05883) (xy 328.5744 -49.16297) (xy 328.5744 -58.42) (xy 377.061994 -58.42)
			(xy 377.065974 -58.330117) (xy 377.077882 -58.240937) (xy 377.097625 -58.153159) (xy 377.125049 -58.067469)
			(xy 377.159938 -57.984538) (xy 377.202021 -57.905016) (xy 377.250967 -57.829523) (xy 377.306394 -57.758652)
			(xy 377.367867 -57.692957) (xy 377.434906 -57.632952) (xy 377.506986 -57.579107) (xy 377.583542 -57.531843)
			(xy 377.663977 -57.49153) (xy 377.747659 -57.458483) (xy 377.833934 -57.432962) (xy 377.922128 -57.415166)
			(xy 378.011549 -57.405233) (xy 378.101498 -57.403243) (xy 378.191271 -57.40921) (xy 378.280166 -57.423088)
			(xy 378.367486 -57.444768) (xy 378.452548 -57.474081) (xy 378.534687 -57.510797) (xy 378.613259 -57.554628)
			(xy 378.68765 -57.605232) (xy 378.757277 -57.662213) (xy 378.821596 -57.725125) (xy 378.880104 -57.793475)
			(xy 378.932341 -57.866728) (xy 378.9779 -57.944311) (xy 379.016424 -58.025618) (xy 379.047611 -58.110011)
			(xy 379.071218 -58.19683) (xy 379.087059 -58.285395) (xy 379.095011 -58.375014) (xy 379.095508 -58.42)
			(xy 396.619994 -58.42) (xy 396.623974 -58.330117) (xy 396.635882 -58.240937) (xy 396.655625 -58.153159)
			(xy 396.683049 -58.067469) (xy 396.717938 -57.984538) (xy 396.760021 -57.905016) (xy 396.808967 -57.829523)
			(xy 396.864394 -57.758652) (xy 396.925867 -57.692957) (xy 396.992906 -57.632952) (xy 397.064986 -57.579107)
			(xy 397.141542 -57.531843) (xy 397.221977 -57.49153) (xy 397.305659 -57.458483) (xy 397.391934 -57.432962)
			(xy 397.480128 -57.415166) (xy 397.569549 -57.405233) (xy 397.659498 -57.403243) (xy 397.749271 -57.40921)
			(xy 397.838166 -57.423088) (xy 397.925486 -57.444768) (xy 398.010548 -57.474081) (xy 398.092687 -57.510797)
			(xy 398.171259 -57.554628) (xy 398.24565 -57.605232) (xy 398.315277 -57.662213) (xy 398.379596 -57.725125)
			(xy 398.438104 -57.793475) (xy 398.490341 -57.866728) (xy 398.5359 -57.944311) (xy 398.574424 -58.025618)
			(xy 398.605611 -58.110011) (xy 398.629218 -58.19683) (xy 398.645059 -58.285395) (xy 398.653011 -58.375014)
			(xy 398.653508 -58.42) (xy 398.653011 -58.464986) (xy 398.645059 -58.554605) (xy 398.629218 -58.64317)
			(xy 398.605611 -58.729989) (xy 398.574424 -58.814382) (xy 398.5359 -58.895689) (xy 398.490341 -58.973272)
			(xy 398.438104 -59.046525) (xy 398.379596 -59.114875) (xy 398.315277 -59.177787) (xy 398.24565 -59.234768)
			(xy 398.171259 -59.285372) (xy 398.092687 -59.329203) (xy 398.010548 -59.365919) (xy 397.925486 -59.395232)
			(xy 397.838166 -59.416912) (xy 397.749271 -59.43079) (xy 397.659498 -59.436757) (xy 397.569549 -59.434767)
			(xy 397.480128 -59.424834) (xy 397.391934 -59.407038) (xy 397.305659 -59.381517) (xy 397.221977 -59.34847)
			(xy 397.141542 -59.308157) (xy 397.064986 -59.260893) (xy 396.992906 -59.207048) (xy 396.925867 -59.147043)
			(xy 396.864394 -59.081348) (xy 396.808967 -59.010477) (xy 396.760021 -58.934984) (xy 396.717938 -58.855462)
			(xy 396.683049 -58.772531) (xy 396.655625 -58.686841) (xy 396.635882 -58.599063) (xy 396.623974 -58.509883)
			(xy 396.619994 -58.42) (xy 379.095508 -58.42) (xy 379.095011 -58.464986) (xy 379.087059 -58.554605)
			(xy 379.071218 -58.64317) (xy 379.047611 -58.729989) (xy 379.016424 -58.814382) (xy 378.9779 -58.895689)
			(xy 378.932341 -58.973272) (xy 378.880104 -59.046525) (xy 378.821596 -59.114875) (xy 378.757277 -59.177787)
			(xy 378.68765 -59.234768) (xy 378.613259 -59.285372) (xy 378.534687 -59.329203) (xy 378.452548 -59.365919)
			(xy 378.367486 -59.395232) (xy 378.280166 -59.416912) (xy 378.191271 -59.43079) (xy 378.101498 -59.436757)
			(xy 378.011549 -59.434767) (xy 377.922128 -59.424834) (xy 377.833934 -59.407038) (xy 377.747659 -59.381517)
			(xy 377.663977 -59.34847) (xy 377.583542 -59.308157) (xy 377.506986 -59.260893) (xy 377.434906 -59.207048)
			(xy 377.367867 -59.147043) (xy 377.306394 -59.081348) (xy 377.250967 -59.010477) (xy 377.202021 -58.934984)
			(xy 377.159938 -58.855462) (xy 377.125049 -58.772531) (xy 377.097625 -58.686841) (xy 377.077882 -58.599063)
			(xy 377.065974 -58.509883) (xy 377.061994 -58.42) (xy 328.5744 -58.42) (xy 328.5744 -62.399348) (xy 334.47888 -62.399348)
			(xy 334.47888 -62.314652) (xy 334.486931 -62.230338) (xy 334.50296 -62.147172) (xy 334.526821 -62.065905)
			(xy 334.5583 -61.987275) (xy 334.597111 -61.911994) (xy 334.642901 -61.840742) (xy 334.695257 -61.774166)
			(xy 334.753705 -61.712868) (xy 334.817715 -61.657403) (xy 334.886707 -61.608274) (xy 334.960057 -61.565925)
			(xy 335.0371 -61.530741) (xy 335.117139 -61.503039) (xy 335.199448 -61.483071) (xy 335.283283 -61.471018)
			(xy 335.367884 -61.466988) (xy 335.452485 -61.471018) (xy 335.53632 -61.483071) (xy 335.618629 -61.503039)
			(xy 335.698668 -61.530741) (xy 335.775711 -61.565925) (xy 335.849061 -61.608274) (xy 335.918053 -61.657403)
			(xy 335.982063 -61.712868) (xy 336.040511 -61.774166) (xy 336.092867 -61.840742) (xy 336.138657 -61.911994)
			(xy 336.177468 -61.987275) (xy 336.208947 -62.065905) (xy 336.232808 -62.147172) (xy 336.248837 -62.230338)
			(xy 336.256888 -62.314652) (xy 336.257392 -62.357) (xy 336.256888 -62.399348) (xy 336.248837 -62.483662)
			(xy 336.232808 -62.566828) (xy 336.208947 -62.648095) (xy 336.177468 -62.726725) (xy 336.138657 -62.802006)
			(xy 336.092867 -62.873258) (xy 336.040511 -62.939834) (xy 335.982063 -63.001132) (xy 335.918053 -63.056597)
			(xy 335.849061 -63.105726) (xy 335.775711 -63.148075) (xy 335.698668 -63.183259) (xy 335.618629 -63.210961)
			(xy 335.53632 -63.230929) (xy 335.452485 -63.242982) (xy 335.367884 -63.247013) (xy 335.283283 -63.242982)
			(xy 335.199448 -63.230929) (xy 335.117139 -63.210961) (xy 335.0371 -63.183259) (xy 334.960057 -63.148075)
			(xy 334.886707 -63.105726) (xy 334.817715 -63.056597) (xy 334.753705 -63.001132) (xy 334.695257 -62.939834)
			(xy 334.642901 -62.873258) (xy 334.597111 -62.802006) (xy 334.5583 -62.726725) (xy 334.526821 -62.648095)
			(xy 334.50296 -62.566828) (xy 334.486931 -62.483662) (xy 334.47888 -62.399348) (xy 328.5744 -62.399348)
			(xy 328.5744 -73.676948) (xy 334.47888 -73.676948) (xy 334.47888 -73.592252) (xy 334.486931 -73.507938)
			(xy 334.50296 -73.424772) (xy 334.526821 -73.343505) (xy 334.5583 -73.264875) (xy 334.597111 -73.189594)
			(xy 334.642901 -73.118342) (xy 334.695257 -73.051766) (xy 334.753705 -72.990468) (xy 334.817715 -72.935003)
			(xy 334.886707 -72.885874) (xy 334.960057 -72.843525) (xy 335.0371 -72.808341) (xy 335.117139 -72.780639)
			(xy 335.199448 -72.760671) (xy 335.283283 -72.748618) (xy 335.367884 -72.744588) (xy 335.452485 -72.748618)
			(xy 335.53632 -72.760671) (xy 335.618629 -72.780639) (xy 335.698668 -72.808341) (xy 335.775711 -72.843525)
			(xy 335.849061 -72.885874) (xy 335.918053 -72.935003) (xy 335.982063 -72.990468) (xy 336.040511 -73.051766)
			(xy 336.092867 -73.118342) (xy 336.138657 -73.189594) (xy 336.177468 -73.264875) (xy 336.208947 -73.343505)
			(xy 336.232808 -73.424772) (xy 336.248837 -73.507938) (xy 336.256888 -73.592252) (xy 336.257392 -73.6346)
			(xy 336.256888 -73.676948) (xy 336.248837 -73.761262) (xy 336.232808 -73.844428) (xy 336.208947 -73.925695)
			(xy 336.177468 -74.004325) (xy 336.138657 -74.079606) (xy 336.092867 -74.150858) (xy 336.040511 -74.217434)
			(xy 335.982063 -74.278732) (xy 335.918053 -74.334197) (xy 335.849061 -74.383326) (xy 335.775711 -74.425675)
			(xy 335.698668 -74.460859) (xy 335.618629 -74.488561) (xy 335.53632 -74.508529) (xy 335.452485 -74.520582)
			(xy 335.367884 -74.524613) (xy 335.283283 -74.520582) (xy 335.199448 -74.508529) (xy 335.117139 -74.488561)
			(xy 335.0371 -74.460859) (xy 334.960057 -74.425675) (xy 334.886707 -74.383326) (xy 334.817715 -74.334197)
			(xy 334.753705 -74.278732) (xy 334.695257 -74.217434) (xy 334.642901 -74.150858) (xy 334.597111 -74.079606)
			(xy 334.5583 -74.004325) (xy 334.526821 -73.925695) (xy 334.50296 -73.844428) (xy 334.486931 -73.761262)
			(xy 334.47888 -73.676948) (xy 328.5744 -73.676948) (xy 328.5744 -79.629) (xy 328.740262 -79.794862)
			(xy 333.57439 -79.794862)
		)
		(stroke
			(width 0)
			(type solid)
		)
		(fill yes)
		(layer "In2.Cu")
		(net "P52V_HS1")
	)
	(gr_poly
		(pts
			(xy 229.340918 -85.906356) (xy 229.350986 -85.905928) (xy 229.369581 -85.898204) (xy 229.376986 -85.89137)
			(xy 239.334548 -85.89137) (xy 239.344614 -85.890937) (xy 239.363203 -85.883207) (xy 239.370616 -85.876384)
			(xy 247.635014 -77.611986) (xy 247.642409 -77.605132) (xy 247.661008 -77.59739) (xy 247.671082 -77.597)
			(xy 257.153918 -77.597) (xy 257.163987 -77.596573) (xy 257.182586 -77.588854) (xy 257.189986 -77.582014)
			(xy 261.732014 -73.039986) (xy 261.738868 -73.032591) (xy 261.74661 -73.013992) (xy 261.747 -73.003918)
			(xy 261.747 -72.538082) (xy 261.746573 -72.528013) (xy 261.738854 -72.509414) (xy 261.732014 -72.502014)
			(xy 261.687564 -72.457564) (xy 261.663942 -72.450198) (xy 261.651496 -72.452484) (xy 261.612211 -72.459147)
			(xy 261.532843 -72.466268) (xy 261.493 -72.466708) (xy 261.450652 -72.466204) (xy 261.366338 -72.458153)
			(xy 261.283172 -72.442124) (xy 261.201905 -72.418263) (xy 261.123275 -72.386784) (xy 261.047994 -72.347973)
			(xy 260.976742 -72.302183) (xy 260.910166 -72.249827) (xy 260.848868 -72.191379) (xy 260.793403 -72.127369)
			(xy 260.744274 -72.058377) (xy 260.701925 -71.985027) (xy 260.666741 -71.907984) (xy 260.639039 -71.827945)
			(xy 260.619071 -71.745636) (xy 260.607018 -71.661801) (xy 260.602988 -71.5772) (xy 260.607018 -71.492599)
			(xy 260.619071 -71.408764) (xy 260.639039 -71.326455) (xy 260.666741 -71.246416) (xy 260.701925 -71.169373)
			(xy 260.744274 -71.096023) (xy 260.793403 -71.027031) (xy 260.848868 -70.963021) (xy 260.910166 -70.904573)
			(xy 260.976742 -70.852217) (xy 261.047994 -70.806427) (xy 261.123275 -70.767616) (xy 261.201905 -70.736137)
			(xy 261.283172 -70.712276) (xy 261.366338 -70.696247) (xy 261.450652 -70.688196) (xy 261.493 -70.687692)
			(xy 261.534851 -70.688172) (xy 261.618182 -70.696033) (xy 261.700407 -70.711686) (xy 261.780798 -70.734992)
			(xy 261.819898 -70.749922) (xy 261.834122 -70.75551) (xy 261.863586 -70.749414) (xy 262.392414 -70.220586)
			(xy 262.399268 -70.213191) (xy 262.40701 -70.194592) (xy 262.4074 -70.184518) (xy 262.4074 -65.380108)
			(xy 262.406921 -65.37021) (xy 262.399419 -65.351887) (xy 262.385558 -65.33775) (xy 262.376666 -65.333372)
			(xy 262.337169 -65.315863) (xy 262.261447 -65.27425) (xy 262.190117 -65.225491) (xy 262.123851 -65.170046)
			(xy 262.063272 -65.108438) (xy 262.008952 -65.041246) (xy 261.961403 -64.969105) (xy 261.921072 -64.892693)
			(xy 261.888339 -64.812731) (xy 261.863513 -64.729972) (xy 261.846828 -64.645196) (xy 261.838442 -64.559201)
			(xy 261.837932 -64.516) (xy 261.838392 -64.474898) (xy 261.845977 -64.393043) (xy 261.861083 -64.312238)
			(xy 261.88358 -64.233171) (xy 261.913277 -64.156518) (xy 261.94992 -64.082931) (xy 261.993196 -64.01304)
			(xy 262.042737 -63.94744) (xy 262.098119 -63.886691) (xy 262.158871 -63.831311) (xy 262.224473 -63.781773)
			(xy 262.294366 -63.7385) (xy 262.367954 -63.70186) (xy 262.444609 -63.672167) (xy 262.523677 -63.649674)
			(xy 262.604483 -63.634572) (xy 262.686337 -63.62699) (xy 262.72744 -63.626492) (xy 262.768492 -63.626966)
			(xy 262.850247 -63.634537) (xy 262.930956 -63.649611) (xy 263.009932 -63.672059) (xy 263.086503 -63.701691)
			(xy 263.160017 -63.738253) (xy 263.229848 -63.781436) (xy 263.295402 -63.830871) (xy 263.356121 -63.886137)
			(xy 263.411488 -63.946764) (xy 263.461031 -64.012236) (xy 263.48309 -64.046862) (xy 263.48944 -64.056768)
			(xy 263.508744 -64.06896) (xy 263.599422 -64.079628) (xy 263.610978 -64.080412) (xy 263.632805 -64.072735)
			(xy 263.641332 -64.064896) (xy 265.40333 -62.302898) (xy 265.410184 -62.295503) (xy 265.417929 -62.276904)
			(xy 265.418316 -62.26683) (xy 265.418316 -54.355238) (xy 265.417882 -54.345172) (xy 265.410154 -54.326583)
			(xy 265.40333 -54.31917) (xy 263.326626 -52.242466) (xy 263.319227 -52.235624) (xy 263.300628 -52.227906)
			(xy 263.290558 -52.22748) (xy 260.194044 -52.22748) (xy 260.183978 -52.227913) (xy 260.165386 -52.235639)
			(xy 260.157976 -52.242466) (xy 258.5847 -53.815742) (xy 258.577304 -53.822595) (xy 258.558706 -53.830338)
			(xy 258.548632 -53.830728) (xy 229.849934 -53.830728) (xy 229.839882 -53.830225) (xy 229.821318 -53.822507)
			(xy 229.813866 -53.815742) (xy 228.438964 -52.44084) (xy 228.43212 -52.433441) (xy 228.424397 -52.414842)
			(xy 228.423978 -52.404772) (xy 228.423978 -31.542482) (xy 228.424404 -31.532413) (xy 228.43212 -31.513811)
			(xy 228.438964 -31.506414) (xy 228.438964 -29.282898) (xy 228.439389 -29.272829) (xy 228.447111 -29.254231)
			(xy 228.45395 -29.24683) (xy 230.01859 -27.68219) (xy 230.025984 -27.675332) (xy 230.044583 -27.66758)
			(xy 230.054658 -27.667204) (xy 276.809962 -27.667204) (xy 276.820027 -27.666769) (xy 276.838616 -27.65904)
			(xy 276.84603 -27.652218) (xy 277.29815 -27.200098) (xy 277.305002 -27.192702) (xy 277.312743 -27.174103)
			(xy 277.313136 -27.16403) (xy 277.313136 -15.144242) (xy 277.31357 -15.134177) (xy 277.321304 -15.115591)
			(xy 277.328122 -15.108174) (xy 280.443686 -11.99261) (xy 280.451089 -11.985776) (xy 280.469687 -11.978071)
			(xy 280.479754 -11.977624) (xy 344.555318 -11.977624) (xy 344.565387 -11.977198) (xy 344.583989 -11.969482)
			(xy 344.591386 -11.962638) (xy 345.399614 -11.15441) (xy 345.406471 -11.147016) (xy 345.414223 -11.128417)
			(xy 345.4146 -11.118342) (xy 345.4146 -7.895082) (xy 345.414173 -7.885013) (xy 345.406454 -7.866414)
			(xy 345.399614 -7.859014) (xy 344.85707 -7.31647) (xy 344.849727 -7.309657) (xy 344.831263 -7.301924)
			(xy 344.821256 -7.301484) (xy 223.461326 -7.301484) (xy 223.451336 -7.302017) (xy 223.432896 -7.309722)
			(xy 223.425512 -7.31647) (xy 221.485968 -9.256014) (xy 221.478572 -9.262865) (xy 221.459973 -9.270601)
			(xy 221.4499 -9.271) (xy 219.364814 -9.271) (xy 219.354751 -9.270561) (xy 219.336169 -9.262825) (xy 219.328746 -9.256014)
			(xy 216.32037 -6.247638) (xy 216.312972 -6.240792) (xy 216.294373 -6.233062) (xy 216.284302 -6.232652)
			(xy 121.67743 -6.232652) (xy 121.667367 -6.233089) (xy 121.648786 -6.240827) (xy 121.641362 -6.247638)
			(xy 120.918986 -6.970014) (xy 120.912132 -6.977409) (xy 120.90439 -6.996008) (xy 120.904 -7.006082)
			(xy 120.904 -11.678412) (xy 120.904425 -11.688481) (xy 120.912143 -11.707082) (xy 120.918986 -11.71448)
			(xy 121.270014 -12.065508) (xy 121.277414 -12.072352) (xy 121.296011 -12.08008) (xy 121.306082 -12.080494)
			(xy 160.6042 -12.080494) (xy 160.61427 -12.080917) (xy 160.632876 -12.08863) (xy 160.640268 -12.09548)
			(xy 162.672014 -14.127226) (xy 162.678866 -14.134622) (xy 162.686604 -14.153221) (xy 162.687 -14.163294)
			(xy 162.687 -22.560114) (xy 205.177635 -22.560114) (xy 205.177635 -22.389758) (xy 205.18562 -22.21959)
			(xy 205.201572 -22.049983) (xy 205.225457 -21.881311) (xy 205.257221 -21.713943) (xy 205.296796 -21.548248)
			(xy 205.344093 -21.38459) (xy 205.39901 -21.223329) (xy 205.461425 -21.064819) (xy 205.531201 -20.909409)
			(xy 205.608184 -20.757441) (xy 205.692206 -20.609247) (xy 205.783082 -20.465155) (xy 205.880612 -20.325481)
			(xy 205.984582 -20.190532) (xy 206.094763 -20.060604) (xy 206.210912 -19.935984) (xy 206.332776 -19.816945)
			(xy 206.460084 -19.703749) (xy 206.592559 -19.596644) (xy 206.729909 -19.495867) (xy 206.871831 -19.401638)
			(xy 207.018013 -19.314165) (xy 207.168136 -19.23364) (xy 207.321867 -19.16024) (xy 207.47887 -19.094126)
			(xy 207.6388 -19.035444) (xy 207.801304 -18.984323) (xy 207.966025 -18.940875) (xy 208.132603 -18.905196)
			(xy 208.300669 -18.877364) (xy 208.469855 -18.85744) (xy 208.639789 -18.845468) (xy 208.810098 -18.841475)
			(xy 208.980407 -18.845468) (xy 209.150341 -18.85744) (xy 209.319527 -18.877364) (xy 209.487593 -18.905196)
			(xy 209.654171 -18.940875) (xy 209.818892 -18.984323) (xy 209.981396 -19.035444) (xy 210.141326 -19.094126)
			(xy 210.298329 -19.16024) (xy 210.45206 -19.23364) (xy 210.602183 -19.314165) (xy 210.748365 -19.401638)
			(xy 210.890287 -19.495867) (xy 211.027637 -19.596644) (xy 211.160112 -19.703749) (xy 211.28742 -19.816945)
			(xy 211.409284 -19.935984) (xy 211.525433 -20.060604) (xy 211.635614 -20.190532) (xy 211.739584 -20.325481)
			(xy 211.837114 -20.465155) (xy 211.92799 -20.609247) (xy 212.012012 -20.757441) (xy 212.088995 -20.909409)
			(xy 212.158771 -21.064819) (xy 212.221186 -21.223329) (xy 212.276103 -21.38459) (xy 212.3234 -21.548248)
			(xy 212.362975 -21.713943) (xy 212.394739 -21.881311) (xy 212.418624 -22.049983) (xy 212.434576 -22.21959)
			(xy 212.442561 -22.389758) (xy 212.44306 -22.474936) (xy 212.442561 -22.560114) (xy 235.177575 -22.560114)
			(xy 235.177575 -22.389758) (xy 235.18556 -22.21959) (xy 235.201512 -22.049983) (xy 235.225397 -21.881311)
			(xy 235.257161 -21.713943) (xy 235.296736 -21.548248) (xy 235.344033 -21.38459) (xy 235.39895 -21.223329)
			(xy 235.461365 -21.064819) (xy 235.531141 -20.909409) (xy 235.608124 -20.757441) (xy 235.692146 -20.609247)
			(xy 235.783022 -20.465155) (xy 235.880552 -20.325481) (xy 235.984522 -20.190532) (xy 236.094703 -20.060604)
			(xy 236.210852 -19.935984) (xy 236.332716 -19.816945) (xy 236.460024 -19.703749) (xy 236.592499 -19.596644)
			(xy 236.729849 -19.495867) (xy 236.871771 -19.401638) (xy 237.017953 -19.314165) (xy 237.168076 -19.23364)
			(xy 237.321807 -19.16024) (xy 237.47881 -19.094126) (xy 237.63874 -19.035444) (xy 237.801244 -18.984323)
			(xy 237.965965 -18.940875) (xy 238.132543 -18.905196) (xy 238.300609 -18.877364) (xy 238.469795 -18.85744)
			(xy 238.639729 -18.845468) (xy 238.810038 -18.841475) (xy 238.980347 -18.845468) (xy 239.150281 -18.85744)
			(xy 239.319467 -18.877364) (xy 239.487533 -18.905196) (xy 239.654111 -18.940875) (xy 239.818832 -18.984323)
			(xy 239.981336 -19.035444) (xy 240.141266 -19.094126) (xy 240.298269 -19.16024) (xy 240.452 -19.23364)
			(xy 240.602123 -19.314165) (xy 240.748305 -19.401638) (xy 240.890227 -19.495867) (xy 241.027577 -19.596644)
			(xy 241.160052 -19.703749) (xy 241.28736 -19.816945) (xy 241.409224 -19.935984) (xy 241.525373 -20.060604)
			(xy 241.635554 -20.190532) (xy 241.739524 -20.325481) (xy 241.837054 -20.465155) (xy 241.92793 -20.609247)
			(xy 242.011952 -20.757441) (xy 242.088935 -20.909409) (xy 242.158711 -21.064819) (xy 242.221126 -21.223329)
			(xy 242.276043 -21.38459) (xy 242.32334 -21.548248) (xy 242.362915 -21.713943) (xy 242.394679 -21.881311)
			(xy 242.418564 -22.049983) (xy 242.434516 -22.21959) (xy 242.442501 -22.389758) (xy 242.443 -22.474936)
			(xy 242.442501 -22.560114) (xy 242.434516 -22.730282) (xy 242.418564 -22.899889) (xy 242.394679 -23.068561)
			(xy 242.362915 -23.235929) (xy 242.32334 -23.401624) (xy 242.276043 -23.565282) (xy 242.221126 -23.726543)
			(xy 242.158711 -23.885053) (xy 242.088935 -24.040463) (xy 242.011952 -24.192431) (xy 241.92793 -24.340625)
			(xy 241.837054 -24.484717) (xy 241.739524 -24.624391) (xy 241.635554 -24.75934) (xy 241.525373 -24.889268)
			(xy 241.409224 -25.013888) (xy 241.28736 -25.132927) (xy 241.160052 -25.246123) (xy 241.027577 -25.353228)
			(xy 240.890227 -25.454005) (xy 240.748305 -25.548234) (xy 240.602123 -25.635707) (xy 240.452 -25.716232)
			(xy 240.298269 -25.789632) (xy 240.141266 -25.855746) (xy 239.981336 -25.914428) (xy 239.818832 -25.965549)
			(xy 239.654111 -26.008997) (xy 239.487533 -26.044676) (xy 239.319467 -26.072508) (xy 239.150281 -26.092432)
			(xy 238.980347 -26.104404) (xy 238.810038 -26.108398) (xy 238.639729 -26.104404) (xy 238.469795 -26.092432)
			(xy 238.300609 -26.072508) (xy 238.132543 -26.044676) (xy 237.965965 -26.008997) (xy 237.801244 -25.965549)
			(xy 237.63874 -25.914428) (xy 237.47881 -25.855746) (xy 237.321807 -25.789632) (xy 237.168076 -25.716232)
			(xy 237.017953 -25.635707) (xy 236.871771 -25.548234) (xy 236.729849 -25.454005) (xy 236.592499 -25.353228)
			(xy 236.460024 -25.246123) (xy 236.332716 -25.132927) (xy 236.210852 -25.013888) (xy 236.094703 -24.889268)
			(xy 235.984522 -24.75934) (xy 235.880552 -24.624391) (xy 235.783022 -24.484717) (xy 235.692146 -24.340625)
			(xy 235.608124 -24.192431) (xy 235.531141 -24.040463) (xy 235.461365 -23.885053) (xy 235.39895 -23.726543)
			(xy 235.344033 -23.565282) (xy 235.296736 -23.401624) (xy 235.257161 -23.235929) (xy 235.225397 -23.068561)
			(xy 235.201512 -22.899889) (xy 235.18556 -22.730282) (xy 235.177575 -22.560114) (xy 212.442561 -22.560114)
			(xy 212.434576 -22.730282) (xy 212.418624 -22.899889) (xy 212.394739 -23.068561) (xy 212.362975 -23.235929)
			(xy 212.3234 -23.401624) (xy 212.276103 -23.565282) (xy 212.221186 -23.726543) (xy 212.158771 -23.885053)
			(xy 212.088995 -24.040463) (xy 212.012012 -24.192431) (xy 211.92799 -24.340625) (xy 211.837114 -24.484717)
			(xy 211.739584 -24.624391) (xy 211.635614 -24.75934) (xy 211.525433 -24.889268) (xy 211.409284 -25.013888)
			(xy 211.28742 -25.132927) (xy 211.160112 -25.246123) (xy 211.027637 -25.353228) (xy 210.890287 -25.454005)
			(xy 210.748365 -25.548234) (xy 210.602183 -25.635707) (xy 210.45206 -25.716232) (xy 210.298329 -25.789632)
			(xy 210.141326 -25.855746) (xy 209.981396 -25.914428) (xy 209.818892 -25.965549) (xy 209.654171 -26.008997)
			(xy 209.487593 -26.044676) (xy 209.319527 -26.072508) (xy 209.150341 -26.092432) (xy 208.980407 -26.104404)
			(xy 208.810098 -26.108398) (xy 208.639789 -26.104404) (xy 208.469855 -26.092432) (xy 208.300669 -26.072508)
			(xy 208.132603 -26.044676) (xy 207.966025 -26.008997) (xy 207.801304 -25.965549) (xy 207.6388 -25.914428)
			(xy 207.47887 -25.855746) (xy 207.321867 -25.789632) (xy 207.168136 -25.716232) (xy 207.018013 -25.635707)
			(xy 206.871831 -25.548234) (xy 206.729909 -25.454005) (xy 206.592559 -25.353228) (xy 206.460084 -25.246123)
			(xy 206.332776 -25.132927) (xy 206.210912 -25.013888) (xy 206.094763 -24.889268) (xy 205.984582 -24.75934)
			(xy 205.880612 -24.624391) (xy 205.783082 -24.484717) (xy 205.692206 -24.340625) (xy 205.608184 -24.192431)
			(xy 205.531201 -24.040463) (xy 205.461425 -23.885053) (xy 205.39901 -23.726543) (xy 205.344093 -23.565282)
			(xy 205.296796 -23.401624) (xy 205.257221 -23.235929) (xy 205.225457 -23.068561) (xy 205.201572 -22.899889)
			(xy 205.18562 -22.730282) (xy 205.177635 -22.560114) (xy 162.687 -22.560114) (xy 162.687 -26.92781)
			(xy 162.687425 -26.937879) (xy 162.695142 -26.956481) (xy 162.701986 -26.963878) (xy 163.550346 -27.812238)
			(xy 163.557744 -27.819084) (xy 163.576343 -27.826811) (xy 163.586414 -27.827224) (xy 210.116674 -27.827224)
			(xy 210.126738 -27.827661) (xy 210.14532 -27.835397) (xy 210.152742 -27.84221) (xy 211.855304 -29.544772)
			(xy 211.862139 -29.552175) (xy 211.869846 -29.570773) (xy 211.87029 -29.58084) (xy 211.87029 -31.405322)
			(xy 211.870717 -31.415391) (xy 211.878436 -31.43399) (xy 211.885276 -31.44139) (xy 211.885276 -52.421282)
			(xy 211.884837 -52.431345) (xy 211.877099 -52.449926) (xy 211.87029 -52.45735) (xy 210.699096 -53.628544)
			(xy 210.6917 -53.635396) (xy 210.673101 -53.643138) (xy 210.663028 -53.64353) (xy 183.198008 -53.64353)
			(xy 183.187936 -53.643109) (xy 183.169327 -53.6354) (xy 183.16194 -53.628544) (xy 180.09616 -50.562764)
			(xy 180.089313 -50.555366) (xy 180.081582 -50.536768) (xy 180.081174 -50.526696) (xy 180.081174 -49.515268)
			(xy 180.080744 -49.505201) (xy 180.073019 -49.486607) (xy 180.066188 -49.4792) (xy 179.859686 -49.272698)
			(xy 179.852286 -49.265854) (xy 179.833689 -49.258125) (xy 179.823618 -49.257712) (xy 178.403758 -49.257712)
			(xy 178.393691 -49.258143) (xy 178.375099 -49.26587) (xy 178.36769 -49.272698) (xy 178.118262 -49.522126)
			(xy 178.111413 -49.529523) (xy 178.103678 -49.548122) (xy 178.103276 -49.558194) (xy 178.103276 -49.688496)
			(xy 178.103968 -49.700657) (xy 178.115111 -49.722276) (xy 178.124612 -49.729898) (xy 178.20259 -49.785016)
			(xy 178.22672 -49.788572) (xy 178.238404 -49.784508) (xy 178.268995 -49.774465) (xy 178.332453 -49.763611)
			(xy 178.364642 -49.762918) (xy 178.391889 -49.763407) (xy 178.445829 -49.771168) (xy 178.498115 -49.786526)
			(xy 178.547683 -49.809168) (xy 178.593525 -49.838633) (xy 178.634708 -49.874322) (xy 178.670392 -49.915508)
			(xy 178.699853 -49.961353) (xy 178.722489 -50.010924) (xy 178.737841 -50.063212) (xy 178.745596 -50.117153)
			(xy 178.745596 -50.171647) (xy 178.737841 -50.225588) (xy 178.722489 -50.277876) (xy 178.699853 -50.327447)
			(xy 178.670392 -50.373292) (xy 178.634708 -50.414478) (xy 178.593525 -50.450167) (xy 178.547683 -50.479632)
			(xy 178.498115 -50.502274) (xy 178.445829 -50.517632) (xy 178.391889 -50.525393) (xy 178.364642 -50.525934)
			(xy 178.332453 -50.525242) (xy 178.268996 -50.514383) (xy 178.238404 -50.504344) (xy 178.22672 -50.50028)
			(xy 178.20259 -50.503836) (xy 178.124612 -50.558954) (xy 178.115103 -50.56657) (xy 178.103959 -50.588192)
			(xy 178.103276 -50.600356) (xy 178.103276 -51.268376) (xy 178.103781 -51.278427) (xy 178.111502 -51.296988)
			(xy 178.118262 -51.304444) (xy 178.89601 -52.082192) (xy 178.910742 -52.089558) (xy 178.91887 -52.090574)
			(xy 178.94605 -52.094805) (xy 178.998897 -52.11006) (xy 179.049006 -52.132748) (xy 179.095337 -52.162396)
			(xy 179.13693 -52.198391) (xy 179.172921 -52.239987) (xy 179.202566 -52.28632) (xy 179.22525 -52.33643)
			(xy 179.240501 -52.389279) (xy 179.244752 -52.416456) (xy 179.245768 -52.424584) (xy 179.253134 -52.439316)
			(xy 181.366414 -54.552596) (xy 181.37327 -54.55999) (xy 181.38102 -54.578589) (xy 181.3814 -54.588664)
			(xy 181.3814 -54.637249) (xy 259.848378 -54.637249) (xy 259.848378 -54.582751) (xy 259.856133 -54.528808)
			(xy 259.871485 -54.476517) (xy 259.894123 -54.426943) (xy 259.923585 -54.381095) (xy 259.959271 -54.339906)
			(xy 260.000455 -54.304215) (xy 260.046299 -54.274747) (xy 260.09587 -54.252103) (xy 260.148159 -54.236743)
			(xy 260.202101 -54.228981) (xy 260.22935 -54.228492) (xy 260.255953 -54.228982) (xy 260.308644 -54.236357)
			(xy 260.359798 -54.250984) (xy 260.408423 -54.27258) (xy 260.453574 -54.300725) (xy 260.494374 -54.334873)
			(xy 260.530032 -54.374361) (xy 260.545326 -54.396132) (xy 260.55366 -54.407612) (xy 260.575404 -54.425816)
			(xy 260.601317 -54.437334) (xy 260.6294 -54.441274) (xy 260.657483 -54.437334) (xy 260.683396 -54.425816)
			(xy 260.70514 -54.407612) (xy 260.713474 -54.396132) (xy 260.728771 -54.374363) (xy 260.764437 -54.334884)
			(xy 260.80524 -54.300741) (xy 260.85039 -54.272596) (xy 260.899011 -54.250993) (xy 260.950161 -54.236352)
			(xy 261.002848 -54.228956) (xy 261.02945 -54.228492) (xy 261.056705 -54.228952) (xy 261.110662 -54.236703)
			(xy 261.162965 -54.252055) (xy 261.212552 -54.274694) (xy 261.258411 -54.304161) (xy 261.29961 -54.339855)
			(xy 261.335309 -54.381049) (xy 261.364782 -54.426904) (xy 261.387428 -54.476488) (xy 261.402786 -54.52879)
			(xy 261.410545 -54.582745) (xy 261.410545 -54.637255) (xy 261.402786 -54.69121) (xy 261.387428 -54.743512)
			(xy 261.364782 -54.793096) (xy 261.335309 -54.838951) (xy 261.29961 -54.880145) (xy 261.258411 -54.915839)
			(xy 261.212552 -54.945306) (xy 261.162965 -54.967945) (xy 261.110662 -54.983297) (xy 261.056705 -54.991048)
			(xy 261.02945 -54.991508) (xy 261.002847 -54.991018) (xy 260.950156 -54.983643) (xy 260.899002 -54.969016)
			(xy 260.850377 -54.94742) (xy 260.805226 -54.919275) (xy 260.764426 -54.885127) (xy 260.728768 -54.845639)
			(xy 260.713474 -54.823868) (xy 260.70514 -54.812388) (xy 260.683396 -54.794184) (xy 260.657483 -54.782666)
			(xy 260.6294 -54.778726) (xy 260.601317 -54.782666) (xy 260.575404 -54.794184) (xy 260.55366 -54.812388)
			(xy 260.545326 -54.823868) (xy 260.530029 -54.845637) (xy 260.494363 -54.885116) (xy 260.45356 -54.919259)
			(xy 260.40841 -54.947404) (xy 260.359789 -54.969007) (xy 260.308639 -54.983648) (xy 260.255952 -54.991044)
			(xy 260.22935 -54.991508) (xy 260.202101 -54.991019) (xy 260.148159 -54.983257) (xy 260.09587 -54.967897)
			(xy 260.046299 -54.945253) (xy 260.000455 -54.915785) (xy 259.959271 -54.880094) (xy 259.923585 -54.838905)
			(xy 259.894123 -54.793057) (xy 259.871485 -54.743483) (xy 259.856133 -54.691192) (xy 259.848378 -54.637249)
			(xy 181.3814 -54.637249) (xy 181.3814 -68.776088) (xy 181.381921 -68.786275) (xy 181.389945 -68.805011)
			(xy 181.40459 -68.819187) (xy 181.413912 -68.823332) (xy 181.516782 -68.86321) (xy 181.547516 -68.856098)
			(xy 181.558184 -68.844414) (xy 181.586209 -68.814339) (xy 181.64695 -68.75894) (xy 181.712547 -68.709384)
			(xy 181.782438 -68.666096) (xy 181.856027 -68.629444) (xy 181.932685 -68.599743) (xy 182.011757 -68.577246)
			(xy 182.092569 -68.562144) (xy 182.17443 -68.554567) (xy 182.215536 -68.554092) (xy 182.256637 -68.554568)
			(xy 182.338489 -68.562156) (xy 182.419292 -68.577264) (xy 182.428907 -68.58) (xy 183.920388 -68.58)
			(xy 183.924418 -68.495399) (xy 183.936471 -68.411564) (xy 183.956439 -68.329255) (xy 183.984141 -68.249216)
			(xy 184.019325 -68.172173) (xy 184.061674 -68.098823) (xy 184.110803 -68.029831) (xy 184.166268 -67.965821)
			(xy 184.227566 -67.907373) (xy 184.294142 -67.855017) (xy 184.365394 -67.809227) (xy 184.440675 -67.770416)
			(xy 184.519305 -67.738937) (xy 184.600572 -67.715076) (xy 184.683738 -67.699047) (xy 184.768052 -67.690996)
			(xy 184.8104 -67.690492) (xy 184.856796 -67.691075) (xy 184.949084 -67.70072) (xy 185.039868 -67.719916)
			(xy 185.128161 -67.748454) (xy 185.170826 -67.766692) (xy 185.180766 -67.770512) (xy 185.202034 -67.770512)
			(xy 185.211974 -67.766692) (xy 185.254636 -67.748447) (xy 185.342929 -67.719903) (xy 185.433714 -67.70071)
			(xy 185.526004 -67.691077) (xy 185.5724 -67.690492) (xy 185.614748 -67.690996) (xy 185.699062 -67.699047)
			(xy 185.782228 -67.715076) (xy 185.863495 -67.738937) (xy 185.942125 -67.770416) (xy 186.017406 -67.809227)
			(xy 186.088658 -67.855017) (xy 186.155234 -67.907373) (xy 186.216532 -67.965821) (xy 186.271997 -68.029831)
			(xy 186.321126 -68.098823) (xy 186.363475 -68.172173) (xy 186.398659 -68.249216) (xy 186.426361 -68.329255)
			(xy 186.446329 -68.411564) (xy 186.458382 -68.495399) (xy 186.462413 -68.58) (xy 186.458382 -68.664601)
			(xy 186.446329 -68.748436) (xy 186.426361 -68.830745) (xy 186.398659 -68.910784) (xy 186.363475 -68.987827)
			(xy 186.321126 -69.061177) (xy 186.271997 -69.130169) (xy 186.216532 -69.194179) (xy 186.155234 -69.252627)
			(xy 186.088658 -69.304983) (xy 186.017406 -69.350773) (xy 185.942125 -69.389584) (xy 185.863495 -69.421063)
			(xy 185.782228 -69.444924) (xy 185.699062 -69.460953) (xy 185.614748 -69.469004) (xy 185.5724 -69.469508)
			(xy 185.526004 -69.468925) (xy 185.433716 -69.45928) (xy 185.342932 -69.440084) (xy 185.254639 -69.411546)
			(xy 185.211974 -69.393308) (xy 185.202034 -69.389488) (xy 185.180766 -69.389488) (xy 185.170826 -69.393308)
			(xy 185.128164 -69.411553) (xy 185.039871 -69.440097) (xy 184.949086 -69.45929) (xy 184.856796 -69.468923)
			(xy 184.8104 -69.469508) (xy 184.768052 -69.469004) (xy 184.683738 -69.460953) (xy 184.600572 -69.444924)
			(xy 184.519305 -69.421063) (xy 184.440675 -69.389584) (xy 184.365394 -69.350773) (xy 184.294142 -69.304983)
			(xy 184.227566 -69.252627) (xy 184.166268 -69.194179) (xy 184.110803 -69.130169) (xy 184.061674 -69.061177)
			(xy 184.019325 -68.987827) (xy 183.984141 -68.910784) (xy 183.956439 -68.830745) (xy 183.936471 -68.748436)
			(xy 183.924418 -68.664601) (xy 183.920388 -68.58) (xy 182.428907 -68.58) (xy 182.498356 -68.599762)
			(xy 182.575007 -68.62946) (xy 182.648591 -68.666103) (xy 182.71848 -68.709379) (xy 182.784078 -68.758919)
			(xy 182.844826 -68.8143) (xy 182.900204 -68.875049) (xy 182.949742 -68.94065) (xy 182.993015 -69.01054)
			(xy 183.029655 -69.084126) (xy 183.059349 -69.160778) (xy 183.081845 -69.239843) (xy 183.096949 -69.320646)
			(xy 183.104533 -69.402499) (xy 183.105044 -69.4436) (xy 183.104483 -69.488931) (xy 183.095261 -69.579124)
			(xy 183.076904 -69.667908) (xy 183.049602 -69.754362) (xy 183.013639 -69.837587) (xy 182.992014 -69.877432)
			(xy 182.986426 -69.887338) (xy 182.984902 -69.909436) (xy 183.020208 -70.003416) (xy 183.035956 -70.01891)
			(xy 183.046624 -70.02272) (xy 183.086107 -70.037263) (xy 183.162387 -70.072787) (xy 183.234971 -70.115355)
			(xy 183.303211 -70.164588) (xy 183.366497 -70.220044) (xy 183.424264 -70.281229) (xy 183.475995 -70.347596)
			(xy 183.521227 -70.418551) (xy 183.559557 -70.49346) (xy 183.590642 -70.571654) (xy 183.614204 -70.652434)
			(xy 183.630032 -70.735078) (xy 183.637986 -70.818847) (xy 183.638444 -70.86092) (xy 183.63794 -70.903268)
			(xy 183.629889 -70.987582) (xy 183.61386 -71.070748) (xy 183.589999 -71.152015) (xy 183.55852 -71.230645)
			(xy 183.519709 -71.305926) (xy 183.473919 -71.377178) (xy 183.421563 -71.443754) (xy 183.363115 -71.505052)
			(xy 183.299105 -71.560517) (xy 183.230113 -71.609646) (xy 183.156763 -71.651995) (xy 183.07972 -71.687179)
			(xy 182.999681 -71.714881) (xy 182.917372 -71.734849) (xy 182.833537 -71.746902) (xy 182.748936 -71.750933)
			(xy 182.664335 -71.746902) (xy 182.5805 -71.734849) (xy 182.498191 -71.714881) (xy 182.418152 -71.687179)
			(xy 182.341109 -71.651995) (xy 182.267759 -71.609646) (xy 182.198767 -71.560517) (xy 182.134757 -71.505052)
			(xy 182.076309 -71.443754) (xy 182.023953 -71.377178) (xy 181.978163 -71.305926) (xy 181.939352 -71.230645)
			(xy 181.907873 -71.152015) (xy 181.884012 -71.070748) (xy 181.867983 -70.987582) (xy 181.859932 -70.903268)
			(xy 181.859428 -70.86092) (xy 181.859988 -70.815588) (xy 181.869207 -70.725395) (xy 181.887562 -70.636609)
			(xy 181.914862 -70.550154) (xy 181.950823 -70.466927) (xy 181.972458 -70.427088) (xy 181.978046 -70.417182)
			(xy 181.97957 -70.395084) (xy 181.944264 -70.301104) (xy 181.928516 -70.28561) (xy 181.917848 -70.2818)
			(xy 181.876913 -70.266697) (xy 181.797941 -70.229583) (xy 181.722986 -70.18491) (xy 181.652769 -70.133107)
			(xy 181.587965 -70.074674) (xy 181.558184 -70.042786) (xy 181.547516 -70.031102) (xy 181.516782 -70.02399)
			(xy 181.413912 -70.063868) (xy 181.404548 -70.06795) (xy 181.38986 -70.082121) (xy 181.381884 -70.100907)
			(xy 181.3814 -70.111112) (xy 181.3814 -74.337348) (xy 183.260996 -74.337348) (xy 183.260996 -74.252652)
			(xy 183.269047 -74.168338) (xy 183.285076 -74.085172) (xy 183.308937 -74.003905) (xy 183.340416 -73.925275)
			(xy 183.379227 -73.849994) (xy 183.425017 -73.778742) (xy 183.477373 -73.712166) (xy 183.535821 -73.650868)
			(xy 183.599831 -73.595403) (xy 183.668823 -73.546274) (xy 183.742173 -73.503925) (xy 183.819216 -73.468741)
			(xy 183.899255 -73.441039) (xy 183.981564 -73.421071) (xy 184.065399 -73.409018) (xy 184.15 -73.404988)
			(xy 184.234601 -73.409018) (xy 184.318436 -73.421071) (xy 184.400745 -73.441039) (xy 184.480784 -73.468741)
			(xy 184.557827 -73.503925) (xy 184.631177 -73.546274) (xy 184.700169 -73.595403) (xy 184.764179 -73.650868)
			(xy 184.822627 -73.712166) (xy 184.874983 -73.778742) (xy 184.920773 -73.849994) (xy 184.959584 -73.925275)
			(xy 184.991063 -74.003905) (xy 185.014924 -74.085172) (xy 185.030953 -74.168338) (xy 185.039004 -74.252652)
			(xy 185.039508 -74.295) (xy 185.039004 -74.337348) (xy 185.030953 -74.421662) (xy 185.014924 -74.504828)
			(xy 184.991063 -74.586095) (xy 184.959584 -74.664725) (xy 184.920773 -74.740006) (xy 184.874983 -74.811258)
			(xy 184.822627 -74.877834) (xy 184.764179 -74.939132) (xy 184.700169 -74.994597) (xy 184.631177 -75.043726)
			(xy 184.557827 -75.086075) (xy 184.480784 -75.121259) (xy 184.400745 -75.148961) (xy 184.318436 -75.168929)
			(xy 184.234601 -75.180982) (xy 184.15 -75.185013) (xy 184.065399 -75.180982) (xy 183.981564 -75.168929)
			(xy 183.899255 -75.148961) (xy 183.819216 -75.121259) (xy 183.742173 -75.086075) (xy 183.668823 -75.043726)
			(xy 183.599831 -74.994597) (xy 183.535821 -74.939132) (xy 183.477373 -74.877834) (xy 183.425017 -74.811258)
			(xy 183.379227 -74.740006) (xy 183.340416 -74.664725) (xy 183.308937 -74.586095) (xy 183.285076 -74.504828)
			(xy 183.269047 -74.421662) (xy 183.260996 -74.337348) (xy 181.3814 -74.337348) (xy 181.3814 -75.289918)
			(xy 181.381827 -75.299987) (xy 181.389546 -75.318586) (xy 181.396386 -75.325986) (xy 181.747414 -75.677014)
			(xy 181.754809 -75.683868) (xy 181.773408 -75.69161) (xy 181.783482 -75.692) (xy 183.604408 -75.692)
			(xy 183.62295 -75.691492) (xy 183.641492 -75.692) (xy 184.509918 -75.692) (xy 184.519987 -75.692427)
			(xy 184.538586 -75.700146) (xy 184.545986 -75.706986) (xy 185.97499 -77.13599) (xy 185.982334 -77.142803)
			(xy 186.000797 -77.150541) (xy 186.010804 -77.150976) (xy 199.7456 -77.150976) (xy 199.77067 -77.151442)
			(xy 199.820193 -77.159288) (xy 199.867878 -77.174787) (xy 199.912551 -77.197556) (xy 199.95311 -77.227035)
			(xy 199.971152 -77.244448) (xy 200.054972 -77.328014) (xy 200.06237 -77.334858) (xy 200.08097 -77.34258)
			(xy 200.09104 -77.343) (xy 200.384918 -77.343) (xy 200.394987 -77.343427) (xy 200.413586 -77.351146)
			(xy 200.420986 -77.357986) (xy 202.773114 -79.710114) (xy 205.177635 -79.710114) (xy 205.177635 -79.539758)
			(xy 205.18562 -79.36959) (xy 205.201572 -79.199983) (xy 205.225457 -79.031311) (xy 205.257221 -78.863943)
			(xy 205.296796 -78.698248) (xy 205.344093 -78.53459) (xy 205.39901 -78.373329) (xy 205.461425 -78.214819)
			(xy 205.531201 -78.059409) (xy 205.608184 -77.907441) (xy 205.692206 -77.759247) (xy 205.783082 -77.615155)
			(xy 205.880612 -77.475481) (xy 205.984582 -77.340532) (xy 206.094763 -77.210604) (xy 206.210912 -77.085984)
			(xy 206.332776 -76.966945) (xy 206.460084 -76.853749) (xy 206.592559 -76.746644) (xy 206.729909 -76.645867)
			(xy 206.871831 -76.551638) (xy 207.018013 -76.464165) (xy 207.168136 -76.38364) (xy 207.321867 -76.31024)
			(xy 207.47887 -76.244126) (xy 207.6388 -76.185444) (xy 207.801304 -76.134323) (xy 207.966025 -76.090875)
			(xy 208.132603 -76.055196) (xy 208.300669 -76.027364) (xy 208.469855 -76.00744) (xy 208.639789 -75.995468)
			(xy 208.810098 -75.991475) (xy 208.980407 -75.995468) (xy 209.150341 -76.00744) (xy 209.319527 -76.027364)
			(xy 209.487593 -76.055196) (xy 209.654171 -76.090875) (xy 209.818892 -76.134323) (xy 209.981396 -76.185444)
			(xy 210.141326 -76.244126) (xy 210.298329 -76.31024) (xy 210.45206 -76.38364) (xy 210.602183 -76.464165)
			(xy 210.748365 -76.551638) (xy 210.890287 -76.645867) (xy 211.027637 -76.746644) (xy 211.160112 -76.853749)
			(xy 211.28742 -76.966945) (xy 211.409284 -77.085984) (xy 211.525433 -77.210604) (xy 211.635614 -77.340532)
			(xy 211.739584 -77.475481) (xy 211.837114 -77.615155) (xy 211.92799 -77.759247) (xy 212.012012 -77.907441)
			(xy 212.088995 -78.059409) (xy 212.158771 -78.214819) (xy 212.221186 -78.373329) (xy 212.276103 -78.53459)
			(xy 212.3234 -78.698248) (xy 212.362975 -78.863943) (xy 212.394739 -79.031311) (xy 212.418624 -79.199983)
			(xy 212.434576 -79.36959) (xy 212.442561 -79.539758) (xy 212.44306 -79.624936) (xy 212.442561 -79.710114)
			(xy 235.177575 -79.710114) (xy 235.177575 -79.539758) (xy 235.18556 -79.36959) (xy 235.201512 -79.199983)
			(xy 235.225397 -79.031311) (xy 235.257161 -78.863943) (xy 235.296736 -78.698248) (xy 235.344033 -78.53459)
			(xy 235.39895 -78.373329) (xy 235.461365 -78.214819) (xy 235.531141 -78.059409) (xy 235.608124 -77.907441)
			(xy 235.692146 -77.759247) (xy 235.783022 -77.615155) (xy 235.880552 -77.475481) (xy 235.984522 -77.340532)
			(xy 236.094703 -77.210604) (xy 236.210852 -77.085984) (xy 236.332716 -76.966945) (xy 236.460024 -76.853749)
			(xy 236.592499 -76.746644) (xy 236.729849 -76.645867) (xy 236.871771 -76.551638) (xy 237.017953 -76.464165)
			(xy 237.168076 -76.38364) (xy 237.321807 -76.31024) (xy 237.47881 -76.244126) (xy 237.63874 -76.185444)
			(xy 237.801244 -76.134323) (xy 237.965965 -76.090875) (xy 238.132543 -76.055196) (xy 238.300609 -76.027364)
			(xy 238.469795 -76.00744) (xy 238.639729 -75.995468) (xy 238.810038 -75.991475) (xy 238.980347 -75.995468)
			(xy 239.150281 -76.00744) (xy 239.319467 -76.027364) (xy 239.487533 -76.055196) (xy 239.654111 -76.090875)
			(xy 239.818832 -76.134323) (xy 239.981336 -76.185444) (xy 240.141266 -76.244126) (xy 240.298269 -76.31024)
			(xy 240.452 -76.38364) (xy 240.602123 -76.464165) (xy 240.748305 -76.551638) (xy 240.890227 -76.645867)
			(xy 241.027577 -76.746644) (xy 241.160052 -76.853749) (xy 241.28736 -76.966945) (xy 241.409224 -77.085984)
			(xy 241.525373 -77.210604) (xy 241.635554 -77.340532) (xy 241.739524 -77.475481) (xy 241.837054 -77.615155)
			(xy 241.92793 -77.759247) (xy 242.011952 -77.907441) (xy 242.088935 -78.059409) (xy 242.158711 -78.214819)
			(xy 242.221126 -78.373329) (xy 242.276043 -78.53459) (xy 242.32334 -78.698248) (xy 242.362915 -78.863943)
			(xy 242.394679 -79.031311) (xy 242.418564 -79.199983) (xy 242.434516 -79.36959) (xy 242.442501 -79.539758)
			(xy 242.443 -79.624936) (xy 242.442501 -79.710114) (xy 242.434516 -79.880282) (xy 242.418564 -80.049889)
			(xy 242.394679 -80.218561) (xy 242.362915 -80.385929) (xy 242.32334 -80.551624) (xy 242.276043 -80.715282)
			(xy 242.221126 -80.876543) (xy 242.158711 -81.035053) (xy 242.088935 -81.190463) (xy 242.011952 -81.342431)
			(xy 241.92793 -81.490625) (xy 241.837054 -81.634717) (xy 241.739524 -81.774391) (xy 241.635554 -81.90934)
			(xy 241.525373 -82.039268) (xy 241.409224 -82.163888) (xy 241.28736 -82.282927) (xy 241.160052 -82.396123)
			(xy 241.027577 -82.503228) (xy 240.890227 -82.604005) (xy 240.748305 -82.698234) (xy 240.602123 -82.785707)
			(xy 240.452 -82.866232) (xy 240.298269 -82.939632) (xy 240.141266 -83.005746) (xy 239.981336 -83.064428)
			(xy 239.818832 -83.115549) (xy 239.654111 -83.158997) (xy 239.487533 -83.194676) (xy 239.319467 -83.222508)
			(xy 239.150281 -83.242432) (xy 238.980347 -83.254404) (xy 238.810038 -83.258398) (xy 238.639729 -83.254404)
			(xy 238.469795 -83.242432) (xy 238.300609 -83.222508) (xy 238.132543 -83.194676) (xy 237.965965 -83.158997)
			(xy 237.801244 -83.115549) (xy 237.63874 -83.064428) (xy 237.47881 -83.005746) (xy 237.321807 -82.939632)
			(xy 237.168076 -82.866232) (xy 237.017953 -82.785707) (xy 236.871771 -82.698234) (xy 236.729849 -82.604005)
			(xy 236.592499 -82.503228) (xy 236.460024 -82.396123) (xy 236.332716 -82.282927) (xy 236.210852 -82.163888)
			(xy 236.094703 -82.039268) (xy 235.984522 -81.90934) (xy 235.880552 -81.774391) (xy 235.783022 -81.634717)
			(xy 235.692146 -81.490625) (xy 235.608124 -81.342431) (xy 235.531141 -81.190463) (xy 235.461365 -81.035053)
			(xy 235.39895 -80.876543) (xy 235.344033 -80.715282) (xy 235.296736 -80.551624) (xy 235.257161 -80.385929)
			(xy 235.225397 -80.218561) (xy 235.201512 -80.049889) (xy 235.18556 -79.880282) (xy 235.177575 -79.710114)
			(xy 212.442561 -79.710114) (xy 212.434576 -79.880282) (xy 212.418624 -80.049889) (xy 212.394739 -80.218561)
			(xy 212.362975 -80.385929) (xy 212.3234 -80.551624) (xy 212.276103 -80.715282) (xy 212.221186 -80.876543)
			(xy 212.158771 -81.035053) (xy 212.088995 -81.190463) (xy 212.012012 -81.342431) (xy 211.92799 -81.490625)
			(xy 211.837114 -81.634717) (xy 211.739584 -81.774391) (xy 211.635614 -81.90934) (xy 211.525433 -82.039268)
			(xy 211.409284 -82.163888) (xy 211.28742 -82.282927) (xy 211.160112 -82.396123) (xy 211.027637 -82.503228)
			(xy 210.890287 -82.604005) (xy 210.748365 -82.698234) (xy 210.602183 -82.785707) (xy 210.45206 -82.866232)
			(xy 210.298329 -82.939632) (xy 210.141326 -83.005746) (xy 209.981396 -83.064428) (xy 209.818892 -83.115549)
			(xy 209.654171 -83.158997) (xy 209.487593 -83.194676) (xy 209.319527 -83.222508) (xy 209.150341 -83.242432)
			(xy 208.980407 -83.254404) (xy 208.810098 -83.258398) (xy 208.639789 -83.254404) (xy 208.469855 -83.242432)
			(xy 208.300669 -83.222508) (xy 208.132603 -83.194676) (xy 207.966025 -83.158997) (xy 207.801304 -83.115549)
			(xy 207.6388 -83.064428) (xy 207.47887 -83.005746) (xy 207.321867 -82.939632) (xy 207.168136 -82.866232)
			(xy 207.018013 -82.785707) (xy 206.871831 -82.698234) (xy 206.729909 -82.604005) (xy 206.592559 -82.503228)
			(xy 206.460084 -82.396123) (xy 206.332776 -82.282927) (xy 206.210912 -82.163888) (xy 206.094763 -82.039268)
			(xy 205.984582 -81.90934) (xy 205.880612 -81.774391) (xy 205.783082 -81.634717) (xy 205.692206 -81.490625)
			(xy 205.608184 -81.342431) (xy 205.531201 -81.190463) (xy 205.461425 -81.035053) (xy 205.39901 -80.876543)
			(xy 205.344093 -80.715282) (xy 205.296796 -80.551624) (xy 205.257221 -80.385929) (xy 205.225457 -80.218561)
			(xy 205.201572 -80.049889) (xy 205.18562 -79.880282) (xy 205.177635 -79.710114) (xy 202.773114 -79.710114)
			(xy 208.95437 -85.89137) (xy 208.961771 -85.898209) (xy 208.980369 -85.905922) (xy 208.990438 -85.906356)
		)
		(stroke
			(width 0)
			(type solid)
		)
		(fill yes)
		(layer "In2.Cu")
		(net "GND")
	)
	(gr_poly
		(pts
			(xy 400.819874 -169.53738) (xy 400.826986 -169.530014) (xy 401.178014 -169.178986) (xy 401.184868 -169.171591)
			(xy 401.19261 -169.152992) (xy 401.193 -169.142918) (xy 401.193 -149.373082) (xy 401.193427 -149.363013)
			(xy 401.201146 -149.344414) (xy 401.207986 -149.337014) (xy 402.194014 -148.350986) (xy 402.201409 -148.344132)
			(xy 402.220008 -148.33639) (xy 402.230082 -148.336) (xy 413.882078 -148.336) (xy 413.900874 -148.32838)
			(xy 413.907986 -148.321014) (xy 415.006028 -147.222972) (xy 415.012878 -147.215575) (xy 415.020613 -147.196977)
			(xy 415.021014 -147.186904) (xy 415.021014 -136.814814) (xy 415.021274 -136.807926) (xy 415.025 -136.794659)
			(xy 415.02838 -136.788652) (xy 415.028634 -136.788398) (xy 415.03219 -136.782302) (xy 415.033968 -136.775952)
			(xy 415.036 -136.761982) (xy 415.036 -76.54036) (xy 413.141414 -74.645774) (xy 375.798334 -74.645774)
			(xy 371.704108 -78.74) (xy 377.061994 -78.74) (xy 377.065974 -78.650117) (xy 377.077882 -78.560937)
			(xy 377.097625 -78.473159) (xy 377.125049 -78.387469) (xy 377.159938 -78.304538) (xy 377.202021 -78.225016)
			(xy 377.250967 -78.149523) (xy 377.306394 -78.078652) (xy 377.367867 -78.012957) (xy 377.434906 -77.952952)
			(xy 377.506986 -77.899107) (xy 377.583542 -77.851843) (xy 377.663977 -77.81153) (xy 377.747659 -77.778483)
			(xy 377.833934 -77.752962) (xy 377.922128 -77.735166) (xy 378.011549 -77.725233) (xy 378.101498 -77.723243)
			(xy 378.191271 -77.72921) (xy 378.280166 -77.743088) (xy 378.367486 -77.764768) (xy 378.452548 -77.794081)
			(xy 378.534687 -77.830797) (xy 378.613259 -77.874628) (xy 378.68765 -77.925232) (xy 378.757277 -77.982213)
			(xy 378.821596 -78.045125) (xy 378.880104 -78.113475) (xy 378.932341 -78.186728) (xy 378.9779 -78.264311)
			(xy 379.016424 -78.345618) (xy 379.047611 -78.430011) (xy 379.071218 -78.51683) (xy 379.087059 -78.605395)
			(xy 379.095011 -78.695014) (xy 379.095508 -78.74) (xy 396.619994 -78.74) (xy 396.623974 -78.650117)
			(xy 396.635882 -78.560937) (xy 396.655625 -78.473159) (xy 396.683049 -78.387469) (xy 396.717938 -78.304538)
			(xy 396.760021 -78.225016) (xy 396.808967 -78.149523) (xy 396.864394 -78.078652) (xy 396.925867 -78.012957)
			(xy 396.992906 -77.952952) (xy 397.064986 -77.899107) (xy 397.141542 -77.851843) (xy 397.221977 -77.81153)
			(xy 397.305659 -77.778483) (xy 397.391934 -77.752962) (xy 397.480128 -77.735166) (xy 397.569549 -77.725233)
			(xy 397.659498 -77.723243) (xy 397.749271 -77.72921) (xy 397.838166 -77.743088) (xy 397.925486 -77.764768)
			(xy 398.010548 -77.794081) (xy 398.092687 -77.830797) (xy 398.171259 -77.874628) (xy 398.24565 -77.925232)
			(xy 398.315277 -77.982213) (xy 398.379596 -78.045125) (xy 398.438104 -78.113475) (xy 398.490341 -78.186728)
			(xy 398.5359 -78.264311) (xy 398.574424 -78.345618) (xy 398.605611 -78.430011) (xy 398.629218 -78.51683)
			(xy 398.645059 -78.605395) (xy 398.653011 -78.695014) (xy 398.653508 -78.74) (xy 398.653011 -78.784986)
			(xy 398.645059 -78.874605) (xy 398.629218 -78.96317) (xy 398.605611 -79.049989) (xy 398.574424 -79.134382)
			(xy 398.5359 -79.215689) (xy 398.490341 -79.293272) (xy 398.438104 -79.366525) (xy 398.379596 -79.434875)
			(xy 398.315277 -79.497787) (xy 398.24565 -79.554768) (xy 398.171259 -79.605372) (xy 398.092687 -79.649203)
			(xy 398.010548 -79.685919) (xy 397.925486 -79.715232) (xy 397.838166 -79.736912) (xy 397.749271 -79.75079)
			(xy 397.659498 -79.756757) (xy 397.569549 -79.754767) (xy 397.480128 -79.744834) (xy 397.391934 -79.727038)
			(xy 397.305659 -79.701517) (xy 397.221977 -79.66847) (xy 397.141542 -79.628157) (xy 397.064986 -79.580893)
			(xy 396.992906 -79.527048) (xy 396.925867 -79.467043) (xy 396.864394 -79.401348) (xy 396.808967 -79.330477)
			(xy 396.760021 -79.254984) (xy 396.717938 -79.175462) (xy 396.683049 -79.092531) (xy 396.655625 -79.006841)
			(xy 396.635882 -78.919063) (xy 396.623974 -78.829883) (xy 396.619994 -78.74) (xy 379.095508 -78.74)
			(xy 379.095011 -78.784986) (xy 379.087059 -78.874605) (xy 379.071218 -78.96317) (xy 379.047611 -79.049989)
			(xy 379.016424 -79.134382) (xy 378.9779 -79.215689) (xy 378.932341 -79.293272) (xy 378.880104 -79.366525)
			(xy 378.821596 -79.434875) (xy 378.757277 -79.497787) (xy 378.68765 -79.554768) (xy 378.613259 -79.605372)
			(xy 378.534687 -79.649203) (xy 378.452548 -79.685919) (xy 378.367486 -79.715232) (xy 378.280166 -79.736912)
			(xy 378.191271 -79.75079) (xy 378.101498 -79.756757) (xy 378.011549 -79.754767) (xy 377.922128 -79.744834)
			(xy 377.833934 -79.727038) (xy 377.747659 -79.701517) (xy 377.663977 -79.66847) (xy 377.583542 -79.628157)
			(xy 377.506986 -79.580893) (xy 377.434906 -79.527048) (xy 377.367867 -79.467043) (xy 377.306394 -79.401348)
			(xy 377.250967 -79.330477) (xy 377.202021 -79.254984) (xy 377.159938 -79.175462) (xy 377.125049 -79.092531)
			(xy 377.097625 -79.006841) (xy 377.077882 -78.919063) (xy 377.065974 -78.829883) (xy 377.061994 -78.74)
			(xy 371.704108 -78.74) (xy 358.88422 -91.559888) (xy 376.553995 -91.559888) (xy 376.55797 -91.449847)
			(xy 376.569876 -91.34038) (xy 376.589649 -91.232057) (xy 376.617187 -91.125443) (xy 376.652346 -91.021095)
			(xy 376.694943 -90.919555) (xy 376.744756 -90.821354) (xy 376.801525 -90.727003) (xy 376.864954 -90.636994)
			(xy 376.934713 -90.551797) (xy 377.010437 -90.471856) (xy 377.091733 -90.397587) (xy 377.178175 -90.329378)
			(xy 377.269314 -90.267584) (xy 377.364675 -90.212528) (xy 377.463759 -90.164496) (xy 377.566052 -90.123739)
			(xy 377.671018 -90.090469) (xy 377.778111 -90.064861) (xy 377.886774 -90.047047) (xy 377.996438 -90.03712)
			(xy 378.106533 -90.035132) (xy 378.216484 -90.041093) (xy 378.325718 -90.054973) (xy 378.433667 -90.076698)
			(xy 378.539766 -90.106157) (xy 378.643463 -90.143194) (xy 378.744217 -90.187617) (xy 378.841503 -90.239195)
			(xy 378.934813 -90.297658) (xy 379.023662 -90.362702) (xy 379.107586 -90.433987) (xy 379.186147 -90.511143)
			(xy 379.258936 -90.593766) (xy 379.325573 -90.681426) (xy 379.385711 -90.773666) (xy 379.439037 -90.870005)
			(xy 379.485272 -90.96994) (xy 379.524176 -91.072952) (xy 379.555545 -91.178502) (xy 379.579216 -91.28604)
			(xy 379.595065 -91.395006) (xy 379.603011 -91.504832) (xy 379.603508 -91.559888) (xy 396.111995 -91.559888)
			(xy 396.11597 -91.449847) (xy 396.127876 -91.34038) (xy 396.147649 -91.232057) (xy 396.175187 -91.125443)
			(xy 396.210346 -91.021095) (xy 396.252943 -90.919555) (xy 396.302756 -90.821354) (xy 396.359525 -90.727003)
			(xy 396.422954 -90.636994) (xy 396.492713 -90.551797) (xy 396.568437 -90.471856) (xy 396.649733 -90.397587)
			(xy 396.736175 -90.329378) (xy 396.827314 -90.267584) (xy 396.922675 -90.212528) (xy 397.021759 -90.164496)
			(xy 397.124052 -90.123739) (xy 397.229018 -90.090469) (xy 397.336111 -90.064861) (xy 397.444774 -90.047047)
			(xy 397.554438 -90.03712) (xy 397.664533 -90.035132) (xy 397.774484 -90.041093) (xy 397.883718 -90.054973)
			(xy 397.991667 -90.076698) (xy 398.097766 -90.106157) (xy 398.201463 -90.143194) (xy 398.302217 -90.187617)
			(xy 398.399503 -90.239195) (xy 398.492813 -90.297658) (xy 398.581662 -90.362702) (xy 398.665586 -90.433987)
			(xy 398.744147 -90.511143) (xy 398.816936 -90.593766) (xy 398.883573 -90.681426) (xy 398.943711 -90.773666)
			(xy 398.997037 -90.870005) (xy 399.043272 -90.96994) (xy 399.082176 -91.072952) (xy 399.113545 -91.178502)
			(xy 399.137216 -91.28604) (xy 399.153065 -91.395006) (xy 399.161011 -91.504832) (xy 399.161508 -91.559888)
			(xy 399.161011 -91.614944) (xy 399.153065 -91.72477) (xy 399.137216 -91.833736) (xy 399.113545 -91.941274)
			(xy 399.082176 -92.046824) (xy 399.043272 -92.149836) (xy 398.997037 -92.249771) (xy 398.943711 -92.34611)
			(xy 398.883573 -92.43835) (xy 398.816936 -92.52601) (xy 398.744147 -92.608633) (xy 398.665586 -92.685789)
			(xy 398.581662 -92.757074) (xy 398.492813 -92.822118) (xy 398.399503 -92.880581) (xy 398.302217 -92.932159)
			(xy 398.201463 -92.976582) (xy 398.097766 -93.013619) (xy 397.991667 -93.043078) (xy 397.883718 -93.064803)
			(xy 397.774484 -93.078683) (xy 397.664533 -93.084644) (xy 397.554438 -93.082656) (xy 397.444774 -93.072729)
			(xy 397.336111 -93.054915) (xy 397.229018 -93.029307) (xy 397.124052 -92.996037) (xy 397.021759 -92.95528)
			(xy 396.922675 -92.907248) (xy 396.827314 -92.852192) (xy 396.736175 -92.790398) (xy 396.649733 -92.722189)
			(xy 396.568437 -92.64792) (xy 396.492713 -92.567979) (xy 396.422954 -92.482782) (xy 396.359525 -92.392773)
			(xy 396.302756 -92.298422) (xy 396.252943 -92.200221) (xy 396.210346 -92.098681) (xy 396.175187 -91.994333)
			(xy 396.147649 -91.887719) (xy 396.127876 -91.779396) (xy 396.11597 -91.669929) (xy 396.111995 -91.559888)
			(xy 379.603508 -91.559888) (xy 379.603011 -91.614944) (xy 379.595065 -91.72477) (xy 379.579216 -91.833736)
			(xy 379.555545 -91.941274) (xy 379.524176 -92.046824) (xy 379.485272 -92.149836) (xy 379.439037 -92.249771)
			(xy 379.385711 -92.34611) (xy 379.325573 -92.43835) (xy 379.258936 -92.52601) (xy 379.186147 -92.608633)
			(xy 379.107586 -92.685789) (xy 379.023662 -92.757074) (xy 378.934813 -92.822118) (xy 378.841503 -92.880581)
			(xy 378.744217 -92.932159) (xy 378.643463 -92.976582) (xy 378.539766 -93.013619) (xy 378.433667 -93.043078)
			(xy 378.325718 -93.064803) (xy 378.216484 -93.078683) (xy 378.106533 -93.084644) (xy 377.996438 -93.082656)
			(xy 377.886774 -93.072729) (xy 377.778111 -93.054915) (xy 377.671018 -93.029307) (xy 377.566052 -92.996037)
			(xy 377.463759 -92.95528) (xy 377.364675 -92.907248) (xy 377.269314 -92.852192) (xy 377.178175 -92.790398)
			(xy 377.091733 -92.722189) (xy 377.010437 -92.64792) (xy 376.934713 -92.567979) (xy 376.864954 -92.482782)
			(xy 376.801525 -92.392773) (xy 376.744756 -92.298422) (xy 376.694943 -92.200221) (xy 376.652346 -92.098681)
			(xy 376.617187 -91.994333) (xy 376.589649 -91.887719) (xy 376.569876 -91.779396) (xy 376.55797 -91.669929)
			(xy 376.553995 -91.559888) (xy 358.88422 -91.559888) (xy 355.356414 -95.087694) (xy 355.356414 -99.06)
			(xy 377.061994 -99.06) (xy 377.065974 -98.970117) (xy 377.077882 -98.880937) (xy 377.097625 -98.793159)
			(xy 377.125049 -98.707469) (xy 377.159938 -98.624538) (xy 377.202021 -98.545016) (xy 377.250967 -98.469523)
			(xy 377.306394 -98.398652) (xy 377.367867 -98.332957) (xy 377.434906 -98.272952) (xy 377.506986 -98.219107)
			(xy 377.583542 -98.171843) (xy 377.663977 -98.13153) (xy 377.747659 -98.098483) (xy 377.833934 -98.072962)
			(xy 377.922128 -98.055166) (xy 378.011549 -98.045233) (xy 378.101498 -98.043243) (xy 378.191271 -98.04921)
			(xy 378.280166 -98.063088) (xy 378.367486 -98.084768) (xy 378.452548 -98.114081) (xy 378.534687 -98.150797)
			(xy 378.613259 -98.194628) (xy 378.68765 -98.245232) (xy 378.757277 -98.302213) (xy 378.821596 -98.365125)
			(xy 378.880104 -98.433475) (xy 378.932341 -98.506728) (xy 378.9779 -98.584311) (xy 379.016424 -98.665618)
			(xy 379.047611 -98.750011) (xy 379.071218 -98.83683) (xy 379.087059 -98.925395) (xy 379.095011 -99.015014)
			(xy 379.095508 -99.06) (xy 396.619994 -99.06) (xy 396.623974 -98.970117) (xy 396.635882 -98.880937)
			(xy 396.655625 -98.793159) (xy 396.683049 -98.707469) (xy 396.717938 -98.624538) (xy 396.760021 -98.545016)
			(xy 396.808967 -98.469523) (xy 396.864394 -98.398652) (xy 396.925867 -98.332957) (xy 396.992906 -98.272952)
			(xy 397.064986 -98.219107) (xy 397.141542 -98.171843) (xy 397.221977 -98.13153) (xy 397.305659 -98.098483)
			(xy 397.391934 -98.072962) (xy 397.480128 -98.055166) (xy 397.569549 -98.045233) (xy 397.659498 -98.043243)
			(xy 397.749271 -98.04921) (xy 397.838166 -98.063088) (xy 397.925486 -98.084768) (xy 398.010548 -98.114081)
			(xy 398.092687 -98.150797) (xy 398.171259 -98.194628) (xy 398.24565 -98.245232) (xy 398.315277 -98.302213)
			(xy 398.379596 -98.365125) (xy 398.438104 -98.433475) (xy 398.490341 -98.506728) (xy 398.5359 -98.584311)
			(xy 398.574424 -98.665618) (xy 398.605611 -98.750011) (xy 398.629218 -98.83683) (xy 398.645059 -98.925395)
			(xy 398.653011 -99.015014) (xy 398.653508 -99.06) (xy 398.653011 -99.104986) (xy 398.645059 -99.194605)
			(xy 398.629218 -99.28317) (xy 398.605611 -99.369989) (xy 398.574424 -99.454382) (xy 398.5359 -99.535689)
			(xy 398.490341 -99.613272) (xy 398.438104 -99.686525) (xy 398.379596 -99.754875) (xy 398.315277 -99.817787)
			(xy 398.24565 -99.874768) (xy 398.171259 -99.925372) (xy 398.092687 -99.969203) (xy 398.010548 -100.005919)
			(xy 397.925486 -100.035232) (xy 397.838166 -100.056912) (xy 397.749271 -100.07079) (xy 397.659498 -100.076757)
			(xy 397.569549 -100.074767) (xy 397.480128 -100.064834) (xy 397.391934 -100.047038) (xy 397.305659 -100.021517)
			(xy 397.221977 -99.98847) (xy 397.141542 -99.948157) (xy 397.064986 -99.900893) (xy 396.992906 -99.847048)
			(xy 396.925867 -99.787043) (xy 396.864394 -99.721348) (xy 396.808967 -99.650477) (xy 396.760021 -99.574984)
			(xy 396.717938 -99.495462) (xy 396.683049 -99.412531) (xy 396.655625 -99.326841) (xy 396.635882 -99.239063)
			(xy 396.623974 -99.149883) (xy 396.619994 -99.06) (xy 379.095508 -99.06) (xy 379.095011 -99.104986)
			(xy 379.087059 -99.194605) (xy 379.071218 -99.28317) (xy 379.047611 -99.369989) (xy 379.016424 -99.454382)
			(xy 378.9779 -99.535689) (xy 378.932341 -99.613272) (xy 378.880104 -99.686525) (xy 378.821596 -99.754875)
			(xy 378.757277 -99.817787) (xy 378.68765 -99.874768) (xy 378.613259 -99.925372) (xy 378.534687 -99.969203)
			(xy 378.452548 -100.005919) (xy 378.367486 -100.035232) (xy 378.280166 -100.056912) (xy 378.191271 -100.07079)
			(xy 378.101498 -100.076757) (xy 378.011549 -100.074767) (xy 377.922128 -100.064834) (xy 377.833934 -100.047038)
			(xy 377.747659 -100.021517) (xy 377.663977 -99.98847) (xy 377.583542 -99.948157) (xy 377.506986 -99.900893)
			(xy 377.434906 -99.847048) (xy 377.367867 -99.787043) (xy 377.306394 -99.721348) (xy 377.250967 -99.650477)
			(xy 377.202021 -99.574984) (xy 377.159938 -99.495462) (xy 377.125049 -99.412531) (xy 377.097625 -99.326841)
			(xy 377.077882 -99.239063) (xy 377.065974 -99.149883) (xy 377.061994 -99.06) (xy 355.356414 -99.06)
			(xy 355.356414 -107.758738) (xy 355.363264 -107.766134) (xy 355.370998 -107.784734) (xy 355.3714 -107.794806)
			(xy 355.3714 -111.879888) (xy 376.553995 -111.879888) (xy 376.55797 -111.769847) (xy 376.569876 -111.66038)
			(xy 376.589649 -111.552057) (xy 376.617187 -111.445443) (xy 376.652346 -111.341095) (xy 376.694943 -111.239555)
			(xy 376.744756 -111.141354) (xy 376.801525 -111.047003) (xy 376.864954 -110.956994) (xy 376.934713 -110.871797)
			(xy 377.010437 -110.791856) (xy 377.091733 -110.717587) (xy 377.178175 -110.649378) (xy 377.269314 -110.587584)
			(xy 377.364675 -110.532528) (xy 377.463759 -110.484496) (xy 377.566052 -110.443739) (xy 377.671018 -110.410469)
			(xy 377.778111 -110.384861) (xy 377.886774 -110.367047) (xy 377.996438 -110.35712) (xy 378.106533 -110.355132)
			(xy 378.216484 -110.361093) (xy 378.325718 -110.374973) (xy 378.433667 -110.396698) (xy 378.539766 -110.426157)
			(xy 378.643463 -110.463194) (xy 378.744217 -110.507617) (xy 378.841503 -110.559195) (xy 378.934813 -110.617658)
			(xy 379.023662 -110.682702) (xy 379.107586 -110.753987) (xy 379.186147 -110.831143) (xy 379.258936 -110.913766)
			(xy 379.325573 -111.001426) (xy 379.385711 -111.093666) (xy 379.439037 -111.190005) (xy 379.485272 -111.28994)
			(xy 379.524176 -111.392952) (xy 379.555545 -111.498502) (xy 379.579216 -111.60604) (xy 379.595065 -111.715006)
			(xy 379.603011 -111.824832) (xy 379.603508 -111.879888) (xy 396.111995 -111.879888) (xy 396.11597 -111.769847)
			(xy 396.127876 -111.66038) (xy 396.147649 -111.552057) (xy 396.175187 -111.445443) (xy 396.210346 -111.341095)
			(xy 396.252943 -111.239555) (xy 396.302756 -111.141354) (xy 396.359525 -111.047003) (xy 396.422954 -110.956994)
			(xy 396.492713 -110.871797) (xy 396.568437 -110.791856) (xy 396.649733 -110.717587) (xy 396.736175 -110.649378)
			(xy 396.827314 -110.587584) (xy 396.922675 -110.532528) (xy 397.021759 -110.484496) (xy 397.124052 -110.443739)
			(xy 397.229018 -110.410469) (xy 397.336111 -110.384861) (xy 397.444774 -110.367047) (xy 397.554438 -110.35712)
			(xy 397.664533 -110.355132) (xy 397.774484 -110.361093) (xy 397.883718 -110.374973) (xy 397.991667 -110.396698)
			(xy 398.097766 -110.426157) (xy 398.201463 -110.463194) (xy 398.302217 -110.507617) (xy 398.399503 -110.559195)
			(xy 398.492813 -110.617658) (xy 398.581662 -110.682702) (xy 398.665586 -110.753987) (xy 398.744147 -110.831143)
			(xy 398.816936 -110.913766) (xy 398.883573 -111.001426) (xy 398.943711 -111.093666) (xy 398.997037 -111.190005)
			(xy 399.043272 -111.28994) (xy 399.082176 -111.392952) (xy 399.113545 -111.498502) (xy 399.137216 -111.60604)
			(xy 399.153065 -111.715006) (xy 399.161011 -111.824832) (xy 399.161508 -111.879888) (xy 399.161011 -111.934944)
			(xy 399.153065 -112.04477) (xy 399.137216 -112.153736) (xy 399.113545 -112.261274) (xy 399.082176 -112.366824)
			(xy 399.043272 -112.469836) (xy 398.997037 -112.569771) (xy 398.943711 -112.66611) (xy 398.883573 -112.75835)
			(xy 398.816936 -112.84601) (xy 398.744147 -112.928633) (xy 398.665586 -113.005789) (xy 398.581662 -113.077074)
			(xy 398.492813 -113.142118) (xy 398.399503 -113.200581) (xy 398.302217 -113.252159) (xy 398.201463 -113.296582)
			(xy 398.097766 -113.333619) (xy 397.991667 -113.363078) (xy 397.883718 -113.384803) (xy 397.774484 -113.398683)
			(xy 397.664533 -113.404644) (xy 397.554438 -113.402656) (xy 397.444774 -113.392729) (xy 397.336111 -113.374915)
			(xy 397.229018 -113.349307) (xy 397.124052 -113.316037) (xy 397.021759 -113.27528) (xy 396.922675 -113.227248)
			(xy 396.827314 -113.172192) (xy 396.736175 -113.110398) (xy 396.649733 -113.042189) (xy 396.568437 -112.96792)
			(xy 396.492713 -112.887979) (xy 396.422954 -112.802782) (xy 396.359525 -112.712773) (xy 396.302756 -112.618422)
			(xy 396.252943 -112.520221) (xy 396.210346 -112.418681) (xy 396.175187 -112.314333) (xy 396.147649 -112.207719)
			(xy 396.127876 -112.099396) (xy 396.11597 -111.989929) (xy 396.111995 -111.879888) (xy 379.603508 -111.879888)
			(xy 379.603011 -111.934944) (xy 379.595065 -112.04477) (xy 379.579216 -112.153736) (xy 379.555545 -112.261274)
			(xy 379.524176 -112.366824) (xy 379.485272 -112.469836) (xy 379.439037 -112.569771) (xy 379.385711 -112.66611)
			(xy 379.325573 -112.75835) (xy 379.258936 -112.84601) (xy 379.186147 -112.928633) (xy 379.107586 -113.005789)
			(xy 379.023662 -113.077074) (xy 378.934813 -113.142118) (xy 378.841503 -113.200581) (xy 378.744217 -113.252159)
			(xy 378.643463 -113.296582) (xy 378.539766 -113.333619) (xy 378.433667 -113.363078) (xy 378.325718 -113.384803)
			(xy 378.216484 -113.398683) (xy 378.106533 -113.404644) (xy 377.996438 -113.402656) (xy 377.886774 -113.392729)
			(xy 377.778111 -113.374915) (xy 377.671018 -113.349307) (xy 377.566052 -113.316037) (xy 377.463759 -113.27528)
			(xy 377.364675 -113.227248) (xy 377.269314 -113.172192) (xy 377.178175 -113.110398) (xy 377.091733 -113.042189)
			(xy 377.010437 -112.96792) (xy 376.934713 -112.887979) (xy 376.864954 -112.802782) (xy 376.801525 -112.712773)
			(xy 376.744756 -112.618422) (xy 376.694943 -112.520221) (xy 376.652346 -112.418681) (xy 376.617187 -112.314333)
			(xy 376.589649 -112.207719) (xy 376.569876 -112.099396) (xy 376.55797 -111.989929) (xy 376.553995 -111.879888)
			(xy 355.3714 -111.879888) (xy 355.3714 -119.38) (xy 377.061994 -119.38) (xy 377.065974 -119.290117)
			(xy 377.077882 -119.200937) (xy 377.097625 -119.113159) (xy 377.125049 -119.027469) (xy 377.159938 -118.944538)
			(xy 377.202021 -118.865016) (xy 377.250967 -118.789523) (xy 377.306394 -118.718652) (xy 377.367867 -118.652957)
			(xy 377.434906 -118.592952) (xy 377.506986 -118.539107) (xy 377.583542 -118.491843) (xy 377.663977 -118.45153)
			(xy 377.747659 -118.418483) (xy 377.833934 -118.392962) (xy 377.922128 -118.375166) (xy 378.011549 -118.365233)
			(xy 378.101498 -118.363243) (xy 378.191271 -118.36921) (xy 378.280166 -118.383088) (xy 378.367486 -118.404768)
			(xy 378.452548 -118.434081) (xy 378.534687 -118.470797) (xy 378.613259 -118.514628) (xy 378.68765 -118.565232)
			(xy 378.757277 -118.622213) (xy 378.821596 -118.685125) (xy 378.880104 -118.753475) (xy 378.932341 -118.826728)
			(xy 378.9779 -118.904311) (xy 379.016424 -118.985618) (xy 379.047611 -119.070011) (xy 379.071218 -119.15683)
			(xy 379.087059 -119.245395) (xy 379.095011 -119.335014) (xy 379.095508 -119.38) (xy 396.619994 -119.38)
			(xy 396.623974 -119.290117) (xy 396.635882 -119.200937) (xy 396.655625 -119.113159) (xy 396.683049 -119.027469)
			(xy 396.717938 -118.944538) (xy 396.760021 -118.865016) (xy 396.808967 -118.789523) (xy 396.864394 -118.718652)
			(xy 396.925867 -118.652957) (xy 396.992906 -118.592952) (xy 397.064986 -118.539107) (xy 397.141542 -118.491843)
			(xy 397.221977 -118.45153) (xy 397.305659 -118.418483) (xy 397.391934 -118.392962) (xy 397.480128 -118.375166)
			(xy 397.569549 -118.365233) (xy 397.659498 -118.363243) (xy 397.749271 -118.36921) (xy 397.838166 -118.383088)
			(xy 397.925486 -118.404768) (xy 398.010548 -118.434081) (xy 398.092687 -118.470797) (xy 398.171259 -118.514628)
			(xy 398.24565 -118.565232) (xy 398.315277 -118.622213) (xy 398.379596 -118.685125) (xy 398.438104 -118.753475)
			(xy 398.490341 -118.826728) (xy 398.5359 -118.904311) (xy 398.574424 -118.985618) (xy 398.605611 -119.070011)
			(xy 398.629218 -119.15683) (xy 398.645059 -119.245395) (xy 398.653011 -119.335014) (xy 398.653508 -119.38)
			(xy 398.653011 -119.424986) (xy 398.645059 -119.514605) (xy 398.629218 -119.60317) (xy 398.605611 -119.689989)
			(xy 398.574424 -119.774382) (xy 398.5359 -119.855689) (xy 398.490341 -119.933272) (xy 398.438104 -120.006525)
			(xy 398.379596 -120.074875) (xy 398.315277 -120.137787) (xy 398.24565 -120.194768) (xy 398.171259 -120.245372)
			(xy 398.092687 -120.289203) (xy 398.010548 -120.325919) (xy 397.925486 -120.355232) (xy 397.838166 -120.376912)
			(xy 397.749271 -120.39079) (xy 397.659498 -120.396757) (xy 397.569549 -120.394767) (xy 397.480128 -120.384834)
			(xy 397.391934 -120.367038) (xy 397.305659 -120.341517) (xy 397.221977 -120.30847) (xy 397.141542 -120.268157)
			(xy 397.064986 -120.220893) (xy 396.992906 -120.167048) (xy 396.925867 -120.107043) (xy 396.864394 -120.041348)
			(xy 396.808967 -119.970477) (xy 396.760021 -119.894984) (xy 396.717938 -119.815462) (xy 396.683049 -119.732531)
			(xy 396.655625 -119.646841) (xy 396.635882 -119.559063) (xy 396.623974 -119.469883) (xy 396.619994 -119.38)
			(xy 379.095508 -119.38) (xy 379.095011 -119.424986) (xy 379.087059 -119.514605) (xy 379.071218 -119.60317)
			(xy 379.047611 -119.689989) (xy 379.016424 -119.774382) (xy 378.9779 -119.855689) (xy 378.932341 -119.933272)
			(xy 378.880104 -120.006525) (xy 378.821596 -120.074875) (xy 378.757277 -120.137787) (xy 378.68765 -120.194768)
			(xy 378.613259 -120.245372) (xy 378.534687 -120.289203) (xy 378.452548 -120.325919) (xy 378.367486 -120.355232)
			(xy 378.280166 -120.376912) (xy 378.191271 -120.39079) (xy 378.101498 -120.396757) (xy 378.011549 -120.394767)
			(xy 377.922128 -120.384834) (xy 377.833934 -120.367038) (xy 377.747659 -120.341517) (xy 377.663977 -120.30847)
			(xy 377.583542 -120.268157) (xy 377.506986 -120.220893) (xy 377.434906 -120.167048) (xy 377.367867 -120.107043)
			(xy 377.306394 -120.041348) (xy 377.250967 -119.970477) (xy 377.202021 -119.894984) (xy 377.159938 -119.815462)
			(xy 377.125049 -119.732531) (xy 377.097625 -119.646841) (xy 377.077882 -119.559063) (xy 377.065974 -119.469883)
			(xy 377.061994 -119.38) (xy 355.3714 -119.38) (xy 355.3714 -132.199888) (xy 376.553995 -132.199888)
			(xy 376.55797 -132.089847) (xy 376.569876 -131.98038) (xy 376.589649 -131.872057) (xy 376.617187 -131.765443)
			(xy 376.652346 -131.661095) (xy 376.694943 -131.559555) (xy 376.744756 -131.461354) (xy 376.801525 -131.367003)
			(xy 376.864954 -131.276994) (xy 376.934713 -131.191797) (xy 377.010437 -131.111856) (xy 377.091733 -131.037587)
			(xy 377.178175 -130.969378) (xy 377.269314 -130.907584) (xy 377.364675 -130.852528) (xy 377.463759 -130.804496)
			(xy 377.566052 -130.763739) (xy 377.671018 -130.730469) (xy 377.778111 -130.704861) (xy 377.886774 -130.687047)
			(xy 377.996438 -130.67712) (xy 378.106533 -130.675132) (xy 378.216484 -130.681093) (xy 378.325718 -130.694973)
			(xy 378.433667 -130.716698) (xy 378.539766 -130.746157) (xy 378.643463 -130.783194) (xy 378.744217 -130.827617)
			(xy 378.841503 -130.879195) (xy 378.934813 -130.937658) (xy 379.023662 -131.002702) (xy 379.107586 -131.073987)
			(xy 379.186147 -131.151143) (xy 379.258936 -131.233766) (xy 379.325573 -131.321426) (xy 379.385711 -131.413666)
			(xy 379.439037 -131.510005) (xy 379.485272 -131.60994) (xy 379.524176 -131.712952) (xy 379.555545 -131.818502)
			(xy 379.579216 -131.92604) (xy 379.595065 -132.035006) (xy 379.603011 -132.144832) (xy 379.603508 -132.199888)
			(xy 396.111995 -132.199888) (xy 396.11597 -132.089847) (xy 396.127876 -131.98038) (xy 396.147649 -131.872057)
			(xy 396.175187 -131.765443) (xy 396.210346 -131.661095) (xy 396.252943 -131.559555) (xy 396.302756 -131.461354)
			(xy 396.359525 -131.367003) (xy 396.422954 -131.276994) (xy 396.492713 -131.191797) (xy 396.568437 -131.111856)
			(xy 396.649733 -131.037587) (xy 396.736175 -130.969378) (xy 396.827314 -130.907584) (xy 396.922675 -130.852528)
			(xy 397.021759 -130.804496) (xy 397.124052 -130.763739) (xy 397.229018 -130.730469) (xy 397.336111 -130.704861)
			(xy 397.444774 -130.687047) (xy 397.554438 -130.67712) (xy 397.664533 -130.675132) (xy 397.774484 -130.681093)
			(xy 397.883718 -130.694973) (xy 397.991667 -130.716698) (xy 398.097766 -130.746157) (xy 398.201463 -130.783194)
			(xy 398.302217 -130.827617) (xy 398.399503 -130.879195) (xy 398.492813 -130.937658) (xy 398.581662 -131.002702)
			(xy 398.665586 -131.073987) (xy 398.744147 -131.151143) (xy 398.816936 -131.233766) (xy 398.883573 -131.321426)
			(xy 398.943711 -131.413666) (xy 398.997037 -131.510005) (xy 399.043272 -131.60994) (xy 399.082176 -131.712952)
			(xy 399.113545 -131.818502) (xy 399.137216 -131.92604) (xy 399.153065 -132.035006) (xy 399.161011 -132.144832)
			(xy 399.161508 -132.199888) (xy 399.161011 -132.254944) (xy 399.153065 -132.36477) (xy 399.137216 -132.473736)
			(xy 399.113545 -132.581274) (xy 399.082176 -132.686824) (xy 399.043272 -132.789836) (xy 398.997037 -132.889771)
			(xy 398.943711 -132.98611) (xy 398.883573 -133.07835) (xy 398.816936 -133.16601) (xy 398.744147 -133.248633)
			(xy 398.665586 -133.325789) (xy 398.581662 -133.397074) (xy 398.492813 -133.462118) (xy 398.399503 -133.520581)
			(xy 398.302217 -133.572159) (xy 398.201463 -133.616582) (xy 398.097766 -133.653619) (xy 397.991667 -133.683078)
			(xy 397.883718 -133.704803) (xy 397.774484 -133.718683) (xy 397.664533 -133.724644) (xy 397.554438 -133.722656)
			(xy 397.444774 -133.712729) (xy 397.336111 -133.694915) (xy 397.229018 -133.669307) (xy 397.124052 -133.636037)
			(xy 397.021759 -133.59528) (xy 396.922675 -133.547248) (xy 396.827314 -133.492192) (xy 396.736175 -133.430398)
			(xy 396.649733 -133.362189) (xy 396.568437 -133.28792) (xy 396.492713 -133.207979) (xy 396.422954 -133.122782)
			(xy 396.359525 -133.032773) (xy 396.302756 -132.938422) (xy 396.252943 -132.840221) (xy 396.210346 -132.738681)
			(xy 396.175187 -132.634333) (xy 396.147649 -132.527719) (xy 396.127876 -132.419396) (xy 396.11597 -132.309929)
			(xy 396.111995 -132.199888) (xy 379.603508 -132.199888) (xy 379.603011 -132.254944) (xy 379.595065 -132.36477)
			(xy 379.579216 -132.473736) (xy 379.555545 -132.581274) (xy 379.524176 -132.686824) (xy 379.485272 -132.789836)
			(xy 379.439037 -132.889771) (xy 379.385711 -132.98611) (xy 379.325573 -133.07835) (xy 379.258936 -133.16601)
			(xy 379.186147 -133.248633) (xy 379.107586 -133.325789) (xy 379.023662 -133.397074) (xy 378.934813 -133.462118)
			(xy 378.841503 -133.520581) (xy 378.744217 -133.572159) (xy 378.643463 -133.616582) (xy 378.539766 -133.653619)
			(xy 378.433667 -133.683078) (xy 378.325718 -133.704803) (xy 378.216484 -133.718683) (xy 378.106533 -133.724644)
			(xy 377.996438 -133.722656) (xy 377.886774 -133.712729) (xy 377.778111 -133.694915) (xy 377.671018 -133.669307)
			(xy 377.566052 -133.636037) (xy 377.463759 -133.59528) (xy 377.364675 -133.547248) (xy 377.269314 -133.492192)
			(xy 377.178175 -133.430398) (xy 377.091733 -133.362189) (xy 377.010437 -133.28792) (xy 376.934713 -133.207979)
			(xy 376.864954 -133.122782) (xy 376.801525 -133.032773) (xy 376.744756 -132.938422) (xy 376.694943 -132.840221)
			(xy 376.652346 -132.738681) (xy 376.617187 -132.634333) (xy 376.589649 -132.527719) (xy 376.569876 -132.419396)
			(xy 376.55797 -132.309929) (xy 376.553995 -132.199888) (xy 355.3714 -132.199888) (xy 355.3714 -135.138414)
			(xy 355.371826 -135.148483) (xy 355.379544 -135.167084) (xy 355.386386 -135.174482) (xy 355.872796 -135.660892)
			(xy 363.013498 -135.660892) (xy 366.647984 -139.295378) (xy 366.647984 -139.7) (xy 377.061994 -139.7)
			(xy 377.065974 -139.610117) (xy 377.077882 -139.520937) (xy 377.097625 -139.433159) (xy 377.125049 -139.347469)
			(xy 377.159938 -139.264538) (xy 377.202021 -139.185016) (xy 377.250967 -139.109523) (xy 377.306394 -139.038652)
			(xy 377.367867 -138.972957) (xy 377.434906 -138.912952) (xy 377.506986 -138.859107) (xy 377.583542 -138.811843)
			(xy 377.663977 -138.77153) (xy 377.747659 -138.738483) (xy 377.833934 -138.712962) (xy 377.922128 -138.695166)
			(xy 378.011549 -138.685233) (xy 378.101498 -138.683243) (xy 378.191271 -138.68921) (xy 378.280166 -138.703088)
			(xy 378.367486 -138.724768) (xy 378.452548 -138.754081) (xy 378.534687 -138.790797) (xy 378.613259 -138.834628)
			(xy 378.68765 -138.885232) (xy 378.757277 -138.942213) (xy 378.821596 -139.005125) (xy 378.880104 -139.073475)
			(xy 378.932341 -139.146728) (xy 378.9779 -139.224311) (xy 379.016424 -139.305618) (xy 379.047611 -139.390011)
			(xy 379.071218 -139.47683) (xy 379.087059 -139.565395) (xy 379.095011 -139.655014) (xy 379.095508 -139.7)
			(xy 396.619994 -139.7) (xy 396.623974 -139.610117) (xy 396.635882 -139.520937) (xy 396.655625 -139.433159)
			(xy 396.683049 -139.347469) (xy 396.717938 -139.264538) (xy 396.760021 -139.185016) (xy 396.808967 -139.109523)
			(xy 396.864394 -139.038652) (xy 396.925867 -138.972957) (xy 396.992906 -138.912952) (xy 397.064986 -138.859107)
			(xy 397.141542 -138.811843) (xy 397.221977 -138.77153) (xy 397.305659 -138.738483) (xy 397.391934 -138.712962)
			(xy 397.480128 -138.695166) (xy 397.569549 -138.685233) (xy 397.659498 -138.683243) (xy 397.749271 -138.68921)
			(xy 397.838166 -138.703088) (xy 397.925486 -138.724768) (xy 398.010548 -138.754081) (xy 398.092687 -138.790797)
			(xy 398.171259 -138.834628) (xy 398.24565 -138.885232) (xy 398.315277 -138.942213) (xy 398.379596 -139.005125)
			(xy 398.438104 -139.073475) (xy 398.490341 -139.146728) (xy 398.5359 -139.224311) (xy 398.574424 -139.305618)
			(xy 398.605611 -139.390011) (xy 398.629218 -139.47683) (xy 398.645059 -139.565395) (xy 398.653011 -139.655014)
			(xy 398.653508 -139.7) (xy 398.653011 -139.744986) (xy 398.645059 -139.834605) (xy 398.629218 -139.92317)
			(xy 398.605611 -140.009989) (xy 398.574424 -140.094382) (xy 398.5359 -140.175689) (xy 398.490341 -140.253272)
			(xy 398.438104 -140.326525) (xy 398.379596 -140.394875) (xy 398.315277 -140.457787) (xy 398.24565 -140.514768)
			(xy 398.171259 -140.565372) (xy 398.092687 -140.609203) (xy 398.010548 -140.645919) (xy 397.925486 -140.675232)
			(xy 397.838166 -140.696912) (xy 397.749271 -140.71079) (xy 397.659498 -140.716757) (xy 397.569549 -140.714767)
			(xy 397.480128 -140.704834) (xy 397.391934 -140.687038) (xy 397.305659 -140.661517) (xy 397.221977 -140.62847)
			(xy 397.141542 -140.588157) (xy 397.064986 -140.540893) (xy 396.992906 -140.487048) (xy 396.925867 -140.427043)
			(xy 396.864394 -140.361348) (xy 396.808967 -140.290477) (xy 396.760021 -140.214984) (xy 396.717938 -140.135462)
			(xy 396.683049 -140.052531) (xy 396.655625 -139.966841) (xy 396.635882 -139.879063) (xy 396.623974 -139.789883)
			(xy 396.619994 -139.7) (xy 379.095508 -139.7) (xy 379.095011 -139.744986) (xy 379.087059 -139.834605)
			(xy 379.071218 -139.92317) (xy 379.047611 -140.009989) (xy 379.016424 -140.094382) (xy 378.9779 -140.175689)
			(xy 378.932341 -140.253272) (xy 378.880104 -140.326525) (xy 378.821596 -140.394875) (xy 378.757277 -140.457787)
			(xy 378.68765 -140.514768) (xy 378.613259 -140.565372) (xy 378.534687 -140.609203) (xy 378.452548 -140.645919)
			(xy 378.367486 -140.675232) (xy 378.280166 -140.696912) (xy 378.191271 -140.71079) (xy 378.101498 -140.716757)
			(xy 378.011549 -140.714767) (xy 377.922128 -140.704834) (xy 377.833934 -140.687038) (xy 377.747659 -140.661517)
			(xy 377.663977 -140.62847) (xy 377.583542 -140.588157) (xy 377.506986 -140.540893) (xy 377.434906 -140.487048)
			(xy 377.367867 -140.427043) (xy 377.306394 -140.361348) (xy 377.250967 -140.290477) (xy 377.202021 -140.214984)
			(xy 377.159938 -140.135462) (xy 377.125049 -140.052531) (xy 377.097625 -139.966841) (xy 377.077882 -139.879063)
			(xy 377.065974 -139.789883) (xy 377.061994 -139.7) (xy 366.647984 -139.7) (xy 366.647984 -150.664926)
			(xy 362.54817 -154.76474) (xy 362.54817 -159.684424) (xy 371.51385 -159.684424) (xy 371.51385 -159.575796)
			(xy 371.521779 -159.467458) (xy 371.537596 -159.359987) (xy 371.561215 -159.253958) (xy 371.592511 -159.149936)
			(xy 371.631316 -159.048475) (xy 371.677424 -158.950118) (xy 371.730588 -158.855389) (xy 371.790526 -158.764794)
			(xy 371.856916 -158.678815) (xy 371.929406 -158.597912) (xy 372.007607 -158.522516) (xy 372.091104 -158.45303)
			(xy 372.17945 -158.389823) (xy 372.272174 -158.333235) (xy 372.368782 -158.283565) (xy 372.468757 -158.24108)
			(xy 372.571567 -158.206007) (xy 372.676663 -158.178531) (xy 372.783484 -158.1588) (xy 372.89146 -158.146919)
			(xy 373.000016 -158.142952) (xy 373.108572 -158.146919) (xy 373.216548 -158.1588) (xy 373.323369 -158.178531)
			(xy 373.428465 -158.206007) (xy 373.531275 -158.24108) (xy 373.63125 -158.283565) (xy 373.727858 -158.333235)
			(xy 373.820582 -158.389823) (xy 373.908928 -158.45303) (xy 373.992425 -158.522516) (xy 374.070626 -158.597912)
			(xy 374.143116 -158.678815) (xy 374.209506 -158.764794) (xy 374.269444 -158.855389) (xy 374.322608 -158.950118)
			(xy 374.368716 -159.048475) (xy 374.407521 -159.149936) (xy 374.438817 -159.253958) (xy 374.462436 -159.359987)
			(xy 374.478253 -159.467458) (xy 374.486182 -159.575796) (xy 374.486678 -159.63011) (xy 374.486182 -159.684424)
			(xy 374.478253 -159.792762) (xy 374.462436 -159.900233) (xy 374.438817 -160.006262) (xy 374.407521 -160.110284)
			(xy 374.368716 -160.211745) (xy 374.322608 -160.310102) (xy 374.269444 -160.404831) (xy 374.209506 -160.495426)
			(xy 374.143116 -160.581405) (xy 374.070626 -160.662308) (xy 373.992425 -160.737704) (xy 373.908928 -160.80719)
			(xy 373.820582 -160.870397) (xy 373.727858 -160.926985) (xy 373.63125 -160.976655) (xy 373.531275 -161.01914)
			(xy 373.428465 -161.054213) (xy 373.323369 -161.081689) (xy 373.216548 -161.10142) (xy 373.108572 -161.113301)
			(xy 373.000016 -161.117268) (xy 372.89146 -161.113301) (xy 372.783484 -161.10142) (xy 372.676663 -161.081689)
			(xy 372.571567 -161.054213) (xy 372.468757 -161.01914) (xy 372.368782 -160.976655) (xy 372.272174 -160.926985)
			(xy 372.17945 -160.870397) (xy 372.091104 -160.80719) (xy 372.007607 -160.737704) (xy 371.929406 -160.662308)
			(xy 371.856916 -160.581405) (xy 371.790526 -160.495426) (xy 371.730588 -160.404831) (xy 371.677424 -160.310102)
			(xy 371.631316 -160.211745) (xy 371.592511 -160.110284) (xy 371.561215 -160.006262) (xy 371.537596 -159.900233)
			(xy 371.521779 -159.792762) (xy 371.51385 -159.684424) (xy 362.54817 -159.684424) (xy 362.54817 -161.484564)
			(xy 362.548673 -161.494616) (xy 362.55639 -161.513181) (xy 362.563156 -161.520632) (xy 362.698538 -161.656014)
			(xy 362.705934 -161.662864) (xy 362.724534 -161.670598) (xy 362.734606 -161.671) (xy 385.865116 -161.671)
			(xy 385.874275 -161.670568) (xy 385.891406 -161.664064) (xy 385.905187 -161.651987) (xy 385.90982 -161.644076)
			(xy 385.935868 -161.596174) (xy 385.994105 -161.503979) (xy 386.059053 -161.416382) (xy 386.130352 -161.333872)
			(xy 386.207603 -161.256906) (xy 386.290378 -161.185914) (xy 386.378214 -161.121291) (xy 386.470625 -161.063397)
			(xy 386.567094 -161.012553) (xy 386.667086 -160.969042) (xy 386.770043 -160.933108) (xy 386.875393 -160.90495)
			(xy 386.982548 -160.884724) (xy 387.090914 -160.872543) (xy 387.199886 -160.868475) (xy 387.308858 -160.872543)
			(xy 387.417224 -160.884724) (xy 387.524379 -160.90495) (xy 387.629729 -160.933108) (xy 387.732686 -160.969042)
			(xy 387.832678 -161.012553) (xy 387.929147 -161.063397) (xy 388.021558 -161.121291) (xy 388.109394 -161.185914)
			(xy 388.192169 -161.256906) (xy 388.26942 -161.333872) (xy 388.340719 -161.416382) (xy 388.405667 -161.503979)
			(xy 388.463904 -161.596174) (xy 388.489952 -161.644076) (xy 388.494582 -161.651999) (xy 388.508332 -161.664131)
			(xy 388.525487 -161.670606) (xy 388.534656 -161.671) (xy 396.345918 -161.671) (xy 396.355987 -161.671427)
			(xy 396.374586 -161.679146) (xy 396.381986 -161.685986) (xy 396.733014 -162.037014) (xy 396.739868 -162.044409)
			(xy 396.74761 -162.063008) (xy 396.748 -162.073082) (xy 396.748 -168.899078) (xy 396.75562 -168.917874)
			(xy 396.762986 -168.924986) (xy 397.368014 -169.530014) (xy 397.375409 -169.536868) (xy 397.394008 -169.54461)
			(xy 397.404082 -169.545) (xy 400.801078 -169.545)
		)
		(stroke
			(width 0)
			(type solid)
		)
		(fill yes)
		(layer "In2.Cu")
		(net "P52V_HS1")
	)
	(gr_poly
		(pts
			(xy 413.985964 -37.973) (xy 413.99599 -37.972587) (xy 414.014519 -37.964923) (xy 414.028703 -37.95075)
			(xy 414.03638 -37.932226) (xy 414.036764 -37.9222) (xy 414.036764 -29.469334) (xy 414.036623 -29.462393)
			(xy 414.033017 -29.448991) (xy 414.029652 -29.442918) (xy 414.016583 -29.420502) (xy 413.995968 -29.372885)
			(xy 413.982006 -29.322911) (xy 413.974956 -29.271504) (xy 413.974534 -29.24556) (xy 413.97502 -29.218309)
			(xy 413.982776 -29.164361) (xy 413.998131 -29.112066) (xy 414.020773 -29.062489) (xy 414.050239 -29.016639)
			(xy 414.08593 -28.975448) (xy 414.127121 -28.939757) (xy 414.172971 -28.910291) (xy 414.222548 -28.887649)
			(xy 414.274843 -28.872294) (xy 414.328791 -28.864538) (xy 414.383293 -28.864538) (xy 414.437241 -28.872294)
			(xy 414.489536 -28.887649) (xy 414.539113 -28.910291) (xy 414.584963 -28.939757) (xy 414.626154 -28.975448)
			(xy 414.661845 -29.016639) (xy 414.691311 -29.062489) (xy 414.694878 -29.0703) (xy 415.53638 -29.0703)
			(xy 415.53678 -29.032002) (xy 415.543509 -28.955703) (xy 415.556977 -28.8803) (xy 415.577077 -28.806389)
			(xy 415.589974 -28.770326) (xy 415.592748 -28.761779) (xy 415.592748 -28.743821) (xy 415.589974 -28.735274)
			(xy 415.577111 -28.6992) (xy 415.55703 -28.625287) (xy 415.543557 -28.54989) (xy 415.536799 -28.473596)
			(xy 415.53638 -28.4353) (xy 415.536912 -28.392875) (xy 415.545229 -28.308434) (xy 415.561782 -28.225214)
			(xy 415.586413 -28.144018) (xy 415.618883 -28.065627) (xy 415.658881 -27.990795) (xy 415.706021 -27.920245)
			(xy 415.759848 -27.854655) (xy 415.819846 -27.794656) (xy 415.885435 -27.740828) (xy 415.955985 -27.693687)
			(xy 416.030816 -27.653688) (xy 416.109206 -27.621217) (xy 416.190402 -27.596585) (xy 416.273622 -27.580031)
			(xy 416.358063 -27.571713) (xy 416.400488 -27.571192) (xy 416.444925 -27.571755) (xy 416.533329 -27.580888)
			(xy 416.620329 -27.599048) (xy 416.705004 -27.626043) (xy 416.786461 -27.661588) (xy 416.82543 -27.682952)
			(xy 416.833225 -27.686916) (xy 416.850449 -27.689875) (xy 416.867673 -27.686916) (xy 416.875468 -27.682952)
			(xy 416.910869 -27.663489) (xy 416.984613 -27.630488) (xy 417.061115 -27.604516) (xy 417.139709 -27.585801)
			(xy 417.219707 -27.574506) (xy 417.30041 -27.57073) (xy 417.381113 -27.574506) (xy 417.461111 -27.585801)
			(xy 417.539705 -27.604516) (xy 417.616207 -27.630488) (xy 417.689951 -27.663489) (xy 417.725352 -27.682952)
			(xy 417.733147 -27.686916) (xy 417.750371 -27.689875) (xy 417.767595 -27.686916) (xy 417.77539 -27.682952)
			(xy 417.814358 -27.661587) (xy 417.895814 -27.626037) (xy 417.980489 -27.599041) (xy 418.067489 -27.580885)
			(xy 418.155895 -27.57176) (xy 418.200332 -27.571192) (xy 418.244794 -27.571758) (xy 418.333247 -27.580887)
			(xy 418.420297 -27.599044) (xy 418.505023 -27.626039) (xy 418.586533 -27.661586) (xy 418.625528 -27.682952)
			(xy 418.63328 -27.686911) (xy 418.65042 -27.689871) (xy 418.66756 -27.686911) (xy 418.675312 -27.682952)
			(xy 418.714309 -27.661586) (xy 418.79581 -27.626015) (xy 418.880535 -27.59901) (xy 418.967588 -27.580857)
			(xy 419.056045 -27.571748) (xy 419.100508 -27.571192) (xy 419.141201 -27.571655) (xy 419.222227 -27.579308)
			(xy 419.302175 -27.594546) (xy 419.380335 -27.617234) (xy 419.456016 -27.64717) (xy 419.528547 -27.68409)
			(xy 419.597284 -27.727667) (xy 419.66162 -27.777513) (xy 419.720984 -27.833188) (xy 419.77485 -27.894198)
			(xy 419.822741 -27.960003) (xy 419.864232 -28.030019) (xy 419.898956 -28.103626) (xy 419.926605 -28.180172)
			(xy 419.946934 -28.258979) (xy 419.959763 -28.339348) (xy 419.962838 -28.379928) (xy 419.963854 -28.396438)
			(xy 419.984682 -28.421584) (xy 420.109396 -28.454858) (xy 420.139876 -28.443174) (xy 420.14902 -28.429458)
			(xy 420.173686 -28.393184) (xy 420.229069 -28.325149) (xy 420.29088 -28.262898) (xy 420.358521 -28.207036)
			(xy 420.431333 -28.158104) (xy 420.508609 -28.11658) (xy 420.589597 -28.082865) (xy 420.673512 -28.057288)
			(xy 420.759537 -28.040097) (xy 420.846837 -28.03146) (xy 420.8907 -28.030932) (xy 420.930473 -28.031376)
			(xy 421.009704 -28.038458) (xy 421.087984 -28.052592) (xy 421.164688 -28.073666) (xy 421.239201 -28.10151)
			(xy 421.275256 -28.118308) (xy 421.285757 -28.12264) (xy 421.308443 -28.12264) (xy 421.318944 -28.118308)
			(xy 421.355003 -28.101523) (xy 421.429521 -28.073695) (xy 421.506224 -28.052625) (xy 421.584501 -28.038481)
			(xy 421.663728 -28.031376) (xy 421.7035 -28.030932) (xy 421.744604 -28.031352) (xy 421.826462 -28.038938)
			(xy 421.907271 -28.054044) (xy 421.986341 -28.076542) (xy 422.062998 -28.10624) (xy 422.136588 -28.142885)
			(xy 422.206483 -28.186163) (xy 422.272086 -28.235706) (xy 422.332837 -28.291091) (xy 422.38822 -28.351845)
			(xy 422.43776 -28.41745) (xy 422.481035 -28.487347) (xy 422.517676 -28.560938) (xy 422.547371 -28.637597)
			(xy 422.569865 -28.716668) (xy 422.584968 -28.797477) (xy 422.59255 -28.879336) (xy 422.593008 -28.92044)
			(xy 422.592459 -28.965211) (xy 422.583464 -29.0543) (xy 422.565558 -29.142033) (xy 422.538924 -29.227521)
			(xy 422.521888 -29.268928) (xy 422.518299 -29.278512) (xy 422.518314 -29.298961) (xy 422.521888 -29.308552)
			(xy 422.538904 -29.349966) (xy 422.565538 -29.435453) (xy 422.583447 -29.523184) (xy 422.59245 -29.61227)
			(xy 422.593008 -29.65704) (xy 422.592572 -29.698143) (xy 422.584983 -29.779998) (xy 422.569874 -29.860804)
			(xy 422.547375 -29.939872) (xy 422.517676 -30.016526) (xy 422.481031 -30.090113) (xy 422.437753 -30.160005)
			(xy 422.388211 -30.225606) (xy 422.332827 -30.286355) (xy 422.272075 -30.341736) (xy 422.206472 -30.391275)
			(xy 422.136578 -30.43455) (xy 422.062989 -30.471192) (xy 421.986334 -30.500887) (xy 421.907266 -30.523384)
			(xy 421.826459 -30.538489) (xy 421.744603 -30.546073) (xy 421.7035 -30.546548) (xy 421.663727 -30.546106)
			(xy 421.584496 -30.539024) (xy 421.506216 -30.524889) (xy 421.429512 -30.503815) (xy 421.354999 -30.47597)
			(xy 421.318944 -30.459172) (xy 421.308443 -30.45484) (xy 421.285757 -30.45484) (xy 421.275256 -30.459172)
			(xy 421.239196 -30.475956) (xy 421.164678 -30.503784) (xy 421.087975 -30.524855) (xy 421.009699 -30.538999)
			(xy 420.930472 -30.546104) (xy 420.8907 -30.546548) (xy 420.849599 -30.546033) (xy 420.767747 -30.538449)
			(xy 420.686944 -30.523345) (xy 420.607879 -30.500849) (xy 420.531227 -30.471155) (xy 420.457642 -30.434515)
			(xy 420.387751 -30.391242) (xy 420.322151 -30.341705) (xy 420.261401 -30.286327) (xy 420.20602 -30.22558)
			(xy 420.15648 -30.159982) (xy 420.113204 -30.090093) (xy 420.076561 -30.01651) (xy 420.046863 -29.939859)
			(xy 420.024364 -29.860795) (xy 420.009257 -29.779993) (xy 420.001668 -29.698141) (xy 420.001192 -29.65704)
			(xy 420.001734 -29.612269) (xy 420.010731 -29.52318) (xy 420.028639 -29.435447) (xy 420.055276 -29.349959)
			(xy 420.072312 -29.308552) (xy 420.075855 -29.298955) (xy 420.07587 -29.278518) (xy 420.072312 -29.268928)
			(xy 420.066282 -29.25456) (xy 420.055102 -29.225471) (xy 420.04996 -29.210762) (xy 420.046358 -29.201852)
			(xy 420.03387 -29.187274) (xy 420.016893 -29.178317) (xy 419.997812 -29.176237) (xy 419.979304 -29.181327)
			(xy 419.963969 -29.192871) (xy 419.953959 -29.20925) (xy 419.951916 -29.218636) (xy 419.944587 -29.258254)
			(xy 419.923418 -29.335998) (xy 419.895104 -29.411435) (xy 419.859891 -29.483909) (xy 419.818085 -29.55279)
			(xy 419.770048 -29.617481) (xy 419.716199 -29.677419) (xy 419.657004 -29.732085) (xy 419.592978 -29.781004)
			(xy 419.524676 -29.82375) (xy 419.452692 -29.859953) (xy 419.37765 -29.889298) (xy 419.300203 -29.91153)
			(xy 419.221022 -29.926457) (xy 419.140796 -29.933949) (xy 419.100508 -29.934408) (xy 419.056047 -29.933824)
			(xy 418.967594 -29.9247) (xy 418.880545 -29.906546) (xy 418.795818 -29.879555) (xy 418.714308 -29.844013)
			(xy 418.675312 -29.822648) (xy 418.66756 -29.818689) (xy 418.65042 -29.815729) (xy 418.63328 -29.818689)
			(xy 418.625528 -29.822648) (xy 418.586544 -29.844038) (xy 418.505039 -29.879604) (xy 418.42031 -29.906604)
			(xy 418.333255 -29.924752) (xy 418.244796 -29.933855) (xy 418.200332 -29.934408) (xy 418.155895 -29.933836)
			(xy 418.067491 -29.924705) (xy 417.980492 -29.906547) (xy 417.895816 -29.879554) (xy 417.814359 -29.844011)
			(xy 417.77539 -29.822648) (xy 417.767611 -29.818624) (xy 417.750371 -29.815606) (xy 417.733131 -29.818624)
			(xy 417.725352 -29.822648) (xy 417.689951 -29.842111) (xy 417.616207 -29.875112) (xy 417.539705 -29.901084)
			(xy 417.461111 -29.919799) (xy 417.381113 -29.931094) (xy 417.30041 -29.93487) (xy 417.219707 -29.931094)
			(xy 417.139709 -29.919799) (xy 417.061115 -29.901084) (xy 416.984613 -29.875112) (xy 416.910869 -29.842111)
			(xy 416.875468 -29.822648) (xy 416.867689 -29.818624) (xy 416.850449 -29.815606) (xy 416.833209 -29.818624)
			(xy 416.82543 -29.822648) (xy 416.786457 -29.844005) (xy 416.705004 -29.879557) (xy 416.620329 -29.906554)
			(xy 416.53333 -29.924712) (xy 416.444925 -29.933839) (xy 416.400488 -29.934408) (xy 416.358062 -29.933899)
			(xy 416.27362 -29.925581) (xy 416.1904 -29.909026) (xy 416.109202 -29.884394) (xy 416.030811 -29.851923)
			(xy 415.955979 -29.811923) (xy 415.885428 -29.764782) (xy 415.819838 -29.710952) (xy 415.759839 -29.650953)
			(xy 415.706011 -29.585362) (xy 415.658871 -29.514811) (xy 415.618872 -29.439979) (xy 415.586402 -29.361586)
			(xy 415.561771 -29.280389) (xy 415.545217 -29.197168) (xy 415.5369 -29.112726) (xy 415.53638 -29.0703)
			(xy 414.694878 -29.0703) (xy 414.713953 -29.112066) (xy 414.729308 -29.164361) (xy 414.737064 -29.218309)
			(xy 414.73755 -29.24556) (xy 414.737091 -29.2715) (xy 414.730022 -29.322898) (xy 414.716062 -29.372867)
			(xy 414.695468 -29.420486) (xy 414.682432 -29.442918) (xy 414.679092 -29.449002) (xy 414.675477 -29.462396)
			(xy 414.67532 -29.469334) (xy 414.67532 -31.206854) (xy 416.669626 -31.206854) (xy 416.677383 -31.152898)
			(xy 416.69274 -31.100594) (xy 416.715384 -31.051008) (xy 416.744854 -31.00515) (xy 416.780552 -30.963953)
			(xy 416.821749 -30.928256) (xy 416.867607 -30.898785) (xy 416.917192 -30.87614) (xy 416.969496 -30.860783)
			(xy 417.023452 -30.853026) (xy 417.077964 -30.853028) (xy 417.13192 -30.860787) (xy 417.184223 -30.876146)
			(xy 417.233807 -30.898792) (xy 417.279664 -30.928265) (xy 417.32086 -30.963964) (xy 417.323879 -30.967448)
			(xy 418.169626 -30.967448) (xy 418.169626 -30.912952) (xy 418.177382 -30.859012) (xy 418.192735 -30.806724)
			(xy 418.215373 -30.757153) (xy 418.244835 -30.711308) (xy 418.280522 -30.670123) (xy 418.321707 -30.634436)
			(xy 418.367551 -30.604974) (xy 418.417122 -30.582335) (xy 418.46941 -30.566982) (xy 418.52335 -30.559226)
			(xy 418.550598 -30.55874) (xy 418.579258 -30.559274) (xy 418.635931 -30.567857) (xy 418.68031 -30.5816)
			(xy 423.239188 -30.5816) (xy 423.243218 -30.496999) (xy 423.255271 -30.413164) (xy 423.275239 -30.330855)
			(xy 423.302941 -30.250816) (xy 423.338125 -30.173773) (xy 423.380474 -30.100423) (xy 423.429603 -30.031431)
			(xy 423.485068 -29.967421) (xy 423.546366 -29.908973) (xy 423.612942 -29.856617) (xy 423.684194 -29.810827)
			(xy 423.759475 -29.772016) (xy 423.838105 -29.740537) (xy 423.919372 -29.716676) (xy 424.002538 -29.700647)
			(xy 424.086852 -29.692596) (xy 424.1292 -29.692092) (xy 424.175596 -29.692675) (xy 424.267884 -29.70232)
			(xy 424.358668 -29.721516) (xy 424.446961 -29.750054) (xy 424.489626 -29.768292) (xy 424.499566 -29.772112)
			(xy 424.520834 -29.772112) (xy 424.530774 -29.768292) (xy 424.573436 -29.750047) (xy 424.661729 -29.721503)
			(xy 424.752514 -29.70231) (xy 424.844804 -29.692677) (xy 424.8912 -29.692092) (xy 424.937596 -29.692675)
			(xy 425.029884 -29.70232) (xy 425.120668 -29.721516) (xy 425.208961 -29.750054) (xy 425.251626 -29.768292)
			(xy 425.261566 -29.772112) (xy 425.282834 -29.772112) (xy 425.292774 -29.768292) (xy 425.335436 -29.750047)
			(xy 425.423729 -29.721503) (xy 425.514514 -29.70231) (xy 425.606804 -29.692677) (xy 425.6532 -29.692092)
			(xy 425.695548 -29.692596) (xy 425.779862 -29.700647) (xy 425.863028 -29.716676) (xy 425.944295 -29.740537)
			(xy 426.022925 -29.772016) (xy 426.098206 -29.810827) (xy 426.169458 -29.856617) (xy 426.236034 -29.908973)
			(xy 426.297332 -29.967421) (xy 426.352797 -30.031431) (xy 426.401926 -30.100423) (xy 426.444275 -30.173773)
			(xy 426.479459 -30.250816) (xy 426.507161 -30.330855) (xy 426.527129 -30.413164) (xy 426.539182 -30.496999)
			(xy 426.543213 -30.5816) (xy 426.539182 -30.666201) (xy 426.527129 -30.750036) (xy 426.507161 -30.832345)
			(xy 426.479459 -30.912384) (xy 426.444275 -30.989427) (xy 426.401926 -31.062777) (xy 426.352797 -31.131769)
			(xy 426.297332 -31.195779) (xy 426.236034 -31.254227) (xy 426.169458 -31.306583) (xy 426.098206 -31.352373)
			(xy 426.022925 -31.391184) (xy 425.944295 -31.422663) (xy 425.863028 -31.446524) (xy 425.779862 -31.462553)
			(xy 425.695548 -31.470604) (xy 425.6532 -31.471108) (xy 425.606804 -31.470525) (xy 425.514516 -31.46088)
			(xy 425.423732 -31.441684) (xy 425.335439 -31.413146) (xy 425.292774 -31.394908) (xy 425.282834 -31.391088)
			(xy 425.261566 -31.391088) (xy 425.251626 -31.394908) (xy 425.208964 -31.413153) (xy 425.120671 -31.441697)
			(xy 425.029886 -31.46089) (xy 424.937596 -31.470523) (xy 424.8912 -31.471108) (xy 424.844804 -31.470525)
			(xy 424.752516 -31.46088) (xy 424.661732 -31.441684) (xy 424.573439 -31.413146) (xy 424.530774 -31.394908)
			(xy 424.520834 -31.391088) (xy 424.499566 -31.391088) (xy 424.489626 -31.394908) (xy 424.446964 -31.413153)
			(xy 424.358671 -31.441697) (xy 424.267886 -31.46089) (xy 424.175596 -31.470523) (xy 424.1292 -31.471108)
			(xy 424.086852 -31.470604) (xy 424.002538 -31.462553) (xy 423.919372 -31.446524) (xy 423.838105 -31.422663)
			(xy 423.759475 -31.391184) (xy 423.684194 -31.352373) (xy 423.612942 -31.306583) (xy 423.546366 -31.254227)
			(xy 423.485068 -31.195779) (xy 423.429603 -31.131769) (xy 423.380474 -31.062777) (xy 423.338125 -30.989427)
			(xy 423.302941 -30.912384) (xy 423.275239 -30.832345) (xy 423.255271 -30.750036) (xy 423.243218 -30.666201)
			(xy 423.239188 -30.5816) (xy 418.68031 -30.5816) (xy 418.690686 -30.584813) (xy 418.74229 -30.609764)
			(xy 418.789586 -30.642147) (xy 418.83151 -30.681236) (xy 418.86712 -30.726152) (xy 418.881814 -30.750764)
			(xy 418.888164 -30.76194) (xy 418.9095 -30.775402) (xy 419.019228 -30.783022) (xy 419.042342 -30.772862)
			(xy 419.050216 -30.762702) (xy 419.06841 -30.740165) (xy 419.11042 -30.700297) (xy 419.157977 -30.667241)
			(xy 419.209987 -30.641759) (xy 419.265252 -30.624435) (xy 419.322502 -30.61567) (xy 419.35146 -30.615128)
			(xy 419.378713 -30.615593) (xy 419.432666 -30.623345) (xy 419.484966 -30.638698) (xy 419.534549 -30.661338)
			(xy 419.580404 -30.690806) (xy 419.621598 -30.726499) (xy 419.657292 -30.767693) (xy 419.68676 -30.813548)
			(xy 419.709401 -30.86313) (xy 419.724754 -30.91543) (xy 419.732507 -30.969383) (xy 419.732968 -30.996636)
			(xy 419.732545 -31.022873) (xy 419.725344 -31.074851) (xy 419.711083 -31.12535) (xy 419.690032 -31.173417)
			(xy 419.662588 -31.218143) (xy 419.629271 -31.258683) (xy 419.610286 -31.276798) (xy 419.601396 -31.28518)
			(xy 419.593014 -31.307786) (xy 419.604444 -31.413196) (xy 419.617652 -31.433262) (xy 419.628066 -31.439358)
			(xy 419.652432 -31.454125) (xy 419.696908 -31.489732) (xy 419.735593 -31.531557) (xy 419.767628 -31.578671)
			(xy 419.792298 -31.630026) (xy 419.809057 -31.684478) (xy 419.81753 -31.740817) (xy 419.818058 -31.769304)
			(xy 419.817572 -31.796555) (xy 419.809816 -31.850503) (xy 419.794461 -31.902798) (xy 419.771819 -31.952375)
			(xy 419.742353 -31.998225) (xy 419.706662 -32.039416) (xy 419.665471 -32.075107) (xy 419.619621 -32.104573)
			(xy 419.570044 -32.127215) (xy 419.517749 -32.14257) (xy 419.463801 -32.150326) (xy 419.409299 -32.150326)
			(xy 419.355351 -32.14257) (xy 419.303056 -32.127215) (xy 419.253479 -32.104573) (xy 419.207629 -32.075107)
			(xy 419.166438 -32.039416) (xy 419.130747 -31.998225) (xy 419.101281 -31.952375) (xy 419.078639 -31.902798)
			(xy 419.063284 -31.850503) (xy 419.055528 -31.796555) (xy 419.055042 -31.769304) (xy 419.055489 -31.743068)
			(xy 419.062685 -31.691091) (xy 419.07694 -31.640592) (xy 419.097987 -31.592525) (xy 419.125427 -31.547798)
			(xy 419.158741 -31.507258) (xy 419.177724 -31.489142) (xy 419.186614 -31.48076) (xy 419.194996 -31.458154)
			(xy 419.183566 -31.352744) (xy 419.170358 -31.332678) (xy 419.159944 -31.326582) (xy 419.138446 -31.313693)
			(xy 419.09874 -31.283101) (xy 419.063396 -31.247558) (xy 419.033026 -31.207682) (xy 419.020244 -31.18612)
			(xy 419.013894 -31.174944) (xy 418.992558 -31.161482) (xy 418.88283 -31.153862) (xy 418.859716 -31.164022)
			(xy 418.851842 -31.174182) (xy 418.833668 -31.196735) (xy 418.791654 -31.236603) (xy 418.744093 -31.269658)
			(xy 418.69208 -31.295138) (xy 418.63681 -31.312457) (xy 418.579558 -31.321217) (xy 418.550598 -31.321756)
			(xy 418.52335 -31.321174) (xy 418.46941 -31.313418) (xy 418.417122 -31.298065) (xy 418.367551 -31.275426)
			(xy 418.321707 -31.245964) (xy 418.280522 -31.210277) (xy 418.244835 -31.169092) (xy 418.215373 -31.123247)
			(xy 418.192735 -31.073676) (xy 418.177382 -31.021388) (xy 418.169626 -30.967448) (xy 417.323879 -30.967448)
			(xy 417.356555 -31.005163) (xy 417.386024 -31.051022) (xy 417.408666 -31.100609) (xy 417.424021 -31.152913)
			(xy 417.431775 -31.20687) (xy 417.432236 -31.234126) (xy 417.432236 -31.244032) (xy 417.432324 -31.25803)
			(xy 417.439263 -31.28514) (xy 417.453299 -31.309349) (xy 417.473379 -31.328839) (xy 417.497996 -31.342147)
			(xy 417.525301 -31.348275) (xy 417.553243 -31.346761) (xy 417.579726 -31.33772) (xy 417.591494 -31.330138)
			(xy 417.615567 -31.314074) (xy 417.667547 -31.288636) (xy 417.722775 -31.271346) (xy 417.779982 -31.262602)
			(xy 417.808918 -31.262066) (xy 417.83617 -31.262575) (xy 417.890118 -31.270334) (xy 417.942413 -31.285692)
			(xy 417.99199 -31.308336) (xy 418.037839 -31.337805) (xy 418.079028 -31.373499) (xy 418.114719 -31.414692)
			(xy 418.144183 -31.460544) (xy 418.166822 -31.510124) (xy 418.182174 -31.56242) (xy 418.189928 -31.616369)
			(xy 418.189925 -31.670872) (xy 418.182166 -31.724821) (xy 418.166807 -31.777115) (xy 418.144163 -31.826692)
			(xy 418.114694 -31.872542) (xy 418.078999 -31.91373) (xy 418.037806 -31.94942) (xy 417.991953 -31.978884)
			(xy 417.942374 -32.001523) (xy 417.890077 -32.016875) (xy 417.836128 -32.024628) (xy 417.781625 -32.024625)
			(xy 417.727677 -32.016865) (xy 417.675382 -32.001506) (xy 417.625806 -31.978862) (xy 417.579956 -31.949392)
			(xy 417.538768 -31.913697) (xy 417.503078 -31.872504) (xy 417.473615 -31.826651) (xy 417.450976 -31.777071)
			(xy 417.435624 -31.724775) (xy 417.427871 -31.670826) (xy 417.42741 -31.643574) (xy 417.42741 -31.633668)
			(xy 417.42725 -31.619674) (xy 417.420316 -31.592576) (xy 417.406287 -31.568376) (xy 417.386218 -31.548891)
			(xy 417.361614 -31.535584) (xy 417.334323 -31.529453) (xy 417.306392 -31.530959) (xy 417.279917 -31.539987)
			(xy 417.268152 -31.547562) (xy 417.244067 -31.563606) (xy 417.192091 -31.589049) (xy 417.136866 -31.606345)
			(xy 417.079663 -31.615095) (xy 417.050728 -31.615634) (xy 417.023472 -31.615175) (xy 416.969515 -31.607421)
			(xy 416.917211 -31.592067) (xy 416.867624 -31.569425) (xy 416.821765 -31.539956) (xy 416.780566 -31.504261)
			(xy 416.744866 -31.463066) (xy 416.715393 -31.417209) (xy 416.692747 -31.367625) (xy 416.677387 -31.315322)
			(xy 416.669628 -31.261366) (xy 416.669626 -31.206854) (xy 414.67532 -31.206854) (xy 414.67532 -32.35071)
			(xy 420.40886 -32.35071) (xy 420.412931 -32.295088) (xy 420.425057 -32.240651) (xy 420.44498 -32.18856)
			(xy 420.472276 -32.139925) (xy 420.506362 -32.095782) (xy 420.546511 -32.057073) (xy 420.591869 -32.024622)
			(xy 420.641469 -31.999121) (xy 420.694253 -31.981114) (xy 420.749096 -31.970984) (xy 420.80483 -31.968947)
			(xy 420.860267 -31.975047) (xy 420.914224 -31.989153) (xy 420.965553 -32.010965) (xy 421.013159 -32.040019)
			(xy 421.056027 -32.075694) (xy 421.093244 -32.117231) (xy 421.124017 -32.163744) (xy 421.147689 -32.214241)
			(xy 421.163757 -32.267648) (xy 421.171877 -32.322824) (xy 421.172386 -32.35071) (xy 421.171877 -32.378596)
			(xy 421.163757 -32.433772) (xy 421.147689 -32.487179) (xy 421.124017 -32.537676) (xy 421.093244 -32.584189)
			(xy 421.056027 -32.625726) (xy 421.013159 -32.661401) (xy 420.965553 -32.690455) (xy 420.914224 -32.712267)
			(xy 420.860267 -32.726373) (xy 420.80483 -32.732473) (xy 420.749096 -32.730436) (xy 420.694253 -32.720306)
			(xy 420.641469 -32.702299) (xy 420.591869 -32.676798) (xy 420.546511 -32.644347) (xy 420.506362 -32.605638)
			(xy 420.472276 -32.561495) (xy 420.44498 -32.51286) (xy 420.425057 -32.460769) (xy 420.412931 -32.406332)
			(xy 420.40886 -32.35071) (xy 414.67532 -32.35071) (xy 414.67532 -33.770316) (xy 415.84956 -33.770316)
			(xy 415.853631 -33.714694) (xy 415.865757 -33.660257) (xy 415.88568 -33.608166) (xy 415.912976 -33.559531)
			(xy 415.947062 -33.515388) (xy 415.987211 -33.476679) (xy 416.032569 -33.444228) (xy 416.082169 -33.418727)
			(xy 416.134953 -33.40072) (xy 416.189796 -33.39059) (xy 416.24553 -33.388553) (xy 416.300967 -33.394653)
			(xy 416.354924 -33.408759) (xy 416.406253 -33.430571) (xy 416.453859 -33.459625) (xy 416.496727 -33.4953)
			(xy 416.533944 -33.536837) (xy 416.564717 -33.58335) (xy 416.588389 -33.633847) (xy 416.604457 -33.687254)
			(xy 416.612577 -33.74243) (xy 416.612905 -33.76041) (xy 418.51402 -33.76041) (xy 418.518091 -33.704788)
			(xy 418.530217 -33.650351) (xy 418.55014 -33.59826) (xy 418.577436 -33.549625) (xy 418.611522 -33.505482)
			(xy 418.651671 -33.466773) (xy 418.697029 -33.434322) (xy 418.746629 -33.408821) (xy 418.799413 -33.390814)
			(xy 418.854256 -33.380684) (xy 418.90999 -33.378647) (xy 418.965427 -33.384747) (xy 419.019384 -33.398853)
			(xy 419.070713 -33.420665) (xy 419.118319 -33.449719) (xy 419.161187 -33.485394) (xy 419.198404 -33.526931)
			(xy 419.229177 -33.573444) (xy 419.252849 -33.623941) (xy 419.268917 -33.677348) (xy 419.277037 -33.732524)
			(xy 419.277546 -33.76041) (xy 419.277037 -33.788296) (xy 419.268917 -33.843472) (xy 419.252849 -33.896879)
			(xy 419.229177 -33.947376) (xy 419.198404 -33.993889) (xy 419.161187 -34.035426) (xy 419.118319 -34.071101)
			(xy 419.070713 -34.100155) (xy 419.019384 -34.121967) (xy 418.965427 -34.136073) (xy 418.90999 -34.142173)
			(xy 418.854256 -34.140136) (xy 418.799413 -34.130006) (xy 418.746629 -34.111999) (xy 418.697029 -34.086498)
			(xy 418.651671 -34.054047) (xy 418.611522 -34.015338) (xy 418.577436 -33.971195) (xy 418.55014 -33.92256)
			(xy 418.530217 -33.870469) (xy 418.518091 -33.816032) (xy 418.51402 -33.76041) (xy 416.612905 -33.76041)
			(xy 416.613086 -33.770316) (xy 416.612577 -33.798202) (xy 416.604457 -33.853378) (xy 416.588389 -33.906785)
			(xy 416.564717 -33.957282) (xy 416.533944 -34.003795) (xy 416.496727 -34.045332) (xy 416.453859 -34.081007)
			(xy 416.406253 -34.110061) (xy 416.354924 -34.131873) (xy 416.300967 -34.145979) (xy 416.24553 -34.152079)
			(xy 416.189796 -34.150042) (xy 416.134953 -34.139912) (xy 416.082169 -34.121905) (xy 416.032569 -34.096404)
			(xy 415.987211 -34.063953) (xy 415.947062 -34.025244) (xy 415.912976 -33.981101) (xy 415.88568 -33.932466)
			(xy 415.865757 -33.880375) (xy 415.853631 -33.825938) (xy 415.84956 -33.770316) (xy 414.67532 -33.770316)
			(xy 414.67532 -35.052) (xy 423.035982 -35.052) (xy 423.040053 -34.996378) (xy 423.052179 -34.941941)
			(xy 423.072102 -34.88985) (xy 423.099398 -34.841215) (xy 423.133484 -34.797072) (xy 423.173633 -34.758363)
			(xy 423.218991 -34.725912) (xy 423.268591 -34.700411) (xy 423.321375 -34.682404) (xy 423.376218 -34.672274)
			(xy 423.431952 -34.670237) (xy 423.487389 -34.676337) (xy 423.541346 -34.690443) (xy 423.592675 -34.712255)
			(xy 423.640281 -34.741309) (xy 423.683149 -34.776984) (xy 423.720366 -34.818521) (xy 423.751139 -34.865034)
			(xy 423.774811 -34.915531) (xy 423.790879 -34.968938) (xy 423.798999 -35.024114) (xy 423.799508 -35.052)
			(xy 423.798999 -35.079886) (xy 423.790879 -35.135062) (xy 423.774811 -35.188469) (xy 423.751139 -35.238966)
			(xy 423.720366 -35.285479) (xy 423.683149 -35.327016) (xy 423.640281 -35.362691) (xy 423.592675 -35.391745)
			(xy 423.541346 -35.413557) (xy 423.487389 -35.427663) (xy 423.431952 -35.433763) (xy 423.376218 -35.431726)
			(xy 423.321375 -35.421596) (xy 423.268591 -35.403589) (xy 423.218991 -35.378088) (xy 423.173633 -35.345637)
			(xy 423.133484 -35.306928) (xy 423.099398 -35.262785) (xy 423.072102 -35.21415) (xy 423.052179 -35.162059)
			(xy 423.040053 -35.107622) (xy 423.035982 -35.052) (xy 414.67532 -35.052) (xy 414.67532 -37.9222)
			(xy 414.67574 -37.93222) (xy 414.683411 -37.950733) (xy 414.697584 -37.9649) (xy 414.7161 -37.972564)
			(xy 414.72612 -37.973) (xy 422.634918 -37.973) (xy 422.644987 -37.972573) (xy 422.663586 -37.964854)
			(xy 422.670986 -37.958014) (xy 427.721014 -32.907986) (xy 427.727868 -32.900591) (xy 427.73561 -32.881992)
			(xy 427.736 -32.871918) (xy 427.736 -32.664146) (xy 427.735695 -32.65515) (xy 427.729594 -32.638226)
			(xy 427.724062 -32.631126) (xy 427.707117 -32.610396) (xy 427.678595 -32.565083) (xy 427.656693 -32.516226)
			(xy 427.641843 -32.464784) (xy 427.634338 -32.411771) (xy 427.633892 -32.385) (xy 427.634364 -32.358232)
			(xy 427.641885 -32.305225) (xy 427.656736 -32.253789) (xy 427.678628 -32.204932) (xy 427.70713 -32.159613)
			(xy 427.724062 -32.138874) (xy 427.729594 -32.13177) (xy 427.73572 -32.114852) (xy 427.736 -32.105854)
			(xy 427.736 -26.818082) (xy 427.735573 -26.808013) (xy 427.727854 -26.789414) (xy 427.721014 -26.782014)
			(xy 424.321986 -23.382986) (xy 424.314591 -23.376132) (xy 424.295992 -23.36839) (xy 424.285918 -23.368)
			(xy 409.596082 -23.368) (xy 409.586013 -23.368427) (xy 409.567414 -23.376146) (xy 409.560014 -23.382986)
			(xy 407.811986 -25.131014) (xy 407.805132 -25.138409) (xy 407.79739 -25.157008) (xy 407.797 -25.167082)
			(xy 407.797 -26.4008) (xy 411.953947 -26.4008) (xy 411.957978 -26.316196) (xy 411.970031 -26.232359)
			(xy 411.99 -26.150047) (xy 412.017702 -26.070005) (xy 412.052887 -25.99296) (xy 412.095236 -25.919607)
			(xy 412.144366 -25.850613) (xy 412.199832 -25.7866) (xy 412.261131 -25.72815) (xy 412.327709 -25.675792)
			(xy 412.398962 -25.629999) (xy 412.474246 -25.591186) (xy 412.552877 -25.559705) (xy 412.634146 -25.535841)
			(xy 412.717314 -25.51981) (xy 412.80163 -25.511757) (xy 412.84398 -25.511252) (xy 412.885192 -25.511722)
			(xy 412.967262 -25.519352) (xy 413.048276 -25.534538) (xy 413.127537 -25.557152) (xy 413.204368 -25.586998)
			(xy 413.278109 -25.623822) (xy 413.348129 -25.667307) (xy 413.413827 -25.717081) (xy 413.474641 -25.772718)
			(xy 413.53005 -25.83374) (xy 413.579577 -25.899625) (xy 413.6228 -25.969807) (xy 413.659347 -26.043686)
			(xy 413.67456 -26.08199) (xy 413.67837 -26.09215) (xy 413.693356 -26.10739) (xy 413.784034 -26.142442)
			(xy 413.80537 -26.141172) (xy 413.815022 -26.136346) (xy 413.841841 -26.123472) (xy 413.89847 -26.105255)
			(xy 413.957237 -26.096026) (xy 413.98698 -26.095452) (xy 414.014231 -26.095994) (xy 414.068178 -26.103748)
			(xy 414.120473 -26.1191) (xy 414.170051 -26.141739) (xy 414.215901 -26.171204) (xy 414.257092 -26.206894)
			(xy 414.292784 -26.248083) (xy 414.322251 -26.293932) (xy 414.344893 -26.343508) (xy 414.360248 -26.395802)
			(xy 414.368005 -26.449749) (xy 414.368005 -26.450036) (xy 415.29889 -26.450036) (xy 415.299356 -26.408335)
			(xy 415.307166 -26.3253) (xy 415.322712 -26.24336) (xy 415.345857 -26.163234) (xy 415.376398 -26.085625)
			(xy 415.414067 -26.011215) (xy 415.458533 -25.940656) (xy 415.509407 -25.874567) (xy 415.566242 -25.813529)
			(xy 415.628539 -25.758077) (xy 415.661856 -25.732994) (xy 415.670411 -25.726068) (xy 415.68107 -25.706834)
			(xy 415.68243 -25.69591) (xy 415.686144 -25.654539) (xy 415.700231 -25.572675) (xy 415.721888 -25.49248)
			(xy 415.750926 -25.414652) (xy 415.787092 -25.339871) (xy 415.830071 -25.268786) (xy 415.87949 -25.202018)
			(xy 415.934918 -25.140146) (xy 415.995871 -25.083711) (xy 416.06182 -25.033204) (xy 416.132189 -24.989063)
			(xy 416.206367 -24.951675) (xy 416.283708 -24.921364) (xy 416.363536 -24.898394) (xy 416.445159 -24.882965)
			(xy 416.527864 -24.875213) (xy 416.569398 -24.874728) (xy 416.613191 -24.875285) (xy 416.700352 -24.883915)
			(xy 416.786245 -24.901061) (xy 416.870039 -24.926559) (xy 416.950924 -24.960162) (xy 416.989768 -24.980392)
			(xy 417.001234 -24.98581) (xy 417.026562 -24.98581) (xy 417.038028 -24.980392) (xy 417.076868 -24.960148)
			(xy 417.157744 -24.926515) (xy 417.241538 -24.901002) (xy 417.327435 -24.883858) (xy 417.414602 -24.875249)
			(xy 417.458398 -24.874728) (xy 417.502191 -24.875285) (xy 417.589352 -24.883915) (xy 417.675245 -24.901061)
			(xy 417.759039 -24.926559) (xy 417.839924 -24.960162) (xy 417.878768 -24.980392) (xy 417.890234 -24.98581)
			(xy 417.915562 -24.98581) (xy 417.927028 -24.980392) (xy 417.965868 -24.960148) (xy 418.046744 -24.926515)
			(xy 418.130538 -24.901002) (xy 418.216435 -24.883858) (xy 418.303602 -24.875249) (xy 418.347398 -24.874728)
			(xy 418.397558 -24.87545) (xy 418.497238 -24.886777) (xy 418.54628 -24.897334) (xy 418.556797 -24.899303)
			(xy 418.577781 -24.89521) (xy 418.595265 -24.882906) (xy 418.601144 -24.873966) (xy 418.623029 -24.838556)
			(xy 418.672412 -24.771537) (xy 418.727842 -24.709425) (xy 418.788833 -24.652765) (xy 418.854851 -24.602051)
			(xy 418.92532 -24.557728) (xy 418.999621 -24.520183) (xy 419.077105 -24.489745) (xy 419.157095 -24.466681)
			(xy 419.23889 -24.451191) (xy 419.321774 -24.443413) (xy 419.363398 -24.442928) (xy 419.405749 -24.443344)
			(xy 419.490068 -24.451395) (xy 419.573239 -24.467425) (xy 419.65451 -24.491288) (xy 419.733145 -24.522769)
			(xy 419.808431 -24.561581) (xy 419.879687 -24.607375) (xy 419.946267 -24.659734) (xy 420.007569 -24.718185)
			(xy 420.063037 -24.782198) (xy 420.112169 -24.851194) (xy 420.15452 -24.924549) (xy 420.189707 -25.001596)
			(xy 420.21741 -25.08164) (xy 420.237379 -25.163954) (xy 420.249434 -25.247794) (xy 420.253464 -25.3324)
			(xy 420.249434 -25.417006) (xy 420.237379 -25.500846) (xy 420.21741 -25.58316) (xy 420.189707 -25.663204)
			(xy 420.15452 -25.740251) (xy 420.112169 -25.813606) (xy 420.063037 -25.882602) (xy 420.007569 -25.946615)
			(xy 419.94684 -26.00452) (xy 420.508682 -26.00452) (xy 420.512753 -25.948898) (xy 420.524879 -25.894461)
			(xy 420.544802 -25.84237) (xy 420.572098 -25.793735) (xy 420.606184 -25.749592) (xy 420.646333 -25.710883)
			(xy 420.691691 -25.678432) (xy 420.741291 -25.652931) (xy 420.794075 -25.634924) (xy 420.848918 -25.624794)
			(xy 420.904652 -25.622757) (xy 420.960089 -25.628857) (xy 421.014046 -25.642963) (xy 421.065375 -25.664775)
			(xy 421.112981 -25.693829) (xy 421.155849 -25.729504) (xy 421.193066 -25.771041) (xy 421.223839 -25.817554)
			(xy 421.247511 -25.868051) (xy 421.263579 -25.921458) (xy 421.271699 -25.976634) (xy 421.272208 -26.00452)
			(xy 421.271699 -26.032406) (xy 421.263579 -26.087582) (xy 421.247511 -26.140989) (xy 421.223839 -26.191486)
			(xy 421.193066 -26.237999) (xy 421.155849 -26.279536) (xy 421.112981 -26.315211) (xy 421.065375 -26.344265)
			(xy 421.014046 -26.366077) (xy 420.960089 -26.380183) (xy 420.904652 -26.386283) (xy 420.848918 -26.384246)
			(xy 420.794075 -26.374116) (xy 420.741291 -26.356109) (xy 420.691691 -26.330608) (xy 420.646333 -26.298157)
			(xy 420.606184 -26.259448) (xy 420.572098 -26.215305) (xy 420.544802 -26.16667) (xy 420.524879 -26.114579)
			(xy 420.512753 -26.060142) (xy 420.508682 -26.00452) (xy 419.94684 -26.00452) (xy 419.946267 -26.005066)
			(xy 419.879687 -26.057425) (xy 419.808431 -26.103219) (xy 419.733145 -26.142031) (xy 419.65451 -26.173512)
			(xy 419.573239 -26.197375) (xy 419.490068 -26.213405) (xy 419.405749 -26.221456) (xy 419.363398 -26.221944)
			(xy 419.313238 -26.221221) (xy 419.213558 -26.209894) (xy 419.164516 -26.199338) (xy 419.153999 -26.197378)
			(xy 419.133018 -26.201471) (xy 419.115533 -26.213769) (xy 419.109652 -26.222706) (xy 419.086512 -26.260171)
			(xy 419.033894 -26.330786) (xy 418.974564 -26.395864) (xy 418.909102 -26.454769) (xy 418.87394 -26.481278)
			(xy 418.865396 -26.488215) (xy 418.854731 -26.507441) (xy 418.853366 -26.518362) (xy 418.849632 -26.559731)
			(xy 418.835547 -26.641595) (xy 418.813893 -26.72179) (xy 418.784857 -26.799618) (xy 418.748693 -26.874399)
			(xy 418.718704 -26.924) (xy 421.765982 -26.924) (xy 421.770053 -26.868378) (xy 421.782179 -26.813941)
			(xy 421.802102 -26.76185) (xy 421.829398 -26.713215) (xy 421.863484 -26.669072) (xy 421.903633 -26.630363)
			(xy 421.948991 -26.597912) (xy 421.998591 -26.572411) (xy 422.051375 -26.554404) (xy 422.106218 -26.544274)
			(xy 422.161952 -26.542237) (xy 422.217389 -26.548337) (xy 422.271346 -26.562443) (xy 422.322675 -26.584255)
			(xy 422.370281 -26.613309) (xy 422.413149 -26.648984) (xy 422.450366 -26.690521) (xy 422.481139 -26.737034)
			(xy 422.504811 -26.787531) (xy 422.520879 -26.840938) (xy 422.528999 -26.896114) (xy 422.529508 -26.924)
			(xy 422.528999 -26.951886) (xy 422.520879 -27.007062) (xy 422.504811 -27.060469) (xy 422.481139 -27.110966)
			(xy 422.450366 -27.157479) (xy 422.413149 -27.199016) (xy 422.370281 -27.234691) (xy 422.322675 -27.263745)
			(xy 422.271346 -27.285557) (xy 422.217389 -27.299663) (xy 422.161952 -27.305763) (xy 422.106218 -27.303726)
			(xy 422.051375 -27.293596) (xy 421.998591 -27.275589) (xy 421.948991 -27.250088) (xy 421.903633 -27.217637)
			(xy 421.863484 -27.178928) (xy 421.829398 -27.134785) (xy 421.802102 -27.08615) (xy 421.782179 -27.034059)
			(xy 421.770053 -26.979622) (xy 421.765982 -26.924) (xy 418.718704 -26.924) (xy 418.705715 -26.945484)
			(xy 418.656298 -27.012253) (xy 418.600872 -27.074125) (xy 418.539919 -27.13056) (xy 418.473972 -27.181068)
			(xy 418.403603 -27.225209) (xy 418.329426 -27.262598) (xy 418.252086 -27.292909) (xy 418.172258 -27.315879)
			(xy 418.090636 -27.331307) (xy 418.007932 -27.339059) (xy 417.966398 -27.339544) (xy 417.922605 -27.33898)
			(xy 417.835444 -27.330351) (xy 417.749552 -27.313205) (xy 417.665758 -27.287709) (xy 417.584873 -27.254109)
			(xy 417.546028 -27.23388) (xy 417.534562 -27.228462) (xy 417.509234 -27.228462) (xy 417.497768 -27.23388)
			(xy 417.458928 -27.254123) (xy 417.378051 -27.287757) (xy 417.294258 -27.31327) (xy 417.208361 -27.330414)
			(xy 417.121194 -27.339023) (xy 417.077398 -27.339544) (xy 417.033605 -27.33898) (xy 416.946444 -27.330351)
			(xy 416.860552 -27.313205) (xy 416.776758 -27.287709) (xy 416.695873 -27.254109) (xy 416.657028 -27.23388)
			(xy 416.645562 -27.228462) (xy 416.620234 -27.228462) (xy 416.608768 -27.23388) (xy 416.569928 -27.254123)
			(xy 416.489051 -27.287757) (xy 416.405258 -27.31327) (xy 416.319361 -27.330414) (xy 416.232194 -27.339023)
			(xy 416.188398 -27.339544) (xy 416.147297 -27.339035) (xy 416.065444 -27.331451) (xy 415.984641 -27.316346)
			(xy 415.905576 -27.293851) (xy 415.828924 -27.264156) (xy 415.755338 -27.227516) (xy 415.685447 -27.184242)
			(xy 415.619847 -27.134705) (xy 415.559098 -27.079326) (xy 415.503717 -27.018579) (xy 415.454177 -26.952981)
			(xy 415.410901 -26.883091) (xy 415.374258 -26.809507) (xy 415.34456 -26.732856) (xy 415.322062 -26.653792)
			(xy 415.306954 -26.572989) (xy 415.299366 -26.491137) (xy 415.29889 -26.450036) (xy 414.368005 -26.450036)
			(xy 414.368005 -26.504251) (xy 414.360248 -26.558198) (xy 414.344893 -26.610492) (xy 414.322251 -26.660068)
			(xy 414.292784 -26.705917) (xy 414.257092 -26.747106) (xy 414.215901 -26.782796) (xy 414.170051 -26.812261)
			(xy 414.120473 -26.8349) (xy 414.068178 -26.850252) (xy 414.014231 -26.858006) (xy 413.98698 -26.858468)
			(xy 413.958317 -26.857945) (xy 413.901636 -26.849366) (xy 413.846876 -26.832405) (xy 413.795271 -26.807442)
			(xy 413.771334 -26.791666) (xy 413.762444 -26.78557) (xy 413.741362 -26.78176) (xy 413.646874 -26.804366)
			(xy 413.63011 -26.81732) (xy 413.624776 -26.826972) (xy 413.603537 -26.864728) (xy 413.554825 -26.93637)
			(xy 413.49938 -27.002937) (xy 413.437727 -27.063799) (xy 413.37045 -27.118381) (xy 413.298186 -27.166164)
			(xy 413.22162 -27.206697) (xy 413.141476 -27.239595) (xy 413.058514 -27.264547) (xy 412.973519 -27.281317)
			(xy 412.887297 -27.289746) (xy 412.84398 -27.290268) (xy 412.80163 -27.289843) (xy 412.717314 -27.28179)
			(xy 412.634146 -27.265759) (xy 412.552877 -27.241895) (xy 412.474246 -27.210414) (xy 412.398962 -27.171601)
			(xy 412.327709 -27.125808) (xy 412.261131 -27.07345) (xy 412.199832 -27.015) (xy 412.144366 -26.950987)
			(xy 412.095236 -26.881993) (xy 412.052887 -26.80864) (xy 412.017702 -26.731595) (xy 411.99 -26.651553)
			(xy 411.970031 -26.569241) (xy 411.957978 -26.485404) (xy 411.953947 -26.4008) (xy 407.797 -26.4008)
			(xy 407.797 -27.94) (xy 409.599382 -27.94) (xy 409.603453 -27.884378) (xy 409.615579 -27.829941)
			(xy 409.635502 -27.77785) (xy 409.662798 -27.729215) (xy 409.696884 -27.685072) (xy 409.737033 -27.646363)
			(xy 409.782391 -27.613912) (xy 409.831991 -27.588411) (xy 409.884775 -27.570404) (xy 409.939618 -27.560274)
			(xy 409.995352 -27.558237) (xy 410.050789 -27.564337) (xy 410.104746 -27.578443) (xy 410.156075 -27.600255)
			(xy 410.203681 -27.629309) (xy 410.246549 -27.664984) (xy 410.283766 -27.706521) (xy 410.289851 -27.715718)
			(xy 414.231326 -27.715718) (xy 414.235397 -27.660096) (xy 414.247523 -27.605659) (xy 414.267446 -27.553568)
			(xy 414.294742 -27.504933) (xy 414.328828 -27.46079) (xy 414.368977 -27.422081) (xy 414.414335 -27.38963)
			(xy 414.463935 -27.364129) (xy 414.516719 -27.346122) (xy 414.571562 -27.335992) (xy 414.627296 -27.333955)
			(xy 414.682733 -27.340055) (xy 414.73669 -27.354161) (xy 414.788019 -27.375973) (xy 414.835625 -27.405027)
			(xy 414.878493 -27.440702) (xy 414.91571 -27.482239) (xy 414.946483 -27.528752) (xy 414.970155 -27.579249)
			(xy 414.986223 -27.632656) (xy 414.994343 -27.687832) (xy 414.994852 -27.715718) (xy 414.994343 -27.743604)
			(xy 414.986223 -27.79878) (xy 414.970155 -27.852187) (xy 414.946483 -27.902684) (xy 414.91571 -27.949197)
			(xy 414.878493 -27.990734) (xy 414.835625 -28.026409) (xy 414.788019 -28.055463) (xy 414.73669 -28.077275)
			(xy 414.682733 -28.091381) (xy 414.627296 -28.097481) (xy 414.571562 -28.095444) (xy 414.516719 -28.085314)
			(xy 414.463935 -28.067307) (xy 414.414335 -28.041806) (xy 414.368977 -28.009355) (xy 414.328828 -27.970646)
			(xy 414.294742 -27.926503) (xy 414.267446 -27.877868) (xy 414.247523 -27.825777) (xy 414.235397 -27.77134)
			(xy 414.231326 -27.715718) (xy 410.289851 -27.715718) (xy 410.314539 -27.753034) (xy 410.338211 -27.803531)
			(xy 410.354279 -27.856938) (xy 410.362399 -27.912114) (xy 410.362908 -27.94) (xy 410.362399 -27.967886)
			(xy 410.354279 -28.023062) (xy 410.338211 -28.076469) (xy 410.314539 -28.126966) (xy 410.283766 -28.173479)
			(xy 410.246549 -28.215016) (xy 410.203681 -28.250691) (xy 410.156075 -28.279745) (xy 410.104746 -28.301557)
			(xy 410.050789 -28.315663) (xy 409.995352 -28.321763) (xy 409.939618 -28.319726) (xy 409.884775 -28.309596)
			(xy 409.831991 -28.291589) (xy 409.782391 -28.266088) (xy 409.737033 -28.233637) (xy 409.696884 -28.194928)
			(xy 409.662798 -28.150785) (xy 409.635502 -28.10215) (xy 409.615579 -28.050059) (xy 409.603453 -27.995622)
			(xy 409.599382 -27.94) (xy 407.797 -27.94) (xy 407.797 -29.21) (xy 409.599382 -29.21) (xy 409.603453 -29.154378)
			(xy 409.615579 -29.099941) (xy 409.635502 -29.04785) (xy 409.662798 -28.999215) (xy 409.696884 -28.955072)
			(xy 409.737033 -28.916363) (xy 409.782391 -28.883912) (xy 409.831991 -28.858411) (xy 409.884775 -28.840404)
			(xy 409.939618 -28.830274) (xy 409.995352 -28.828237) (xy 410.050789 -28.834337) (xy 410.104746 -28.848443)
			(xy 410.156075 -28.870255) (xy 410.203681 -28.899309) (xy 410.246549 -28.934984) (xy 410.283766 -28.976521)
			(xy 410.314539 -29.023034) (xy 410.338211 -29.073531) (xy 410.354279 -29.126938) (xy 410.362399 -29.182114)
			(xy 410.362908 -29.21) (xy 410.362399 -29.237886) (xy 410.354279 -29.293062) (xy 410.338211 -29.346469)
			(xy 410.314539 -29.396966) (xy 410.283766 -29.443479) (xy 410.246549 -29.485016) (xy 410.203681 -29.520691)
			(xy 410.156075 -29.549745) (xy 410.104746 -29.571557) (xy 410.050789 -29.585663) (xy 409.995352 -29.591763)
			(xy 409.939618 -29.589726) (xy 409.884775 -29.579596) (xy 409.831991 -29.561589) (xy 409.782391 -29.536088)
			(xy 409.737033 -29.503637) (xy 409.696884 -29.464928) (xy 409.662798 -29.420785) (xy 409.635502 -29.37215)
			(xy 409.615579 -29.320059) (xy 409.603453 -29.265622) (xy 409.599382 -29.21) (xy 407.797 -29.21)
			(xy 407.797 -30.48) (xy 409.599382 -30.48) (xy 409.603453 -30.424378) (xy 409.615579 -30.369941)
			(xy 409.635502 -30.31785) (xy 409.662798 -30.269215) (xy 409.696884 -30.225072) (xy 409.737033 -30.186363)
			(xy 409.782391 -30.153912) (xy 409.831991 -30.128411) (xy 409.884775 -30.110404) (xy 409.939618 -30.100274)
			(xy 409.995352 -30.098237) (xy 410.050789 -30.104337) (xy 410.104746 -30.118443) (xy 410.156075 -30.140255)
			(xy 410.203681 -30.169309) (xy 410.246549 -30.204984) (xy 410.283766 -30.246521) (xy 410.314539 -30.293034)
			(xy 410.338211 -30.343531) (xy 410.354279 -30.396938) (xy 410.362399 -30.452114) (xy 410.362908 -30.48)
			(xy 410.362399 -30.507886) (xy 410.354279 -30.563062) (xy 410.338211 -30.616469) (xy 410.314539 -30.666966)
			(xy 410.283766 -30.713479) (xy 410.246549 -30.755016) (xy 410.203681 -30.790691) (xy 410.156075 -30.819745)
			(xy 410.104746 -30.841557) (xy 410.050789 -30.855663) (xy 409.995352 -30.861763) (xy 409.939618 -30.859726)
			(xy 409.884775 -30.849596) (xy 409.831991 -30.831589) (xy 409.782391 -30.806088) (xy 409.737033 -30.773637)
			(xy 409.696884 -30.734928) (xy 409.662798 -30.690785) (xy 409.635502 -30.64215) (xy 409.615579 -30.590059)
			(xy 409.603453 -30.535622) (xy 409.599382 -30.48) (xy 407.797 -30.48) (xy 407.797 -33.02) (xy 409.599382 -33.02)
			(xy 409.603453 -32.964378) (xy 409.615579 -32.909941) (xy 409.635502 -32.85785) (xy 409.662798 -32.809215)
			(xy 409.696884 -32.765072) (xy 409.737033 -32.726363) (xy 409.782391 -32.693912) (xy 409.831991 -32.668411)
			(xy 409.884775 -32.650404) (xy 409.939618 -32.640274) (xy 409.995352 -32.638237) (xy 410.050789 -32.644337)
			(xy 410.104746 -32.658443) (xy 410.156075 -32.680255) (xy 410.203681 -32.709309) (xy 410.246549 -32.744984)
			(xy 410.283766 -32.786521) (xy 410.314539 -32.833034) (xy 410.338211 -32.883531) (xy 410.354279 -32.936938)
			(xy 410.362399 -32.992114) (xy 410.362908 -33.02) (xy 410.362399 -33.047886) (xy 410.354279 -33.103062)
			(xy 410.338211 -33.156469) (xy 410.314539 -33.206966) (xy 410.283766 -33.253479) (xy 410.246549 -33.295016)
			(xy 410.203681 -33.330691) (xy 410.156075 -33.359745) (xy 410.104746 -33.381557) (xy 410.050789 -33.395663)
			(xy 409.995352 -33.401763) (xy 409.939618 -33.399726) (xy 409.884775 -33.389596) (xy 409.831991 -33.371589)
			(xy 409.782391 -33.346088) (xy 409.737033 -33.313637) (xy 409.696884 -33.274928) (xy 409.662798 -33.230785)
			(xy 409.635502 -33.18215) (xy 409.615579 -33.130059) (xy 409.603453 -33.075622) (xy 409.599382 -33.02)
			(xy 407.797 -33.02) (xy 407.797 -37.316918) (xy 407.797427 -37.326987) (xy 407.805146 -37.345586)
			(xy 407.811986 -37.352986) (xy 407.95194 -37.49294) (xy 407.959354 -37.499614) (xy 407.977789 -37.507175)
			(xy 407.987754 -37.507672) (xy 410.773626 -37.507672) (xy 410.780565 -37.507523) (xy 410.793959 -37.503904)
			(xy 410.800042 -37.50056) (xy 410.822459 -37.487495) (xy 410.870077 -37.466886) (xy 410.920051 -37.452932)
			(xy 410.971457 -37.44589) (xy 410.9974 -37.445442) (xy 411.024652 -37.445905) (xy 411.0786 -37.453663)
			(xy 411.130895 -37.469019) (xy 411.180472 -37.491662) (xy 411.226321 -37.521131) (xy 411.26751 -37.556826)
			(xy 411.303199 -37.598019) (xy 411.332662 -37.643872) (xy 411.355298 -37.693452) (xy 411.370648 -37.745749)
			(xy 411.378398 -37.799698) (xy 411.378908 -37.82695) (xy 411.377384 -37.862002) (xy 411.376368 -37.87267)
			(xy 411.382972 -37.89299) (xy 411.440884 -37.95649) (xy 411.448379 -37.964043) (xy 411.467843 -37.972595)
			(xy 411.478476 -37.973)
		)
		(stroke
			(width 0)
			(type solid)
		)
		(fill yes)
		(layer "In2.Cu")
		(net "P3V3_AUX")
	)
	(gr_poly
		(pts
			(xy 75.000104 -171.141898) (xy 75.095459 -171.141392) (xy 75.285997 -171.133298) (xy 75.47602 -171.117124)
			(xy 75.665185 -171.092901) (xy 75.853152 -171.06067) (xy 76.039581 -171.020492) (xy 76.224138 -170.972437)
			(xy 76.406488 -170.916593) (xy 76.586304 -170.853059) (xy 76.763262 -170.781952) (xy 76.937042 -170.703398)
			(xy 77.107332 -170.61754) (xy 77.273824 -170.524532) (xy 77.436219 -170.424541) (xy 77.594224 -170.317748)
			(xy 77.747555 -170.204346) (xy 77.895934 -170.084538) (xy 78.039094 -169.958541) (xy 78.176779 -169.826581)
			(xy 78.308738 -169.688897) (xy 78.434736 -169.545737) (xy 78.554543 -169.397358) (xy 78.667946 -169.244028)
			(xy 78.774739 -169.086023) (xy 78.87473 -168.923628) (xy 78.967738 -168.757135) (xy 79.053597 -168.586846)
			(xy 79.13215 -168.413065) (xy 79.203258 -168.236108) (xy 79.266791 -168.056292) (xy 79.322636 -167.873941)
			(xy 79.370691 -167.689385) (xy 79.41087 -167.502956) (xy 79.4431 -167.314989) (xy 79.467324 -167.125824)
			(xy 79.483497 -166.935801) (xy 79.491592 -166.745263) (xy 79.492094 -166.649908) (xy 79.492094 -161.299906)
			(xy 79.49259 -161.216412) (xy 79.500536 -161.049613) (xy 79.516409 -160.88338) (xy 79.540173 -160.718091)
			(xy 79.571776 -160.554121) (xy 79.611145 -160.391839) (xy 79.65819 -160.231615) (xy 79.712807 -160.073811)
			(xy 79.774869 -159.918784) (xy 79.844239 -159.766886) (xy 79.920757 -159.61846) (xy 80.004251 -159.473844)
			(xy 80.094531 -159.333364) (xy 80.191394 -159.197339) (xy 80.294619 -159.066077) (xy 80.403972 -158.939876)
			(xy 80.519207 -158.81902) (xy 80.640062 -158.703785) (xy 80.766263 -158.59443) (xy 80.897525 -158.491204)
			(xy 81.033549 -158.394341) (xy 81.174029 -158.30406) (xy 81.318645 -158.220565) (xy 81.46707 -158.144047)
			(xy 81.618967 -158.074677) (xy 81.773994 -158.012613) (xy 81.931798 -157.957996) (xy 82.092022 -157.910949)
			(xy 82.254303 -157.87158) (xy 82.418274 -157.839976) (xy 82.583562 -157.816211) (xy 82.749795 -157.800337)
			(xy 82.916594 -157.792391) (xy 83.000088 -157.791912) (xy 83.49996 -157.791912) (xy 83.595316 -157.791414)
			(xy 83.785856 -157.783321) (xy 83.97588 -157.76715) (xy 84.165048 -157.742927) (xy 84.353016 -157.710699)
			(xy 84.539448 -157.670521) (xy 84.724006 -157.622468) (xy 84.906359 -157.566624) (xy 85.086177 -157.503092)
			(xy 85.263137 -157.431985) (xy 85.436919 -157.353432) (xy 85.607211 -157.267575) (xy 85.773706 -157.174567)
			(xy 85.936103 -157.074577) (xy 86.09411 -156.967784) (xy 86.247443 -156.854382) (xy 86.395824 -156.734574)
			(xy 86.538987 -156.608577) (xy 86.676673 -156.476617) (xy 86.808635 -156.338932) (xy 86.934634 -156.195771)
			(xy 87.054444 -156.047392) (xy 87.167848 -155.894061) (xy 87.274643 -155.736055) (xy 87.374636 -155.573659)
			(xy 87.467646 -155.407166) (xy 87.553506 -155.236875) (xy 87.632061 -155.063094) (xy 87.70317 -154.886135)
			(xy 87.766705 -154.706317) (xy 87.822551 -154.523966) (xy 87.870607 -154.339408) (xy 87.910787 -154.152977)
			(xy 87.943018 -153.965009) (xy 87.967243 -153.775842) (xy 87.983417 -153.585818) (xy 87.991512 -153.395278)
			(xy 87.99195 -153.299922) (xy 87.99195 -110.499906) (xy 87.992448 -110.374117) (xy 88.000358 -110.122665)
			(xy 88.016162 -109.871584) (xy 88.039844 -109.621124) (xy 88.071382 -109.371531) (xy 88.110744 -109.123053)
			(xy 88.15789 -108.875933) (xy 88.212776 -108.630415) (xy 88.275346 -108.386743) (xy 88.345539 -108.145157)
			(xy 88.423285 -107.905894) (xy 88.508508 -107.669191) (xy 88.601123 -107.435282) (xy 88.70104 -107.204397)
			(xy 88.80816 -106.976765) (xy 88.922376 -106.75261) (xy 89.043577 -106.532152) (xy 89.171643 -106.31561)
			(xy 89.306446 -106.103198) (xy 89.447855 -105.895124) (xy 89.59573 -105.691595) (xy 89.749925 -105.492811)
			(xy 89.910287 -105.298968) (xy 90.076658 -105.110257) (xy 90.248875 -104.926866) (xy 90.426767 -104.748974)
			(xy 90.610159 -104.576757) (xy 90.798869 -104.410386) (xy 90.992712 -104.250023) (xy 91.191497 -104.095829)
			(xy 91.395026 -103.947954) (xy 91.6031 -103.806545) (xy 91.815512 -103.671742) (xy 92.032054 -103.543676)
			(xy 92.252511 -103.422476) (xy 92.476667 -103.308259) (xy 92.704299 -103.20114) (xy 92.935184 -103.101223)
			(xy 93.169093 -103.008607) (xy 93.405796 -102.923384) (xy 93.645058 -102.845638) (xy 93.886645 -102.775445)
			(xy 94.130317 -102.712875) (xy 94.375834 -102.65799) (xy 94.622954 -102.610843) (xy 94.871433 -102.571482)
			(xy 95.121026 -102.539944) (xy 95.371486 -102.516262) (xy 95.622567 -102.500458) (xy 95.874019 -102.492548)
			(xy 95.999808 -102.492048) (xy 344.000074 -102.492048) (xy 344.125864 -102.492537) (xy 344.37732 -102.500438)
			(xy 344.628404 -102.516234) (xy 344.878867 -102.539909) (xy 345.128464 -102.57144) (xy 345.376946 -102.610795)
			(xy 345.62407 -102.657936) (xy 345.869592 -102.712815) (xy 346.113268 -102.77538) (xy 346.354859 -102.845568)
			(xy 346.594126 -102.92331) (xy 346.830833 -103.008529) (xy 347.064747 -103.101142) (xy 347.295636 -103.201056)
			(xy 347.523272 -103.308173) (xy 347.747432 -103.422387) (xy 347.967894 -103.543586) (xy 348.184439 -103.671651)
			(xy 348.396856 -103.806454) (xy 348.604933 -103.947862) (xy 348.808466 -104.095737) (xy 349.007253 -104.249932)
			(xy 349.201099 -104.410295) (xy 349.389812 -104.576667) (xy 349.573207 -104.748885) (xy 349.751101 -104.926779)
			(xy 349.923319 -105.110173) (xy 350.089692 -105.298886) (xy 350.250056 -105.492731) (xy 350.404251 -105.691518)
			(xy 350.552126 -105.895051) (xy 350.693536 -106.103128) (xy 350.828339 -106.315544) (xy 350.956404 -106.532089)
			(xy 351.077604 -106.75255) (xy 351.191819 -106.97671) (xy 351.298936 -107.204346) (xy 351.398851 -107.435235)
			(xy 351.491464 -107.669148) (xy 351.576683 -107.905855) (xy 351.654426 -108.145122) (xy 351.724615 -108.386713)
			(xy 351.78718 -108.630389) (xy 351.84206 -108.87591) (xy 351.889202 -109.123034) (xy 351.928557 -109.371517)
			(xy 351.960089 -109.621113) (xy 351.983764 -109.871576) (xy 351.999561 -110.12266) (xy 352.007463 -110.374116)
			(xy 352.007932 -110.499906) (xy 352.007932 -153.299922) (xy 352.008439 -153.395276) (xy 352.016533 -153.585814)
			(xy 352.032708 -153.775835) (xy 352.056932 -153.965) (xy 352.089163 -154.152965) (xy 352.129342 -154.339394)
			(xy 352.177398 -154.523949) (xy 352.233242 -154.706298) (xy 352.296776 -154.886113) (xy 352.367884 -155.063069)
			(xy 352.446438 -155.236848) (xy 352.532297 -155.407137) (xy 352.625305 -155.573628) (xy 352.725296 -155.736022)
			(xy 352.832089 -155.894025) (xy 352.945492 -156.047354) (xy 353.0653 -156.195732) (xy 353.191297 -156.338892)
			(xy 353.323257 -156.476574) (xy 353.460941 -156.608533) (xy 353.604101 -156.734529) (xy 353.75248 -156.854335)
			(xy 353.90581 -156.967736) (xy 354.063815 -157.074528) (xy 354.22621 -157.174517) (xy 354.392702 -157.267524)
			(xy 354.562991 -157.353381) (xy 354.736771 -157.431933) (xy 354.913728 -157.50304) (xy 355.093544 -157.566571)
			(xy 355.275894 -157.622414) (xy 355.460449 -157.670468) (xy 355.646878 -157.710646) (xy 355.834844 -157.742875)
			(xy 356.024008 -157.767097) (xy 356.21403 -157.783269) (xy 356.404568 -157.791362) (xy 356.499922 -157.791912)
			(xy 357.000048 -157.791912) (xy 357.083541 -157.79241) (xy 357.250338 -157.800358) (xy 357.416569 -157.816233)
			(xy 357.581855 -157.839999) (xy 357.745823 -157.871604) (xy 357.908102 -157.910974) (xy 358.068324 -157.958022)
			(xy 358.226126 -158.012639) (xy 358.38115 -158.074704) (xy 358.533046 -158.144074) (xy 358.681468 -158.220593)
			(xy 358.826082 -158.304088) (xy 358.966559 -158.394369) (xy 359.102581 -158.491232) (xy 359.233841 -158.594457)
			(xy 359.36004 -158.703811) (xy 359.480893 -158.819046) (xy 359.596126 -158.9399) (xy 359.705478 -159.066101)
			(xy 359.808701 -159.197362) (xy 359.905562 -159.333386) (xy 359.99584 -159.473864) (xy 360.079333 -159.618479)
			(xy 360.15585 -159.766903) (xy 360.225218 -159.9188) (xy 360.287279 -160.073825) (xy 360.341895 -160.231627)
			(xy 360.38894 -160.39185) (xy 360.428308 -160.554129) (xy 360.459909 -160.718098) (xy 360.483674 -160.883385)
			(xy 360.499546 -161.049615) (xy 360.507492 -161.216413) (xy 360.508042 -161.299906) (xy 360.508042 -166.649908)
			(xy 360.508541 -166.745263) (xy 360.516636 -166.9358) (xy 360.532809 -167.125823) (xy 360.557033 -167.314988)
			(xy 360.589264 -167.502954) (xy 360.629443 -167.689383) (xy 360.677498 -167.873938) (xy 360.733342 -168.056288)
			(xy 360.796876 -168.236104) (xy 360.867984 -168.413061) (xy 360.946538 -168.586841) (xy 361.032396 -168.75713)
			(xy 361.125405 -168.923621) (xy 361.225396 -169.086016) (xy 361.332189 -169.24402) (xy 361.445592 -169.397349)
			(xy 361.5654 -169.545728) (xy 361.691398 -169.688888) (xy 361.823357 -169.826571) (xy 361.961042 -169.95853)
			(xy 362.104203 -170.084526) (xy 362.252582 -170.204333) (xy 362.405913 -170.317734) (xy 362.563918 -170.424526)
			(xy 362.726313 -170.524515) (xy 362.892806 -170.617522) (xy 363.063096 -170.70338) (xy 363.236876 -170.781932)
			(xy 363.413834 -170.853038) (xy 363.59365 -170.91657) (xy 363.776 -170.972413) (xy 363.960556 -171.020467)
			(xy 364.146985 -171.060644) (xy 364.334952 -171.092873) (xy 364.524117 -171.117095) (xy 364.71414 -171.133267)
			(xy 364.904677 -171.14136) (xy 365.000032 -171.141898) (xy 403.999954 -171.141898) (xy 404.09531 -171.1414)
			(xy 404.28585 -171.133308) (xy 404.475874 -171.117136) (xy 404.665041 -171.092914) (xy 404.85301 -171.060686)
			(xy 405.039441 -171.020508) (xy 405.224 -170.972455) (xy 405.406352 -170.916612) (xy 405.58617 -170.85308)
			(xy 405.76313 -170.781973) (xy 405.936913 -170.70342) (xy 406.107205 -170.617562) (xy 406.273699 -170.524554)
			(xy 406.436096 -170.424564) (xy 406.594104 -170.317772) (xy 406.747436 -170.204369) (xy 406.895817 -170.084561)
			(xy 407.03898 -169.958564) (xy 407.176666 -169.826604) (xy 407.308627 -169.688919) (xy 407.434627 -169.545758)
			(xy 407.554436 -169.397379) (xy 407.66784 -169.244048) (xy 407.774635 -169.086042) (xy 407.874627 -168.923646)
			(xy 407.967637 -168.757152) (xy 408.053497 -168.586861) (xy 408.132052 -168.41308) (xy 408.20316 -168.236121)
			(xy 408.266695 -168.056304) (xy 408.32254 -167.873952) (xy 408.370596 -167.689394) (xy 408.410775 -167.502963)
			(xy 408.443006 -167.314995) (xy 408.46723 -167.125828) (xy 408.483404 -166.935803) (xy 408.491499 -166.745264)
			(xy 408.491944 -166.649908) (xy 408.491944 -163.299902) (xy 408.492443 -163.194388) (xy 408.500526 -162.983513)
			(xy 408.51668 -162.773104) (xy 408.540882 -162.563467) (xy 408.573095 -162.354911) (xy 408.613273 -162.147742)
			(xy 408.661357 -161.942264) (xy 408.717276 -161.738779) (xy 408.780948 -161.537585) (xy 408.85228 -161.338977)
			(xy 408.931166 -161.143247) (xy 409.017492 -160.950683) (xy 409.11113 -160.761566) (xy 409.211943 -160.576175)
			(xy 409.319783 -160.394781) (xy 409.434492 -160.217651) (xy 409.555901 -160.045044) (xy 409.683832 -159.877215)
			(xy 409.818098 -159.714408) (xy 409.958502 -159.556864) (xy 410.104837 -159.404814) (xy 410.256888 -159.25848)
			(xy 410.414433 -159.118078) (xy 410.57724 -158.983813) (xy 410.74507 -158.855882) (xy 410.917677 -158.734474)
			(xy 411.094808 -158.619766) (xy 411.276203 -158.511927) (xy 411.461595 -158.411115) (xy 411.650712 -158.317478)
			(xy 411.843277 -158.231154) (xy 412.039007 -158.152268) (xy 412.237615 -158.080938) (xy 412.43881 -158.017267)
			(xy 412.642296 -157.961349) (xy 412.847774 -157.913267) (xy 413.054943 -157.87309) (xy 413.263499 -157.840877)
			(xy 413.473136 -157.816677) (xy 413.683545 -157.800524) (xy 413.89442 -157.792443) (xy 413.999934 -157.791912)
			(xy 434.999892 -157.791912) (xy 435.095247 -157.791406) (xy 435.285786 -157.783312) (xy 435.475809 -157.767139)
			(xy 435.664975 -157.742916) (xy 435.852942 -157.710686) (xy 436.039373 -157.670508) (xy 436.223929 -157.622454)
			(xy 436.406281 -157.56661) (xy 436.586097 -157.503077) (xy 436.763056 -157.43197) (xy 436.936837 -157.353416)
			(xy 437.107127 -157.267558) (xy 437.27362 -157.17455) (xy 437.436016 -157.07456) (xy 437.594022 -156.967767)
			(xy 437.747353 -156.854365) (xy 437.895733 -156.734557) (xy 438.038894 -156.60856) (xy 438.176579 -156.476601)
			(xy 438.30854 -156.338916) (xy 438.434538 -156.195756) (xy 438.554346 -156.047377) (xy 438.66775 -155.894046)
			(xy 438.774543 -155.736041) (xy 438.874535 -155.573646) (xy 438.967544 -155.407154) (xy 439.053403 -155.236864)
			(xy 439.131958 -155.063083) (xy 439.203066 -154.886125) (xy 439.2666 -154.706309) (xy 439.322445 -154.523958)
			(xy 439.370501 -154.339402) (xy 439.410681 -154.152972) (xy 439.442912 -153.965005) (xy 439.467136 -153.775839)
			(xy 439.483311 -153.585816) (xy 439.491405 -153.395277) (xy 439.491882 -153.299922) (xy 439.491882 -136.77011)
			(xy 439.492393 -136.664597) (xy 439.500486 -136.453727) (xy 439.51665 -136.243322) (xy 439.540861 -136.03369)
			(xy 439.573083 -135.82514) (xy 439.613269 -135.617976) (xy 439.661359 -135.412504) (xy 439.717285 -135.209024)
			(xy 439.780962 -135.007835) (xy 439.852299 -134.809233) (xy 439.931189 -134.613509) (xy 440.017518 -134.42095)
			(xy 440.111159 -134.231839) (xy 440.211974 -134.046453) (xy 440.319816 -133.865064) (xy 440.434526 -133.687939)
			(xy 440.555935 -133.515337) (xy 440.683866 -133.347512) (xy 440.818131 -133.18471) (xy 440.958533 -133.02717)
			(xy 441.104866 -132.875122) (xy 441.256915 -132.728791) (xy 441.414457 -132.588391) (xy 441.577261 -132.454128)
			(xy 441.745087 -132.326199) (xy 441.91769 -132.204791) (xy 442.094817 -132.090083) (xy 442.276207 -131.982244)
			(xy 442.461594 -131.881431) (xy 442.650706 -131.787792) (xy 442.843266 -131.701465) (xy 443.038991 -131.622577)
			(xy 443.237594 -131.551242) (xy 443.438783 -131.487567) (xy 443.642264 -131.431644) (xy 443.847737 -131.383556)
			(xy 444.054901 -131.343372) (xy 444.263452 -131.311152) (xy 444.473084 -131.286944) (xy 444.683489 -131.270783)
			(xy 444.894359 -131.262691) (xy 444.999872 -131.26212) (xy 471.000074 -131.26212) (xy 471.09543 -131.261614)
			(xy 471.285969 -131.253522) (xy 471.475993 -131.237349) (xy 471.665159 -131.213127) (xy 471.853128 -131.180897)
			(xy 472.039558 -131.14072) (xy 472.224116 -131.092666) (xy 472.406468 -131.036822) (xy 472.586285 -130.97329)
			(xy 472.763245 -130.902183) (xy 472.937026 -130.82363) (xy 473.107318 -130.737772) (xy 473.273812 -130.644764)
			(xy 473.436208 -130.544774) (xy 473.594215 -130.437982) (xy 473.747547 -130.32458) (xy 473.895928 -130.204772)
			(xy 474.03909 -130.078775) (xy 474.176776 -129.946815) (xy 474.308737 -129.809131) (xy 474.434736 -129.66597)
			(xy 474.554545 -129.517591) (xy 474.667949 -129.364261) (xy 474.774744 -129.206255) (xy 474.874736 -129.04386)
			(xy 474.967746 -128.877367) (xy 475.053606 -128.707077) (xy 475.132161 -128.533296) (xy 475.20327 -128.356338)
			(xy 475.266805 -128.176521) (xy 475.32265 -127.99417) (xy 475.370707 -127.809613) (xy 475.410887 -127.623182)
			(xy 475.443118 -127.435215) (xy 475.467343 -127.246049) (xy 475.483518 -127.056025) (xy 475.491613 -126.865486)
			(xy 475.492064 -126.77013) (xy 475.492064 -21.770086) (xy 475.491565 -21.674731) (xy 475.48347 -21.484194)
			(xy 475.467296 -21.294171) (xy 475.443072 -21.105007) (xy 475.410841 -20.917041) (xy 475.370662 -20.730612)
			(xy 475.322607 -20.546056) (xy 475.266762 -20.363706) (xy 475.203229 -20.183891) (xy 475.132121 -20.006934)
			(xy 475.053567 -19.833155) (xy 474.967708 -19.662865) (xy 474.874699 -19.496374) (xy 474.774708 -19.33398)
			(xy 474.667915 -19.175975) (xy 474.554512 -19.022646) (xy 474.434704 -18.874268) (xy 474.308707 -18.731108)
			(xy 474.176747 -18.593425) (xy 474.039062 -18.461466) (xy 473.895902 -18.33547) (xy 473.747522 -18.215663)
			(xy 473.594192 -18.102262) (xy 473.436187 -17.99547) (xy 473.273792 -17.895481) (xy 473.107299 -17.802473)
			(xy 472.937009 -17.716616) (xy 472.763229 -17.638064) (xy 472.586272 -17.566957) (xy 472.406456 -17.503425)
			(xy 472.224105 -17.447582) (xy 472.039549 -17.399529) (xy 471.85312 -17.359351) (xy 471.665154 -17.327122)
			(xy 471.475989 -17.3029) (xy 471.285966 -17.286727) (xy 471.095429 -17.278635) (xy 471.000074 -17.278096)
			(xy 444.999872 -17.278096) (xy 444.894359 -17.277587) (xy 444.683488 -17.269495) (xy 444.473081 -17.253334)
			(xy 444.263448 -17.229125) (xy 444.054895 -17.196905) (xy 443.84773 -17.156721) (xy 443.642256 -17.108631)
			(xy 443.438775 -17.052708) (xy 443.237584 -16.989031) (xy 443.038981 -16.917696) (xy 442.843255 -16.838806)
			(xy 442.650694 -16.752478) (xy 442.461581 -16.658838) (xy 442.276194 -16.558023) (xy 442.094803 -16.450182)
			(xy 441.917676 -16.335473) (xy 441.745073 -16.214064) (xy 441.577246 -16.086133) (xy 441.414443 -15.951868)
			(xy 441.256901 -15.811465) (xy 441.104852 -15.665132) (xy 440.95852 -15.513083) (xy 440.818118 -15.355541)
			(xy 440.683854 -15.192737) (xy 440.555923 -15.024909) (xy 440.434515 -14.852305) (xy 440.319806 -14.675178)
			(xy 440.211966 -14.493787) (xy 440.111152 -14.308399) (xy 440.017512 -14.119286) (xy 439.931185 -13.926725)
			(xy 439.852296 -13.730999) (xy 439.780962 -13.532395) (xy 439.717286 -13.331204) (xy 439.661363 -13.127723)
			(xy 439.613275 -12.922248) (xy 439.573091 -12.715083) (xy 439.540872 -12.506531) (xy 439.516664 -12.296897)
			(xy 439.500503 -12.086491) (xy 439.492413 -11.875619) (xy 439.491882 -11.770106) (xy 439.491882 -4.99999)
			(xy 439.491376 -4.904635) (xy 439.483281 -4.714098) (xy 439.467108 -4.524075) (xy 439.442884 -4.33491)
			(xy 439.410653 -4.146944) (xy 439.370474 -3.960515) (xy 439.322419 -3.775959) (xy 439.266575 -3.593609)
			(xy 439.203041 -3.413794) (xy 439.131934 -3.236837) (xy 439.05338 -3.063057) (xy 438.967522 -2.892768)
			(xy 438.874513 -2.726276) (xy 438.774522 -2.563881) (xy 438.66773 -2.405877) (xy 438.554327 -2.252547)
			(xy 438.434519 -2.104169) (xy 438.308522 -1.961009) (xy 438.176562 -1.823325) (xy 438.038878 -1.691366)
			(xy 437.895718 -1.565369) (xy 437.747339 -1.445562) (xy 437.594008 -1.33216) (xy 437.436004 -1.225368)
			(xy 437.273609 -1.125378) (xy 437.107116 -1.03237) (xy 436.936827 -0.946512) (xy 436.763047 -0.867959)
			(xy 436.586089 -0.796852) (xy 436.406274 -0.73332) (xy 436.223923 -0.677476) (xy 436.039367 -0.629422)
			(xy 435.852938 -0.589243) (xy 435.664972 -0.557014) (xy 435.475807 -0.53279) (xy 435.285784 -0.516618)
			(xy 435.095247 -0.508524) (xy 434.999892 -0.508) (xy 4.99999 -0.508) (xy 4.904635 -0.508506) (xy 4.714097 -0.5166)
			(xy 4.524074 -0.532773) (xy 4.334909 -0.556997) (xy 4.146942 -0.589227) (xy 3.960513 -0.629406) (xy 3.775956 -0.67746)
			(xy 3.593606 -0.733305) (xy 3.41379 -0.796838) (xy 3.236832 -0.867945) (xy 3.063052 -0.946499) (xy 2.892762 -1.032357)
			(xy 2.72627 -1.125365) (xy 2.563875 -1.225356) (xy 2.40587 -1.332149) (xy 2.25254 -1.445551) (xy 2.10416 -1.565359)
			(xy 1.961 -1.691356) (xy 1.823316 -1.823316) (xy 1.691356 -1.961) (xy 1.565359 -2.10416) (xy 1.445551 -2.25254)
			(xy 1.332149 -2.40587) (xy 1.225356 -2.563875) (xy 1.125365 -2.72627) (xy 1.032357 -2.892762) (xy 0.946499 -3.063052)
			(xy 0.867945 -3.236832) (xy 0.796838 -3.41379) (xy 0.733305 -3.593606) (xy 0.67746 -3.775956) (xy 0.629406 -3.960513)
			(xy 0.589227 -4.146942) (xy 0.556997 -4.334909) (xy 0.532773 -4.524074) (xy 0.5166 -4.714097) (xy 0.508506 -4.904635)
			(xy 0.508 -4.99999) (xy 0.508 -153.299922) (xy 1.015746 -153.299922) (xy 1.015746 -4.99999) (xy 1.016248 -4.91058)
			(xy 1.02427 -4.73194) (xy 1.0403 -4.55384) (xy 1.064303 -4.376638) (xy 1.096233 -4.200692) (xy 1.136024 -4.026356)
			(xy 1.183597 -3.85398) (xy 1.238855 -3.683912) (xy 1.301688 -3.516495) (xy 1.371969 -3.352065) (xy 1.449556 -3.190953)
			(xy 1.534293 -3.033485) (xy 1.62601 -2.879978) (xy 1.724521 -2.730739) (xy 1.829629 -2.586071) (xy 1.941121 -2.446264)
			(xy 2.058774 -2.3116) (xy 2.182349 -2.182349) (xy 2.3116 -2.058774) (xy 2.446264 -1.941121) (xy 2.586071 -1.829629)
			(xy 2.730739 -1.724521) (xy 2.879978 -1.62601) (xy 3.033485 -1.534293) (xy 3.190953 -1.449556) (xy 3.352065 -1.371969)
			(xy 3.516495 -1.301688) (xy 3.683912 -1.238855) (xy 3.85398 -1.183597) (xy 4.026356 -1.136024) (xy 4.200692 -1.096233)
			(xy 4.376638 -1.064303) (xy 4.55384 -1.0403) (xy 4.73194 -1.02427) (xy 4.91058 -1.016248) (xy 4.99999 -1.015746)
			(xy 434.999892 -1.015746) (xy 435.089302 -1.016266) (xy 435.267941 -1.024288) (xy 435.446041 -1.040317)
			(xy 435.623242 -1.06432) (xy 435.799188 -1.096249) (xy 435.973524 -1.13604) (xy 436.1459 -1.183612)
			(xy 436.315967 -1.23887) (xy 436.483385 -1.301702) (xy 436.647814 -1.371982) (xy 436.808925 -1.449569)
			(xy 436.966393 -1.534306) (xy 437.119901 -1.626022) (xy 437.269139 -1.724533) (xy 437.413807 -1.82964)
			(xy 437.553614 -1.941132) (xy 437.688278 -2.058784) (xy 437.817529 -2.182359) (xy 437.941104 -2.311608)
			(xy 438.058757 -2.446272) (xy 438.170249 -2.586078) (xy 438.275357 -2.730746) (xy 438.373869 -2.879984)
			(xy 438.465585 -3.033491) (xy 438.550323 -3.190959) (xy 438.62791 -3.352069) (xy 438.698191 -3.516499)
			(xy 438.761024 -3.683916) (xy 438.816283 -3.853983) (xy 438.863856 -4.026358) (xy 438.903647 -4.200694)
			(xy 438.935577 -4.37664) (xy 438.959581 -4.553841) (xy 438.975611 -4.731941) (xy 438.983634 -4.91058)
			(xy 438.984136 -4.99999) (xy 438.984136 -11.770106) (xy 438.984663 -11.879986) (xy 438.992696 -12.099598)
			(xy 439.008745 -12.318771) (xy 439.032786 -12.537211) (xy 439.06479 -12.754627) (xy 439.104711 -12.97073)
			(xy 439.152499 -13.185231) (xy 439.208088 -13.397843) (xy 439.271405 -13.608283) (xy 439.342365 -13.816271)
			(xy 439.420873 -14.021528) (xy 439.506825 -14.223781) (xy 439.600107 -14.422761) (xy 439.700592 -14.6182)
			(xy 439.808148 -14.80984) (xy 439.922632 -14.997424) (xy 440.043889 -15.180702) (xy 440.171759 -15.359429)
			(xy 440.306071 -15.533367) (xy 440.446645 -15.702284) (xy 440.593295 -15.865955) (xy 440.745824 -16.024161)
			(xy 440.904029 -16.17669) (xy 441.067699 -16.32334) (xy 441.236615 -16.463916) (xy 441.410553 -16.598228)
			(xy 441.58928 -16.726099) (xy 441.772557 -16.847357) (xy 441.960141 -16.961841) (xy 442.15178 -17.069397)
			(xy 442.34722 -17.169884) (xy 442.546199 -17.263166) (xy 442.748452 -17.349118) (xy 442.953709 -17.427628)
			(xy 443.161696 -17.498588) (xy 443.372136 -17.561906) (xy 443.584748 -17.617496) (xy 443.799248 -17.665284)
			(xy 444.015351 -17.705207) (xy 444.232767 -17.737211) (xy 444.451208 -17.761253) (xy 444.67038 -17.777302)
			(xy 444.889992 -17.785336) (xy 444.999872 -17.785842) (xy 471.000074 -17.785842) (xy 471.089484 -17.786376)
			(xy 471.268123 -17.794397) (xy 471.446223 -17.810425) (xy 471.623424 -17.834428) (xy 471.79937 -17.866356)
			(xy 471.973706 -17.906146) (xy 472.146082 -17.953718) (xy 472.31615 -18.008975) (xy 472.483567 -18.071807)
			(xy 472.647997 -18.142086) (xy 472.809108 -18.219672) (xy 472.966576 -18.304408) (xy 473.120084 -18.396124)
			(xy 473.269323 -18.494634) (xy 473.413991 -18.599741) (xy 473.553798 -18.711232) (xy 473.688463 -18.828884)
			(xy 473.817713 -18.952458) (xy 473.941289 -19.081708) (xy 474.058942 -19.216371) (xy 474.170435 -19.356177)
			(xy 474.275543 -19.500844) (xy 474.374055 -19.650082) (xy 474.465772 -19.803589) (xy 474.55051 -19.961056)
			(xy 474.628097 -20.122167) (xy 474.698379 -20.286596) (xy 474.761212 -20.454012) (xy 474.816471 -20.62408)
			(xy 474.864044 -20.796455) (xy 474.903836 -20.970791) (xy 474.935766 -21.146736) (xy 474.95977 -21.323937)
			(xy 474.9758 -21.502037) (xy 474.983823 -21.680676) (xy 474.984318 -21.770086) (xy 474.984318 -126.77013)
			(xy 474.983872 -126.859541) (xy 474.975847 -127.038182) (xy 474.959817 -127.216283) (xy 474.935812 -127.393485)
			(xy 474.903881 -127.569433) (xy 474.864088 -127.74377) (xy 474.816514 -127.916147) (xy 474.761254 -128.086215)
			(xy 474.698419 -128.253634) (xy 474.628137 -128.418064) (xy 474.550548 -128.579176) (xy 474.465809 -128.736644)
			(xy 474.374091 -128.890153) (xy 474.275578 -129.039391) (xy 474.170468 -129.18406) (xy 474.058974 -129.323867)
			(xy 473.94132 -129.458531) (xy 473.817742 -129.587782) (xy 473.68849 -129.711357) (xy 473.553824 -129.82901)
			(xy 473.414015 -129.940502) (xy 473.269345 -130.045609) (xy 473.120105 -130.14412) (xy 472.966596 -130.235837)
			(xy 472.809126 -130.320573) (xy 472.648013 -130.39816) (xy 472.483582 -130.46844) (xy 472.316163 -130.531272)
			(xy 472.146093 -130.58653) (xy 471.973716 -130.634102) (xy 471.799378 -130.673892) (xy 471.62343 -130.70582)
			(xy 471.446227 -130.729823) (xy 471.268126 -130.745851) (xy 471.089485 -130.753873) (xy 471.000074 -130.754374)
			(xy 444.999872 -130.754374) (xy 444.889993 -130.754942) (xy 444.670382 -130.762976) (xy 444.45121 -130.779024)
			(xy 444.232771 -130.803066) (xy 444.015356 -130.83507) (xy 443.799255 -130.874992) (xy 443.584755 -130.92278)
			(xy 443.372144 -130.978369) (xy 443.161705 -131.041686) (xy 442.953719 -131.112645) (xy 442.748462 -131.191154)
			(xy 442.54621 -131.277105) (xy 442.347232 -131.370386) (xy 442.151793 -131.470871) (xy 441.960154 -131.578426)
			(xy 441.772571 -131.692909) (xy 441.589294 -131.814165) (xy 441.410567 -131.942034) (xy 441.23663 -132.076345)
			(xy 441.067713 -132.216918) (xy 440.904043 -132.363566) (xy 440.745838 -132.516094) (xy 440.593309 -132.674298)
			(xy 440.446659 -132.837966) (xy 440.306083 -133.006881) (xy 440.171771 -133.180818) (xy 440.0439 -133.359543)
			(xy 439.922642 -133.542819) (xy 439.808158 -133.730401) (xy 439.7006 -133.922038) (xy 439.600113 -134.117476)
			(xy 439.50683 -134.316454) (xy 439.420877 -134.518705) (xy 439.342367 -134.72396) (xy 439.271405 -134.931946)
			(xy 439.208086 -135.142384) (xy 439.152494 -135.354995) (xy 439.104705 -135.569494) (xy 439.06478 -135.785595)
			(xy 439.032774 -136.00301) (xy 439.00873 -136.221449) (xy 438.992679 -136.44062) (xy 438.984643 -136.660231)
			(xy 438.984136 -136.77011) (xy 438.984136 -153.299922) (xy 438.983664 -153.389332) (xy 438.97564 -153.567973)
			(xy 438.95961 -153.746073) (xy 438.935605 -153.923275) (xy 438.903675 -154.099222) (xy 438.863882 -154.273559)
			(xy 438.816309 -154.445935) (xy 438.761049 -154.616003) (xy 438.698216 -154.783421) (xy 438.627934 -154.947851)
			(xy 438.550346 -155.108962) (xy 438.465608 -155.266431) (xy 438.37389 -155.419939) (xy 438.275378 -155.569177)
			(xy 438.170269 -155.713845) (xy 438.058776 -155.853652) (xy 437.941122 -155.988317) (xy 437.817546 -156.117567)
			(xy 437.688294 -156.241142) (xy 437.553629 -156.358795) (xy 437.413821 -156.470287) (xy 437.269152 -156.575395)
			(xy 437.119913 -156.673906) (xy 436.966405 -156.765622) (xy 436.808936 -156.850359) (xy 436.647824 -156.927946)
			(xy 436.483393 -156.998227) (xy 436.315975 -157.061059) (xy 436.145906 -157.116317) (xy 435.97353 -157.16389)
			(xy 435.799193 -157.203681) (xy 435.623246 -157.23561) (xy 435.446043 -157.259613) (xy 435.267943 -157.275642)
			(xy 435.089302 -157.283664) (xy 434.999892 -157.284166) (xy 413.999934 -157.284166) (xy 413.890053 -157.284693)
			(xy 413.670438 -157.292718) (xy 413.451263 -157.308759) (xy 413.232819 -157.332793) (xy 413.015399 -157.36479)
			(xy 412.799293 -157.404705) (xy 412.584789 -157.452487) (xy 412.372173 -157.508071) (xy 412.161729 -157.571383)
			(xy 411.953737 -157.642339) (xy 411.748476 -157.720844) (xy 411.546219 -157.806793) (xy 411.347236 -157.900071)
			(xy 411.151792 -158.000555) (xy 410.960149 -158.10811) (xy 410.772561 -158.222592) (xy 410.58928 -158.343848)
			(xy 410.41055 -158.471718) (xy 410.236609 -158.60603) (xy 410.067689 -158.746605) (xy 409.904016 -158.893256)
			(xy 409.745809 -159.045786) (xy 409.593277 -159.203993) (xy 409.446626 -159.367665) (xy 409.30605 -159.536584)
			(xy 409.171737 -159.710524) (xy 409.043866 -159.889254) (xy 408.922609 -160.072534) (xy 408.808126 -160.260121)
			(xy 408.70057 -160.451764) (xy 408.600086 -160.647207) (xy 408.506806 -160.84619) (xy 408.420856 -161.048446)
			(xy 408.34235 -161.253707) (xy 408.271393 -161.461698) (xy 408.20808 -161.672142) (xy 408.152495 -161.884758)
			(xy 408.104712 -162.099262) (xy 408.064795 -162.315368) (xy 408.032797 -162.532788) (xy 408.008762 -162.751231)
			(xy 407.99272 -162.970406) (xy 407.984694 -163.190021) (xy 407.984198 -163.299902) (xy 407.984198 -166.649908)
			(xy 407.983758 -166.739319) (xy 407.975734 -166.917961) (xy 407.959704 -167.096062) (xy 407.9357 -167.273266)
			(xy 407.90377 -167.449214) (xy 407.863978 -167.623552) (xy 407.816404 -167.795929) (xy 407.761144 -167.965998)
			(xy 407.69831 -168.133417) (xy 407.628028 -168.297848) (xy 407.550439 -168.458961) (xy 407.4657 -168.61643)
			(xy 407.373982 -168.769939) (xy 407.275469 -168.919178) (xy 407.170359 -169.063847) (xy 407.058865 -169.203655)
			(xy 406.94121 -169.33832) (xy 406.817632 -169.467571) (xy 406.68838 -169.591147) (xy 406.553714 -169.7088)
			(xy 406.413904 -169.820292) (xy 406.269234 -169.9254) (xy 406.119993 -170.023911) (xy 405.966483 -170.115627)
			(xy 405.809013 -170.200364) (xy 405.647899 -170.27795) (xy 405.483467 -170.34823) (xy 405.316047 -170.411062)
			(xy 405.145977 -170.466319) (xy 404.973599 -170.513891) (xy 404.799261 -170.553681) (xy 404.623312 -170.585609)
			(xy 404.446109 -170.609611) (xy 404.268007 -170.625638) (xy 404.089365 -170.633659) (xy 403.999954 -170.634152)
			(xy 365.000032 -170.634152) (xy 364.910622 -170.633618) (xy 364.731983 -170.625597) (xy 364.553883 -170.609569)
			(xy 364.376682 -170.585567) (xy 364.200735 -170.553639) (xy 364.026399 -170.513849) (xy 363.854023 -170.466278)
			(xy 363.683955 -170.411021) (xy 363.516538 -170.348189) (xy 363.352108 -170.27791) (xy 363.190997 -170.200324)
			(xy 363.033528 -170.115588) (xy 362.88002 -170.023872) (xy 362.730782 -169.925362) (xy 362.586113 -169.820255)
			(xy 362.446306 -169.708764) (xy 362.311641 -169.591112) (xy 362.182391 -169.467537) (xy 362.058815 -169.338288)
			(xy 361.941162 -169.203625) (xy 361.829669 -169.063819) (xy 361.724561 -168.919151) (xy 361.626049 -168.769913)
			(xy 361.534332 -168.616406) (xy 361.449594 -168.458939) (xy 361.372007 -168.297828) (xy 361.301726 -168.133399)
			(xy 361.238893 -167.965982) (xy 361.183634 -167.795915) (xy 361.136061 -167.62354) (xy 361.096269 -167.449204)
			(xy 361.064339 -167.273258) (xy 361.040335 -167.096057) (xy 361.024305 -166.917957) (xy 361.016282 -166.739318)
			(xy 361.015788 -166.649908) (xy 361.015788 -161.299906) (xy 361.015228 -161.20979) (xy 361.007143 -161.029739)
			(xy 360.990987 -160.850233) (xy 360.966795 -160.671632) (xy 360.934613 -160.494296) (xy 360.894508 -160.318583)
			(xy 360.846561 -160.144845) (xy 360.790866 -159.973434) (xy 360.727538 -159.804695) (xy 360.656703 -159.638966)
			(xy 360.578504 -159.476582) (xy 360.493098 -159.31787) (xy 360.400658 -159.16315) (xy 360.30137 -159.012732)
			(xy 360.195433 -158.866921) (xy 360.083061 -158.726009) (xy 359.96448 -158.590281) (xy 359.839929 -158.460009)
			(xy 359.709659 -158.335456) (xy 359.573933 -158.216874) (xy 359.433022 -158.1045) (xy 359.287212 -157.998561)
			(xy 359.136796 -157.89927) (xy 358.982077 -157.806828) (xy 358.823366 -157.72142) (xy 358.660983 -157.643219)
			(xy 358.495256 -157.572382) (xy 358.326517 -157.509051) (xy 358.155106 -157.453355) (xy 357.98137 -157.405405)
			(xy 357.805657 -157.365298) (xy 357.628322 -157.333114) (xy 357.449721 -157.308919) (xy 357.270215 -157.292761)
			(xy 357.090164 -157.284673) (xy 357.000048 -157.284166) (xy 356.499922 -157.284166) (xy 356.410513 -157.283621)
			(xy 356.231874 -157.275599) (xy 356.053774 -157.259571) (xy 355.876574 -157.235568) (xy 355.700628 -157.20364)
			(xy 355.526292 -157.16385) (xy 355.353917 -157.116279) (xy 355.18385 -157.061021) (xy 355.016433 -156.99819)
			(xy 354.852004 -156.92791) (xy 354.690893 -156.850325) (xy 354.533425 -156.765589) (xy 354.379918 -156.673874)
			(xy 354.23068 -156.575364) (xy 354.086012 -156.470257) (xy 353.946205 -156.358766) (xy 353.811541 -156.241115)
			(xy 353.682291 -156.117541) (xy 353.558715 -155.988292) (xy 353.441062 -155.853629) (xy 353.329569 -155.713823)
			(xy 353.224462 -155.569156) (xy 353.12595 -155.419919) (xy 353.034233 -155.266413) (xy 352.949495 -155.108946)
			(xy 352.871908 -154.947836) (xy 352.801627 -154.783408) (xy 352.738793 -154.615992) (xy 352.683534 -154.445925)
			(xy 352.635961 -154.27355) (xy 352.596169 -154.099215) (xy 352.564239 -153.92327) (xy 352.540234 -153.746069)
			(xy 352.524204 -153.56797) (xy 352.51618 -153.389331) (xy 352.515678 -153.299922) (xy 352.515678 -110.499906)
			(xy 352.515198 -110.368763) (xy 352.507121 -110.106602) (xy 352.490975 -109.844813) (xy 352.466774 -109.583647)
			(xy 352.434543 -109.323349) (xy 352.39431 -109.064167) (xy 352.346115 -108.806347) (xy 352.290004 -108.550134)
			(xy 352.226029 -108.29577) (xy 352.154251 -108.043497) (xy 352.074738 -107.793553) (xy 351.987566 -107.546177)
			(xy 351.892818 -107.301603) (xy 351.790582 -107.060063) (xy 351.680957 -106.821785) (xy 351.564046 -106.586997)
			(xy 351.439961 -106.35592) (xy 351.308818 -106.128774) (xy 351.170742 -105.905774) (xy 351.025864 -105.687132)
			(xy 350.874322 -105.473055) (xy 350.716259 -105.263747) (xy 350.551826 -105.059405) (xy 350.381178 -104.860224)
			(xy 350.204477 -104.666393) (xy 350.021891 -104.478095) (xy 349.833592 -104.295509) (xy 349.639761 -104.118809)
			(xy 349.440579 -103.948161) (xy 349.236237 -103.783728) (xy 349.026928 -103.625666) (xy 348.812851 -103.474125)
			(xy 348.594209 -103.329248) (xy 348.371209 -103.191172) (xy 348.144063 -103.06003) (xy 347.912985 -102.935944)
			(xy 347.678197 -102.819034) (xy 347.439919 -102.70941) (xy 347.198378 -102.607175) (xy 346.953804 -102.512427)
			(xy 346.706428 -102.425255) (xy 346.456484 -102.345743) (xy 346.204211 -102.273966) (xy 345.949847 -102.209992)
			(xy 345.693633 -102.153881) (xy 345.435813 -102.105686) (xy 345.176631 -102.065455) (xy 344.916334 -102.033223)
			(xy 344.655167 -102.009024) (xy 344.393378 -101.992878) (xy 344.131217 -101.984801) (xy 344.000074 -101.984302)
			(xy 95.999808 -101.984302) (xy 95.868667 -101.984813) (xy 95.606508 -101.992897) (xy 95.344723 -102.009051)
			(xy 95.083559 -102.033258) (xy 94.823265 -102.065496) (xy 94.564087 -102.105734) (xy 94.306271 -102.153934)
			(xy 94.050062 -102.210051) (xy 93.795702 -102.27403) (xy 93.543432 -102.345812) (xy 93.293493 -102.425329)
			(xy 93.046121 -102.512504) (xy 92.801551 -102.607255) (xy 92.560015 -102.709493) (xy 92.321741 -102.81912)
			(xy 92.086957 -102.936032) (xy 91.855883 -103.060119) (xy 91.628741 -103.191263) (xy 91.405745 -103.329339)
			(xy 91.187106 -103.474217) (xy 90.973032 -103.625758) (xy 90.763727 -103.78382) (xy 90.559388 -103.948253)
			(xy 90.360209 -104.118899) (xy 90.16638 -104.295598) (xy 89.978084 -104.478183) (xy 89.7955 -104.666479)
			(xy 89.618801 -104.860308) (xy 89.448154 -105.059486) (xy 89.283722 -105.263825) (xy 89.12566 -105.473131)
			(xy 88.974118 -105.687204) (xy 88.82924 -105.905843) (xy 88.691164 -106.128839) (xy 88.56002 -106.355982)
			(xy 88.435933 -106.587055) (xy 88.319021 -106.82184) (xy 88.209394 -107.060113) (xy 88.107156 -107.301649)
			(xy 88.012404 -107.54622) (xy 87.925229 -107.793591) (xy 87.845713 -108.043531) (xy 87.773931 -108.2958)
			(xy 87.709951 -108.55016) (xy 87.653835 -108.806369) (xy 87.605634 -109.064185) (xy 87.565396 -109.323363)
			(xy 87.533158 -109.583657) (xy 87.508951 -109.844821) (xy 87.492797 -110.106606) (xy 87.484713 -110.368765)
			(xy 87.484204 -110.499906) (xy 87.484204 -153.299922) (xy 87.483771 -153.389333) (xy 87.475747 -153.567975)
			(xy 87.459717 -153.746076) (xy 87.435712 -153.92328) (xy 87.403781 -154.099228) (xy 87.363988 -154.273566)
			(xy 87.316414 -154.445943) (xy 87.261154 -154.616012) (xy 87.19832 -154.783431) (xy 87.128037 -154.947862)
			(xy 87.050448 -155.108974) (xy 86.965709 -155.266443) (xy 86.87399 -155.419952) (xy 86.775477 -155.569191)
			(xy 86.670367 -155.71386) (xy 86.558872 -155.853668) (xy 86.441218 -155.988333) (xy 86.31764 -156.117583)
			(xy 86.188387 -156.241159) (xy 86.053721 -156.358812) (xy 85.913911 -156.470305) (xy 85.76924 -156.575412)
			(xy 85.62 -156.673923) (xy 85.46649 -156.76564) (xy 85.309019 -156.850376) (xy 85.147906 -156.927963)
			(xy 84.983473 -156.998243) (xy 84.816054 -157.061075) (xy 84.645983 -157.116332) (xy 84.473605 -157.163904)
			(xy 84.299267 -157.203694) (xy 84.123318 -157.235622) (xy 83.946115 -157.259624) (xy 83.768013 -157.275652)
			(xy 83.589371 -157.283673) (xy 83.49996 -157.284166) (xy 83.000088 -157.284166) (xy 82.909971 -157.284654)
			(xy 82.729919 -157.292741) (xy 82.55041 -157.308897) (xy 82.371808 -157.333091) (xy 82.19447 -157.365274)
			(xy 82.018755 -157.40538) (xy 81.845017 -157.453329) (xy 81.673604 -157.509025) (xy 81.504863 -157.572355)
			(xy 81.339133 -157.643192) (xy 81.176748 -157.721393) (xy 81.018035 -157.806801) (xy 80.863314 -157.899243)
			(xy 80.712896 -157.998534) (xy 80.567084 -158.104473) (xy 80.426171 -158.216847) (xy 80.290443 -158.33543)
			(xy 80.160171 -158.459983) (xy 80.035618 -158.590256) (xy 79.917036 -158.725985) (xy 79.804662 -158.866898)
			(xy 79.698723 -159.01271) (xy 79.599433 -159.163129) (xy 79.506992 -159.317851) (xy 79.421585 -159.476564)
			(xy 79.343385 -159.638949) (xy 79.272548 -159.80468) (xy 79.209219 -159.973421) (xy 79.153524 -160.144834)
			(xy 79.105575 -160.318573) (xy 79.06547 -160.494288) (xy 79.033288 -160.671625) (xy 79.009095 -160.850228)
			(xy 78.992939 -161.029737) (xy 78.984854 -161.209789) (xy 78.984348 -161.299906) (xy 78.984348 -166.649908)
			(xy 78.98385 -166.739318) (xy 78.975827 -166.917958) (xy 78.959797 -167.096058) (xy 78.935794 -167.273259)
			(xy 78.903864 -167.449206) (xy 78.864072 -167.623542) (xy 78.816499 -167.795918) (xy 78.761241 -167.965986)
			(xy 78.698408 -168.133403) (xy 78.628127 -168.297833) (xy 78.550539 -168.458944) (xy 78.465802 -168.616412)
			(xy 78.374085 -168.76992) (xy 78.275574 -168.919158) (xy 78.170466 -169.063826) (xy 78.058973 -169.203633)
			(xy 77.941321 -169.338298) (xy 77.817745 -169.467548) (xy 77.688495 -169.591123) (xy 77.55383 -169.708776)
			(xy 77.414023 -169.820268) (xy 77.269355 -169.925376) (xy 77.120116 -170.023887) (xy 76.966609 -170.115604)
			(xy 76.809141 -170.200341) (xy 76.648029 -170.277928) (xy 76.483599 -170.348209) (xy 76.316182 -170.411042)
			(xy 76.146114 -170.4663) (xy 75.973738 -170.513873) (xy 75.799402 -170.553664) (xy 75.623456 -170.585594)
			(xy 75.446254 -170.609598) (xy 75.268154 -170.625627) (xy 75.089514 -170.63365) (xy 75.000104 -170.634152)
			(xy 35.999928 -170.634152) (xy 35.910518 -170.633622) (xy 35.731879 -170.625601) (xy 35.553779 -170.609573)
			(xy 35.376577 -170.58557) (xy 35.200631 -170.553642) (xy 35.026295 -170.513852) (xy 34.853919 -170.466281)
			(xy 34.683851 -170.411023) (xy 34.516434 -170.348192) (xy 34.352004 -170.277912) (xy 34.190892 -170.200326)
			(xy 34.033424 -170.11559) (xy 33.879916 -170.023874) (xy 33.730678 -169.925364) (xy 33.586009 -169.820257)
			(xy 33.446202 -169.708765) (xy 33.311537 -169.591114) (xy 33.182287 -169.467539) (xy 33.058711 -169.338289)
			(xy 32.941058 -169.203626) (xy 32.829565 -169.06382) (xy 32.724457 -168.919152) (xy 32.625945 -168.769914)
			(xy 32.534228 -168.616407) (xy 32.44949 -168.45894) (xy 32.371903 -168.297829) (xy 32.301622 -168.1334)
			(xy 32.238789 -167.965983) (xy 32.18353 -167.795915) (xy 32.135957 -167.62354) (xy 32.096165 -167.449204)
			(xy 32.064235 -167.273258) (xy 32.040231 -167.096057) (xy 32.024201 -166.917957) (xy 32.016178 -166.739318)
			(xy 32.015684 -166.649908) (xy 32.015684 -163.299902) (xy 32.015188 -163.190021) (xy 32.007162 -162.970406)
			(xy 31.99112 -162.75123) (xy 31.967085 -162.532786) (xy 31.935087 -162.315366) (xy 31.89517 -162.099259)
			(xy 31.847388 -161.884755) (xy 31.791802 -161.672139) (xy 31.728489 -161.461694) (xy 31.657532 -161.253703)
			(xy 31.579027 -161.048442) (xy 31.493077 -160.846184) (xy 31.399797 -160.647201) (xy 31.299313 -160.451757)
			(xy 31.191757 -160.260114) (xy 31.077274 -160.072527) (xy 30.956017 -159.889246) (xy 30.828146 -159.710515)
			(xy 30.693834 -159.536574) (xy 30.553258 -159.367655) (xy 30.406606 -159.203982) (xy 30.254075 -159.045775)
			(xy 30.095868 -158.893244) (xy 29.932195 -158.746592) (xy 29.763276 -158.606016) (xy 29.589335 -158.471704)
			(xy 29.410604 -158.343833) (xy 29.227323 -158.222576) (xy 29.039736 -158.108093) (xy 28.848093 -158.000537)
			(xy 28.652649 -157.900053) (xy 28.453666 -157.806773) (xy 28.251408 -157.720823) (xy 28.046147 -157.642318)
			(xy 27.838156 -157.571361) (xy 27.627711 -157.508048) (xy 27.415095 -157.452462) (xy 27.200591 -157.40468)
			(xy 26.984484 -157.364763) (xy 26.767064 -157.332765) (xy 26.54862 -157.30873) (xy 26.329444 -157.292688)
			(xy 26.109829 -157.284662) (xy 25.999948 -157.284166) (xy 4.99999 -157.284166) (xy 4.91058 -157.283664)
			(xy 4.73194 -157.275642) (xy 4.55384 -157.259612) (xy 4.376638 -157.235609) (xy 4.200692 -157.203679)
			(xy 4.026356 -157.163888) (xy 3.85398 -157.116315) (xy 3.683912 -157.061057) (xy 3.516495 -156.998224)
			(xy 3.352065 -156.927943) (xy 3.190953 -156.850356) (xy 3.033485 -156.765619) (xy 2.879978 -156.673902)
			(xy 2.730739 -156.575391) (xy 2.586071 -156.470283) (xy 2.446264 -156.358791) (xy 2.3116 -156.241138)
			(xy 2.182349 -156.117563) (xy 2.058774 -155.988312) (xy 1.941121 -155.853648) (xy 1.829629 -155.713841)
			(xy 1.724521 -155.569173) (xy 1.62601 -155.419934) (xy 1.534293 -155.266427) (xy 1.449556 -155.108959)
			(xy 1.371969 -154.947847) (xy 1.301688 -154.783417) (xy 1.238855 -154.616) (xy 1.183597 -154.445932)
			(xy 1.136024 -154.273556) (xy 1.096233 -154.09922) (xy 1.064303 -153.923274) (xy 1.0403 -153.746072)
			(xy 1.02427 -153.567972) (xy 1.016248 -153.389332) (xy 1.015746 -153.299922) (xy 0.508 -153.299922)
			(xy 0.508499 -153.395277) (xy 0.516593 -153.585815) (xy 0.532766 -153.775839) (xy 0.55699 -153.965004)
			(xy 0.58922 -154.152971) (xy 0.629399 -154.339401) (xy 0.677453 -154.523958) (xy 0.733298 -154.706308)
			(xy 0.796831 -154.886125) (xy 0.867938 -155.063083) (xy 0.946492 -155.236863) (xy 1.032351 -155.407153)
			(xy 1.125359 -155.573646) (xy 1.22535 -155.736041) (xy 1.332143 -155.894047) (xy 1.445545 -156.047377)
			(xy 1.565353 -156.195756) (xy 1.691351 -156.338917) (xy 1.82331 -156.476602) (xy 1.960995 -156.608561)
			(xy 2.104156 -156.734559) (xy 2.252535 -156.854367) (xy 2.405865 -156.967769) (xy 2.563871 -157.074562)
			(xy 2.726266 -157.174553) (xy 2.892759 -157.267561) (xy 3.063049 -157.35342) (xy 3.236829 -157.431974)
			(xy 3.413787 -157.503081) (xy 3.593604 -157.566614) (xy 3.775954 -157.622459) (xy 3.960511 -157.670513)
			(xy 4.146941 -157.710692) (xy 4.334908 -157.742922) (xy 4.524073 -157.767146) (xy 4.714097 -157.783319)
			(xy 4.904635 -157.791413) (xy 4.99999 -157.791912) (xy 25.999948 -157.791912) (xy 26.105463 -157.792411)
			(xy 26.316337 -157.800494) (xy 26.526747 -157.816648) (xy 26.736385 -157.84085) (xy 26.944941 -157.873063)
			(xy 27.15211 -157.913241) (xy 27.357588 -157.961325) (xy 27.561074 -158.017244) (xy 27.762269 -158.080916)
			(xy 27.960877 -158.152247) (xy 28.156608 -158.231133) (xy 28.349173 -158.317459) (xy 28.53829 -158.411097)
			(xy 28.723682 -158.51191) (xy 28.905076 -158.61975) (xy 29.082207 -158.734458) (xy 29.254814 -158.855867)
			(xy 29.422645 -158.983799) (xy 29.585451 -159.118065) (xy 29.742996 -159.258468) (xy 29.895047 -159.404803)
			(xy 30.041382 -159.556854) (xy 30.181785 -159.714399) (xy 30.316051 -159.877205) (xy 30.443983 -160.045036)
			(xy 30.565392 -160.217643) (xy 30.6801 -160.394774) (xy 30.78794 -160.576168) (xy 30.888753 -160.76156)
			(xy 30.982391 -160.950677) (xy 31.068717 -161.143242) (xy 31.147603 -161.338973) (xy 31.218934 -161.537581)
			(xy 31.282606 -161.738776) (xy 31.338525 -161.942262) (xy 31.386609 -162.14774) (xy 31.426787 -162.354909)
			(xy 31.459 -162.563465) (xy 31.483202 -162.773103) (xy 31.499356 -162.983513) (xy 31.507439 -163.194387)
			(xy 31.507938 -163.299902) (xy 31.507938 -166.649908) (xy 31.508444 -166.745263) (xy 31.516538 -166.935801)
			(xy 31.532711 -167.125824) (xy 31.556935 -167.314989) (xy 31.589165 -167.502956) (xy 31.629343 -167.689386)
			(xy 31.677398 -167.873942) (xy 31.733242 -168.056293) (xy 31.796775 -168.236109) (xy 31.867882 -168.413067)
			(xy 31.946436 -168.586847) (xy 32.032294 -168.757137) (xy 32.125303 -168.923629) (xy 32.225293 -169.086025)
			(xy 32.332086 -169.24403) (xy 32.445488 -169.39736) (xy 32.565296 -169.545739) (xy 32.691293 -169.6889)
			(xy 32.823253 -169.826584) (xy 32.960937 -169.958544) (xy 33.104098 -170.084541) (xy 33.252477 -170.204349)
			(xy 33.405807 -170.317752) (xy 33.563812 -170.424545) (xy 33.726207 -170.524535) (xy 33.8927 -170.617544)
			(xy 34.062989 -170.703402) (xy 34.23677 -170.781956) (xy 34.413727 -170.853064) (xy 34.593543 -170.916597)
			(xy 34.775894 -170.972441) (xy 34.96045 -171.020496) (xy 35.14688 -171.060675) (xy 35.334847 -171.092905)
			(xy 35.524012 -171.117128) (xy 35.714035 -171.133302) (xy 35.904573 -171.141396) (xy 35.999928 -171.141898)
		)
		(stroke
			(width 0)
			(type solid)
		)
		(fill yes)
		(layer "In2.Cu")
		(net "GND")
	)
	(gr_poly
		(pts
			(xy 405.96185 -169.546524) (xy 405.971917 -169.546092) (xy 405.99051 -169.538368) (xy 405.997918 -169.531538)
			(xy 406.351994 -169.177462) (xy 406.358835 -169.170062) (xy 406.366557 -169.151464) (xy 406.36698 -169.141394)
			(xy 406.36698 -157.907482) (xy 406.367406 -157.897413) (xy 406.375123 -157.878811) (xy 406.381966 -157.871414)
			(xy 407.52014 -156.73324) (xy 407.527539 -156.726396) (xy 407.546137 -156.71867) (xy 407.556208 -156.718254)
			(xy 435.712362 -156.718254) (xy 435.722426 -156.717818) (xy 435.74101 -156.710083) (xy 435.74843 -156.703268)
			(xy 438.277762 -154.173936) (xy 438.284602 -154.166536) (xy 438.29232 -154.147937) (xy 438.292748 -154.137868)
			(xy 438.292748 -133.674612) (xy 438.29317 -133.664542) (xy 438.300887 -133.645939) (xy 438.307734 -133.638544)
			(xy 442.564774 -129.381504) (xy 442.572176 -129.374669) (xy 442.590775 -129.366961) (xy 442.600842 -129.366518)
			(xy 472.244928 -129.366518) (xy 472.254996 -129.36609) (xy 472.273595 -129.358371) (xy 472.280996 -129.351532)
			(xy 473.978478 -127.65405) (xy 473.985319 -127.64665) (xy 473.993039 -127.628051) (xy 473.993464 -127.617982)
			(xy 473.993464 -20.480274) (xy 473.993035 -20.470207) (xy 473.98531 -20.451612) (xy 473.978478 -20.444206)
			(xy 471.769694 -18.235422) (xy 471.762296 -18.228574) (xy 471.743698 -18.220839) (xy 471.733626 -18.220436)
			(xy 452.777352 -18.220436) (xy 452.767286 -18.220869) (xy 452.748698 -18.228599) (xy 452.741284 -18.235422)
			(xy 452.015352 -18.961354) (xy 452.008508 -18.968753) (xy 452.000785 -18.987352) (xy 452.000366 -18.997422)
			(xy 452.000366 -37.223954) (xy 452.000801 -37.234018) (xy 452.008536 -37.252602) (xy 452.015352 -37.260022)
			(xy 462.011014 -47.255684) (xy 462.017857 -47.263083) (xy 462.025574 -47.281682) (xy 462.026 -47.291752)
			(xy 462.026 -47.733458) (xy 462.026508 -47.752) (xy 462.026 -47.770542) (xy 462.026 -49.332134) (xy 462.025571 -49.342201)
			(xy 462.017847 -49.360797) (xy 462.011014 -49.368202) (xy 458.103986 -53.27523) (xy 458.09659 -53.282082)
			(xy 458.077991 -53.289822) (xy 458.067918 -53.290216) (xy 423.488866 -53.290216) (xy 423.478799 -53.290646)
			(xy 423.460205 -53.298371) (xy 423.452798 -53.305202) (xy 420.768018 -55.989982) (xy 468.668617 -55.989982)
			(xy 468.672606 -55.877017) (xy 468.684554 -55.764614) (xy 468.704401 -55.653334) (xy 468.732047 -55.543732)
			(xy 468.767357 -55.436352) (xy 468.810152 -55.331731) (xy 468.860221 -55.230389) (xy 468.917314 -55.132831)
			(xy 468.981147 -55.039544) (xy 469.0514 -54.950991) (xy 469.127725 -54.867615) (xy 469.209741 -54.789831)
			(xy 469.29704 -54.718025) (xy 469.389186 -54.652556) (xy 469.485721 -54.593751) (xy 469.586164 -54.541901)
			(xy 469.690014 -54.497266) (xy 469.796753 -54.460067) (xy 469.905851 -54.43049) (xy 470.016763 -54.408682)
			(xy 470.128937 -54.394753) (xy 470.241815 -54.38877) (xy 470.354833 -54.390765) (xy 470.467429 -54.400727)
			(xy 470.579042 -54.418607) (xy 470.689115 -54.444315) (xy 470.797101 -54.477724) (xy 470.902461 -54.518667)
			(xy 471.004671 -54.566939) (xy 471.103221 -54.622302) (xy 471.197621 -54.684477) (xy 471.287399 -54.753157)
			(xy 471.372109 -54.827999) (xy 471.451329 -54.90863) (xy 471.524664 -54.994647) (xy 471.591749 -55.085624)
			(xy 471.652249 -55.181106) (xy 471.705863 -55.280618) (xy 471.752325 -55.383664) (xy 471.791402 -55.48973)
			(xy 471.822899 -55.598289) (xy 471.846661 -55.708799) (xy 471.862568 -55.82071) (xy 471.870541 -55.933464)
			(xy 471.87104 -55.989982) (xy 471.870541 -56.0465) (xy 471.862568 -56.159254) (xy 471.846661 -56.271165)
			(xy 471.822899 -56.381675) (xy 471.791402 -56.490234) (xy 471.752325 -56.5963) (xy 471.705863 -56.699346)
			(xy 471.652249 -56.798858) (xy 471.591749 -56.89434) (xy 471.524664 -56.985317) (xy 471.451329 -57.071334)
			(xy 471.372109 -57.151965) (xy 471.287399 -57.226807) (xy 471.197621 -57.295487) (xy 471.103221 -57.357662)
			(xy 471.004671 -57.413025) (xy 470.902461 -57.461297) (xy 470.797101 -57.50224) (xy 470.689115 -57.535649)
			(xy 470.579042 -57.561357) (xy 470.467429 -57.579237) (xy 470.354833 -57.589199) (xy 470.241815 -57.591194)
			(xy 470.128937 -57.585211) (xy 470.016763 -57.571282) (xy 469.905851 -57.549474) (xy 469.796753 -57.519897)
			(xy 469.690014 -57.482698) (xy 469.586164 -57.438063) (xy 469.485721 -57.386213) (xy 469.389186 -57.327408)
			(xy 469.29704 -57.261939) (xy 469.209741 -57.190133) (xy 469.127725 -57.112349) (xy 469.0514 -57.028973)
			(xy 468.981147 -56.94042) (xy 468.917314 -56.847133) (xy 468.860221 -56.749575) (xy 468.810152 -56.648233)
			(xy 468.767357 -56.543612) (xy 468.732047 -56.436232) (xy 468.704401 -56.32663) (xy 468.684554 -56.21535)
			(xy 468.672606 -56.102947) (xy 468.668617 -55.989982) (xy 420.768018 -55.989982) (xy 416.682682 -60.075318)
			(xy 416.67583 -60.082714) (xy 416.668654 -60.099956) (xy 422.484046 -60.099956) (xy 422.488076 -59.957621)
			(xy 422.500151 -59.815741) (xy 422.520234 -59.674773) (xy 422.548261 -59.535166) (xy 422.584141 -59.397368)
			(xy 422.627759 -59.261821) (xy 422.678976 -59.128959) (xy 422.737627 -58.999207) (xy 422.803525 -58.872981)
			(xy 422.876459 -58.750685) (xy 422.956196 -58.632712) (xy 423.042478 -58.519439) (xy 423.135031 -58.411228)
			(xy 423.233558 -58.308427) (xy 423.337743 -58.211365) (xy 423.447252 -58.120353) (xy 423.561735 -58.035681)
			(xy 423.680825 -57.957623) (xy 423.80414 -57.886427) (xy 423.931286 -57.822321) (xy 424.061855 -57.765512)
			(xy 424.195429 -57.71618) (xy 424.33158 -57.674484) (xy 424.469871 -57.640558) (xy 424.609861 -57.61451)
			(xy 424.7511 -57.596424) (xy 424.893136 -57.586357) (xy 425.035514 -57.584342) (xy 425.177778 -57.590385)
			(xy 425.319472 -57.604467) (xy 425.460142 -57.626543) (xy 425.599339 -57.656543) (xy 425.736615 -57.694369)
			(xy 425.871531 -57.739901) (xy 426.003655 -57.792992) (xy 426.132564 -57.853474) (xy 426.257845 -57.921152)
			(xy 426.379096 -57.995809) (xy 426.495929 -58.077207) (xy 426.60797 -58.165084) (xy 426.71486 -58.259159)
			(xy 426.816257 -58.359131) (xy 426.911835 -58.464679) (xy 427.001289 -58.575465) (xy 427.084331 -58.691134)
			(xy 427.160697 -58.811317) (xy 427.230141 -58.935627) (xy 427.292441 -59.063668) (xy 427.347397 -59.195027)
			(xy 427.394834 -59.329286) (xy 427.434598 -59.466013) (xy 427.466564 -59.604771) (xy 427.490629 -59.745115)
			(xy 427.506715 -59.886596) (xy 427.51477 -60.02876) (xy 427.515274 -60.099956) (xy 427.51477 -60.171152)
			(xy 427.506715 -60.313316) (xy 427.490629 -60.454797) (xy 427.466564 -60.595141) (xy 427.434598 -60.733899)
			(xy 427.394834 -60.870626) (xy 427.347397 -61.004885) (xy 427.292441 -61.136244) (xy 427.230141 -61.264285)
			(xy 427.160697 -61.388595) (xy 427.084331 -61.508778) (xy 427.001289 -61.624447) (xy 426.911835 -61.735233)
			(xy 426.816257 -61.840781) (xy 426.71486 -61.940753) (xy 426.60797 -62.034828) (xy 426.495929 -62.122705)
			(xy 426.379096 -62.204103) (xy 426.257845 -62.27876) (xy 426.132564 -62.346438) (xy 426.003655 -62.40692)
			(xy 425.871531 -62.460011) (xy 425.736615 -62.505543) (xy 425.599339 -62.543369) (xy 425.460142 -62.573369)
			(xy 425.319472 -62.595445) (xy 425.177778 -62.609527) (xy 425.035514 -62.61557) (xy 424.893136 -62.613555)
			(xy 424.7511 -62.603488) (xy 424.609861 -62.585402) (xy 424.469871 -62.559354) (xy 424.33158 -62.525428)
			(xy 424.195429 -62.483732) (xy 424.061855 -62.4344) (xy 423.931286 -62.377591) (xy 423.80414 -62.313485)
			(xy 423.680825 -62.242289) (xy 423.561735 -62.164231) (xy 423.447252 -62.079559) (xy 423.337743 -61.988547)
			(xy 423.233558 -61.891485) (xy 423.135031 -61.788684) (xy 423.042478 -61.680473) (xy 422.956196 -61.5672)
			(xy 422.876459 -61.449227) (xy 422.803525 -61.326931) (xy 422.737627 -61.200705) (xy 422.678976 -61.070953)
			(xy 422.627759 -60.938091) (xy 422.584141 -60.802544) (xy 422.548261 -60.664746) (xy 422.520234 -60.525139)
			(xy 422.500151 -60.384171) (xy 422.488076 -60.242291) (xy 422.484046 -60.099956) (xy 416.668654 -60.099956)
			(xy 416.668089 -60.101313) (xy 416.667696 -60.111386) (xy 416.667696 -65.532) (xy 441.730892 -65.532)
			(xy 441.73136 -65.50463) (xy 441.739178 -65.450451) (xy 441.754666 -65.397948) (xy 441.777508 -65.348201)
			(xy 441.807231 -65.302234) (xy 441.824872 -65.281302) (xy 441.830968 -65.27419) (xy 441.837318 -65.257172)
			(xy 441.837318 -65.171828) (xy 441.830968 -65.15481) (xy 441.824872 -65.147698) (xy 441.807229 -65.126766)
			(xy 441.777501 -65.080799) (xy 441.754653 -65.031053) (xy 441.739155 -64.978551) (xy 441.731325 -64.924371)
			(xy 441.731325 -64.869629) (xy 441.739155 -64.815449) (xy 441.754653 -64.762947) (xy 441.777501 -64.713201)
			(xy 441.807229 -64.667234) (xy 441.824872 -64.646302) (xy 441.830968 -64.63919) (xy 441.837318 -64.622172)
			(xy 441.837318 -64.536828) (xy 441.830968 -64.51981) (xy 441.824872 -64.512698) (xy 441.807229 -64.491766)
			(xy 441.777501 -64.445799) (xy 441.754653 -64.396053) (xy 441.739155 -64.343551) (xy 441.731325 -64.289371)
			(xy 441.731325 -64.234629) (xy 441.739155 -64.180449) (xy 441.754653 -64.127947) (xy 441.777501 -64.078201)
			(xy 441.807229 -64.032234) (xy 441.824872 -64.011302) (xy 441.830968 -64.00419) (xy 441.837318 -63.987172)
			(xy 441.837318 -63.901828) (xy 441.830968 -63.88481) (xy 441.824872 -63.877698) (xy 441.807229 -63.856766)
			(xy 441.777501 -63.810799) (xy 441.754653 -63.761053) (xy 441.739155 -63.708551) (xy 441.731325 -63.654371)
			(xy 441.731325 -63.599629) (xy 441.739155 -63.545449) (xy 441.754653 -63.492947) (xy 441.777501 -63.443201)
			(xy 441.807229 -63.397234) (xy 441.824872 -63.376302) (xy 441.830968 -63.36919) (xy 441.837318 -63.352172)
			(xy 441.837318 -63.266828) (xy 441.830968 -63.24981) (xy 441.824872 -63.242698) (xy 441.807214 -63.221781)
			(xy 441.777506 -63.175804) (xy 441.754674 -63.126052) (xy 441.739187 -63.073548) (xy 441.731364 -63.01937)
			(xy 441.730892 -62.992) (xy 441.731378 -62.964749) (xy 441.739134 -62.910801) (xy 441.754489 -62.858506)
			(xy 441.777131 -62.808929) (xy 441.806597 -62.763079) (xy 441.842288 -62.721888) (xy 441.883479 -62.686197)
			(xy 441.929329 -62.656731) (xy 441.978906 -62.634089) (xy 442.031201 -62.618734) (xy 442.085149 -62.610978)
			(xy 442.139651 -62.610978) (xy 442.193599 -62.618734) (xy 442.245894 -62.634089) (xy 442.295471 -62.656731)
			(xy 442.341321 -62.686197) (xy 442.382512 -62.721888) (xy 442.418203 -62.763079) (xy 442.447669 -62.808929)
			(xy 442.470311 -62.858506) (xy 442.485666 -62.910801) (xy 442.493422 -62.964749) (xy 442.493908 -62.992)
			(xy 442.49344 -63.01937) (xy 442.485622 -63.073549) (xy 442.470134 -63.126052) (xy 442.447292 -63.175799)
			(xy 442.417569 -63.221766) (xy 442.399928 -63.242698) (xy 442.393832 -63.24981) (xy 442.387482 -63.266828)
			(xy 442.387482 -63.352172) (xy 442.393832 -63.36919) (xy 442.399928 -63.376302) (xy 442.417571 -63.397234)
			(xy 442.447299 -63.443201) (xy 442.470147 -63.492947) (xy 442.485645 -63.545449) (xy 442.493475 -63.599629)
			(xy 442.493475 -63.654371) (xy 442.485645 -63.708551) (xy 442.470147 -63.761053) (xy 442.447299 -63.810799)
			(xy 442.417571 -63.856766) (xy 442.399928 -63.877698) (xy 442.393832 -63.88481) (xy 442.387482 -63.901828)
			(xy 442.387482 -63.987172) (xy 442.393832 -64.00419) (xy 442.399928 -64.011302) (xy 442.417571 -64.032234)
			(xy 442.447299 -64.078201) (xy 442.470147 -64.127947) (xy 442.485645 -64.180449) (xy 442.493475 -64.234629)
			(xy 442.493475 -64.289371) (xy 442.485645 -64.343551) (xy 442.470147 -64.396053) (xy 442.447299 -64.445799)
			(xy 442.417571 -64.491766) (xy 442.399928 -64.512698) (xy 442.393832 -64.51981) (xy 442.387482 -64.536828)
			(xy 442.387482 -64.622172) (xy 442.393832 -64.63919) (xy 442.399928 -64.646302) (xy 442.417571 -64.667234)
			(xy 442.447299 -64.713201) (xy 442.470147 -64.762947) (xy 442.485645 -64.815449) (xy 442.493475 -64.869629)
			(xy 442.493475 -64.924371) (xy 442.485645 -64.978551) (xy 442.470147 -65.031053) (xy 442.447299 -65.080799)
			(xy 442.417571 -65.126766) (xy 442.399928 -65.147698) (xy 442.393832 -65.15481) (xy 442.387482 -65.171828)
			(xy 442.387482 -65.257172) (xy 442.393832 -65.27419) (xy 442.399928 -65.281302) (xy 442.417586 -65.302219)
			(xy 442.447294 -65.348196) (xy 442.470126 -65.397948) (xy 442.485613 -65.450452) (xy 442.493436 -65.50463)
			(xy 442.493908 -65.532) (xy 444.524892 -65.532) (xy 444.52536 -65.50463) (xy 444.533178 -65.450451)
			(xy 444.548666 -65.397948) (xy 444.571508 -65.348201) (xy 444.601231 -65.302234) (xy 444.618872 -65.281302)
			(xy 444.624968 -65.27419) (xy 444.631318 -65.257172) (xy 444.631318 -65.171828) (xy 444.624968 -65.15481)
			(xy 444.618872 -65.147698) (xy 444.601229 -65.126766) (xy 444.571501 -65.080799) (xy 444.548653 -65.031053)
			(xy 444.533155 -64.978551) (xy 444.525325 -64.924371) (xy 444.525325 -64.869629) (xy 444.533155 -64.815449)
			(xy 444.548653 -64.762947) (xy 444.571501 -64.713201) (xy 444.601229 -64.667234) (xy 444.618872 -64.646302)
			(xy 444.624968 -64.63919) (xy 444.631318 -64.622172) (xy 444.631318 -64.536828) (xy 444.624968 -64.51981)
			(xy 444.618872 -64.512698) (xy 444.601229 -64.491766) (xy 444.571501 -64.445799) (xy 444.548653 -64.396053)
			(xy 444.533155 -64.343551) (xy 444.525325 -64.289371) (xy 444.525325 -64.234629) (xy 444.533155 -64.180449)
			(xy 444.548653 -64.127947) (xy 444.571501 -64.078201) (xy 444.601229 -64.032234) (xy 444.618872 -64.011302)
			(xy 444.624968 -64.00419) (xy 444.631318 -63.987172) (xy 444.631318 -63.901828) (xy 444.624968 -63.88481)
			(xy 444.618872 -63.877698) (xy 444.601229 -63.856766) (xy 444.571501 -63.810799) (xy 444.548653 -63.761053)
			(xy 444.533155 -63.708551) (xy 444.525325 -63.654371) (xy 444.525325 -63.599629) (xy 444.533155 -63.545449)
			(xy 444.548653 -63.492947) (xy 444.571501 -63.443201) (xy 444.601229 -63.397234) (xy 444.618872 -63.376302)
			(xy 444.624968 -63.36919) (xy 444.631318 -63.352172) (xy 444.631318 -63.266828) (xy 444.624968 -63.24981)
			(xy 444.618872 -63.242698) (xy 444.601214 -63.221781) (xy 444.571506 -63.175804) (xy 444.548674 -63.126052)
			(xy 444.533187 -63.073548) (xy 444.525364 -63.01937) (xy 444.524892 -62.992) (xy 444.525378 -62.964749)
			(xy 444.533134 -62.910801) (xy 444.548489 -62.858506) (xy 444.571131 -62.808929) (xy 444.600597 -62.763079)
			(xy 444.636288 -62.721888) (xy 444.677479 -62.686197) (xy 444.723329 -62.656731) (xy 444.772906 -62.634089)
			(xy 444.825201 -62.618734) (xy 444.879149 -62.610978) (xy 444.933651 -62.610978) (xy 444.987599 -62.618734)
			(xy 445.039894 -62.634089) (xy 445.089471 -62.656731) (xy 445.135321 -62.686197) (xy 445.176512 -62.721888)
			(xy 445.212203 -62.763079) (xy 445.241669 -62.808929) (xy 445.264311 -62.858506) (xy 445.279666 -62.910801)
			(xy 445.287422 -62.964749) (xy 445.287908 -62.992) (xy 445.28744 -63.01937) (xy 445.279622 -63.073549)
			(xy 445.264134 -63.126052) (xy 445.241292 -63.175799) (xy 445.211569 -63.221766) (xy 445.193928 -63.242698)
			(xy 445.187832 -63.24981) (xy 445.181482 -63.266828) (xy 445.181482 -63.352172) (xy 445.187832 -63.36919)
			(xy 445.193928 -63.376302) (xy 445.211571 -63.397234) (xy 445.241299 -63.443201) (xy 445.264147 -63.492947)
			(xy 445.279645 -63.545449) (xy 445.284126 -63.576454) (xy 448.29222 -63.576454) (xy 448.292769 -63.547538)
			(xy 448.301491 -63.490368) (xy 448.318742 -63.43517) (xy 448.344128 -63.383207) (xy 448.377066 -63.335673)
			(xy 448.416803 -63.293655) (xy 448.439286 -63.275464) (xy 448.448058 -63.267911) (xy 448.458236 -63.247146)
			(xy 448.458844 -63.235586) (xy 448.458844 -63.155322) (xy 448.45828 -63.143753) (xy 448.448083 -63.122981)
			(xy 448.439286 -63.115444) (xy 448.416821 -63.097232) (xy 448.377085 -63.055216) (xy 448.344144 -63.007685)
			(xy 448.318753 -62.955728) (xy 448.301492 -62.900535) (xy 448.292758 -62.843369) (xy 448.29222 -62.814454)
			(xy 448.292706 -62.787203) (xy 448.300462 -62.733255) (xy 448.315817 -62.68096) (xy 448.338459 -62.631383)
			(xy 448.367925 -62.585533) (xy 448.403616 -62.544342) (xy 448.444807 -62.508651) (xy 448.490657 -62.479185)
			(xy 448.540234 -62.456543) (xy 448.592529 -62.441188) (xy 448.646477 -62.433432) (xy 448.700979 -62.433432)
			(xy 448.754927 -62.441188) (xy 448.807222 -62.456543) (xy 448.856799 -62.479185) (xy 448.902649 -62.508651)
			(xy 448.94384 -62.544342) (xy 448.979531 -62.585533) (xy 449.008997 -62.631383) (xy 449.031639 -62.68096)
			(xy 449.046994 -62.733255) (xy 449.05475 -62.787203) (xy 449.055236 -62.814454) (xy 449.054709 -62.843371)
			(xy 449.045985 -62.900543) (xy 449.028731 -62.955743) (xy 449.003341 -63.007705) (xy 448.970398 -63.055239)
			(xy 448.930656 -63.097255) (xy 448.90817 -63.115444) (xy 448.899388 -63.122986) (xy 448.889217 -63.14376)
			(xy 448.888612 -63.155322) (xy 448.888612 -63.235586) (xy 448.889186 -63.247153) (xy 448.899378 -63.267925)
			(xy 448.90817 -63.275464) (xy 448.93063 -63.293683) (xy 448.970368 -63.335696) (xy 449.003311 -63.383225)
			(xy 449.028703 -63.435181) (xy 449.045964 -63.490374) (xy 449.054698 -63.547539) (xy 449.055236 -63.576454)
			(xy 449.054982 -63.590678) (xy 450.57822 -63.590678) (xy 450.578787 -63.561763) (xy 450.587504 -63.504593)
			(xy 450.604752 -63.449395) (xy 450.630135 -63.397433) (xy 450.66307 -63.349898) (xy 450.702804 -63.307879)
			(xy 450.725286 -63.289688) (xy 450.734047 -63.282125) (xy 450.744231 -63.261367) (xy 450.744844 -63.24981)
			(xy 450.744844 -63.169546) (xy 450.744267 -63.157978) (xy 450.734079 -63.137206) (xy 450.725286 -63.129668)
			(xy 450.702784 -63.111499) (xy 450.663051 -63.069474) (xy 450.630114 -63.021934) (xy 450.604729 -62.969969)
			(xy 450.587477 -62.914768) (xy 450.578753 -62.857595) (xy 450.57822 -62.828678) (xy 450.578706 -62.801427)
			(xy 450.586462 -62.747479) (xy 450.601817 -62.695184) (xy 450.624459 -62.645607) (xy 450.653925 -62.599757)
			(xy 450.689616 -62.558566) (xy 450.730807 -62.522875) (xy 450.776657 -62.493409) (xy 450.826234 -62.470767)
			(xy 450.878529 -62.455412) (xy 450.932477 -62.447656) (xy 450.986979 -62.447656) (xy 451.040927 -62.455412)
			(xy 451.093222 -62.470767) (xy 451.142799 -62.493409) (xy 451.188649 -62.522875) (xy 451.22984 -62.558566)
			(xy 451.265531 -62.599757) (xy 451.294997 -62.645607) (xy 451.317639 -62.695184) (xy 451.332994 -62.747479)
			(xy 451.34075 -62.801427) (xy 451.341236 -62.828678) (xy 451.340726 -62.857596) (xy 451.331999 -62.914768)
			(xy 451.314741 -62.969968) (xy 451.289348 -63.021931) (xy 451.256401 -63.069464) (xy 451.216657 -63.111479)
			(xy 451.19417 -63.129668) (xy 451.185422 -63.137243) (xy 451.175232 -63.157992) (xy 451.174612 -63.169546)
			(xy 451.174612 -63.24981) (xy 451.175172 -63.261379) (xy 451.185374 -63.28215) (xy 451.19417 -63.289688)
			(xy 451.216641 -63.307893) (xy 451.256379 -63.349909) (xy 451.28932 -63.397441) (xy 451.314711 -63.449399)
			(xy 451.331969 -63.504595) (xy 451.3407 -63.561763) (xy 451.341236 -63.590678) (xy 452.73722 -63.590678)
			(xy 452.737787 -63.561763) (xy 452.746504 -63.504593) (xy 452.763752 -63.449395) (xy 452.789135 -63.397433)
			(xy 452.82207 -63.349898) (xy 452.861804 -63.307879) (xy 452.884286 -63.289688) (xy 452.893047 -63.282125)
			(xy 452.903231 -63.261367) (xy 452.903844 -63.24981) (xy 452.903844 -63.169546) (xy 452.903267 -63.157978)
			(xy 452.893079 -63.137206) (xy 452.884286 -63.129668) (xy 452.861784 -63.111499) (xy 452.822051 -63.069474)
			(xy 452.789114 -63.021934) (xy 452.763729 -62.969969) (xy 452.746477 -62.914768) (xy 452.737753 -62.857595)
			(xy 452.73722 -62.828678) (xy 452.737706 -62.801427) (xy 452.745462 -62.747479) (xy 452.760817 -62.695184)
			(xy 452.783459 -62.645607) (xy 452.812925 -62.599757) (xy 452.848616 -62.558566) (xy 452.889807 -62.522875)
			(xy 452.935657 -62.493409) (xy 452.985234 -62.470767) (xy 453.037529 -62.455412) (xy 453.091477 -62.447656)
			(xy 453.145979 -62.447656) (xy 453.199927 -62.455412) (xy 453.252222 -62.470767) (xy 453.301799 -62.493409)
			(xy 453.347649 -62.522875) (xy 453.38884 -62.558566) (xy 453.424531 -62.599757) (xy 453.453997 -62.645607)
			(xy 453.476639 -62.695184) (xy 453.489211 -62.738) (xy 454.176382 -62.738) (xy 454.180453 -62.682378)
			(xy 454.192579 -62.627941) (xy 454.212502 -62.57585) (xy 454.239798 -62.527215) (xy 454.273884 -62.483072)
			(xy 454.314033 -62.444363) (xy 454.359391 -62.411912) (xy 454.408991 -62.386411) (xy 454.461775 -62.368404)
			(xy 454.516618 -62.358274) (xy 454.572352 -62.356237) (xy 454.627789 -62.362337) (xy 454.681746 -62.376443)
			(xy 454.733075 -62.398255) (xy 454.780681 -62.427309) (xy 454.823549 -62.462984) (xy 454.860766 -62.504521)
			(xy 454.891539 -62.551034) (xy 454.915211 -62.601531) (xy 454.931279 -62.654938) (xy 454.939399 -62.710114)
			(xy 454.939908 -62.738) (xy 454.939399 -62.765886) (xy 454.931279 -62.821062) (xy 454.915211 -62.874469)
			(xy 454.891539 -62.924966) (xy 454.860766 -62.971479) (xy 454.823549 -63.013016) (xy 454.780681 -63.048691)
			(xy 454.733075 -63.077745) (xy 454.681746 -63.099557) (xy 454.627789 -63.113663) (xy 454.572352 -63.119763)
			(xy 454.516618 -63.117726) (xy 454.461775 -63.107596) (xy 454.408991 -63.089589) (xy 454.359391 -63.064088)
			(xy 454.314033 -63.031637) (xy 454.273884 -62.992928) (xy 454.239798 -62.948785) (xy 454.212502 -62.90015)
			(xy 454.192579 -62.848059) (xy 454.180453 -62.793622) (xy 454.176382 -62.738) (xy 453.489211 -62.738)
			(xy 453.491994 -62.747479) (xy 453.49975 -62.801427) (xy 453.500236 -62.828678) (xy 453.499726 -62.857596)
			(xy 453.490999 -62.914768) (xy 453.473741 -62.969968) (xy 453.448348 -63.021931) (xy 453.415401 -63.069464)
			(xy 453.375657 -63.111479) (xy 453.35317 -63.129668) (xy 453.344422 -63.137243) (xy 453.334232 -63.157992)
			(xy 453.333612 -63.169546) (xy 453.333612 -63.24981) (xy 453.334172 -63.261379) (xy 453.344374 -63.28215)
			(xy 453.35317 -63.289688) (xy 453.375641 -63.307893) (xy 453.415379 -63.349909) (xy 453.44832 -63.397441)
			(xy 453.473711 -63.449399) (xy 453.490969 -63.504595) (xy 453.4997 -63.561763) (xy 453.500236 -63.590678)
			(xy 453.49975 -63.617929) (xy 453.491994 -63.671877) (xy 453.476639 -63.724172) (xy 453.453997 -63.773749)
			(xy 453.424531 -63.819599) (xy 453.38884 -63.86079) (xy 453.347649 -63.896481) (xy 453.301799 -63.925947)
			(xy 453.252222 -63.948589) (xy 453.199927 -63.963944) (xy 453.145979 -63.9717) (xy 453.091477 -63.9717)
			(xy 453.037529 -63.963944) (xy 452.985234 -63.948589) (xy 452.935657 -63.925947) (xy 452.889807 -63.896481)
			(xy 452.848616 -63.86079) (xy 452.812925 -63.819599) (xy 452.783459 -63.773749) (xy 452.760817 -63.724172)
			(xy 452.745462 -63.671877) (xy 452.737706 -63.617929) (xy 452.73722 -63.590678) (xy 451.341236 -63.590678)
			(xy 451.34075 -63.617929) (xy 451.332994 -63.671877) (xy 451.317639 -63.724172) (xy 451.294997 -63.773749)
			(xy 451.265531 -63.819599) (xy 451.22984 -63.86079) (xy 451.188649 -63.896481) (xy 451.142799 -63.925947)
			(xy 451.093222 -63.948589) (xy 451.040927 -63.963944) (xy 450.986979 -63.9717) (xy 450.932477 -63.9717)
			(xy 450.878529 -63.963944) (xy 450.826234 -63.948589) (xy 450.776657 -63.925947) (xy 450.730807 -63.896481)
			(xy 450.689616 -63.86079) (xy 450.653925 -63.819599) (xy 450.624459 -63.773749) (xy 450.601817 -63.724172)
			(xy 450.586462 -63.671877) (xy 450.578706 -63.617929) (xy 450.57822 -63.590678) (xy 449.054982 -63.590678)
			(xy 449.05475 -63.603705) (xy 449.046994 -63.657653) (xy 449.031639 -63.709948) (xy 449.008997 -63.759525)
			(xy 448.979531 -63.805375) (xy 448.94384 -63.846566) (xy 448.902649 -63.882257) (xy 448.856799 -63.911723)
			(xy 448.807222 -63.934365) (xy 448.754927 -63.94972) (xy 448.700979 -63.957476) (xy 448.646477 -63.957476)
			(xy 448.592529 -63.94972) (xy 448.540234 -63.934365) (xy 448.490657 -63.911723) (xy 448.444807 -63.882257)
			(xy 448.403616 -63.846566) (xy 448.367925 -63.805375) (xy 448.338459 -63.759525) (xy 448.315817 -63.709948)
			(xy 448.300462 -63.657653) (xy 448.292706 -63.603705) (xy 448.29222 -63.576454) (xy 445.284126 -63.576454)
			(xy 445.287475 -63.599629) (xy 445.287475 -63.654371) (xy 445.279645 -63.708551) (xy 445.264147 -63.761053)
			(xy 445.241299 -63.810799) (xy 445.211571 -63.856766) (xy 445.193928 -63.877698) (xy 445.187832 -63.88481)
			(xy 445.181482 -63.901828) (xy 445.181482 -63.987172) (xy 445.187832 -64.00419) (xy 445.193928 -64.011302)
			(xy 445.211571 -64.032234) (xy 445.241299 -64.078201) (xy 445.264147 -64.127947) (xy 445.279645 -64.180449)
			(xy 445.287475 -64.234629) (xy 445.287475 -64.289371) (xy 445.279645 -64.343551) (xy 445.264147 -64.396053)
			(xy 445.241299 -64.445799) (xy 445.211571 -64.491766) (xy 445.193928 -64.512698) (xy 445.187832 -64.51981)
			(xy 445.181482 -64.536828) (xy 445.181482 -64.622172) (xy 445.187832 -64.63919) (xy 445.193928 -64.646302)
			(xy 445.211571 -64.667234) (xy 445.241299 -64.713201) (xy 445.264147 -64.762947) (xy 445.279645 -64.815449)
			(xy 445.287475 -64.869629) (xy 445.287475 -64.924371) (xy 445.279645 -64.978551) (xy 445.264147 -65.031053)
			(xy 445.241299 -65.080799) (xy 445.211571 -65.126766) (xy 445.193928 -65.147698) (xy 445.187832 -65.15481)
			(xy 445.181482 -65.171828) (xy 445.181482 -65.257172) (xy 445.187832 -65.27419) (xy 445.193928 -65.281302)
			(xy 445.211586 -65.302219) (xy 445.241294 -65.348196) (xy 445.264126 -65.397948) (xy 445.279613 -65.450452)
			(xy 445.287436 -65.50463) (xy 445.287908 -65.532) (xy 445.287422 -65.559251) (xy 445.279666 -65.613199)
			(xy 445.264311 -65.665494) (xy 445.241669 -65.715071) (xy 445.212203 -65.760921) (xy 445.176512 -65.802112)
			(xy 445.135321 -65.837803) (xy 445.089471 -65.867269) (xy 445.039894 -65.889911) (xy 444.987599 -65.905266)
			(xy 444.933651 -65.913022) (xy 444.879149 -65.913022) (xy 444.825201 -65.905266) (xy 444.772906 -65.889911)
			(xy 444.723329 -65.867269) (xy 444.677479 -65.837803) (xy 444.636288 -65.802112) (xy 444.600597 -65.760921)
			(xy 444.571131 -65.715071) (xy 444.548489 -65.665494) (xy 444.533134 -65.613199) (xy 444.525378 -65.559251)
			(xy 444.524892 -65.532) (xy 442.493908 -65.532) (xy 442.493422 -65.559251) (xy 442.485666 -65.613199)
			(xy 442.470311 -65.665494) (xy 442.447669 -65.715071) (xy 442.418203 -65.760921) (xy 442.382512 -65.802112)
			(xy 442.341321 -65.837803) (xy 442.295471 -65.867269) (xy 442.245894 -65.889911) (xy 442.193599 -65.905266)
			(xy 442.139651 -65.913022) (xy 442.085149 -65.913022) (xy 442.031201 -65.905266) (xy 441.978906 -65.889911)
			(xy 441.929329 -65.867269) (xy 441.883479 -65.837803) (xy 441.842288 -65.802112) (xy 441.806597 -65.760921)
			(xy 441.777131 -65.715071) (xy 441.754489 -65.665494) (xy 441.739134 -65.613199) (xy 441.731378 -65.559251)
			(xy 441.730892 -65.532) (xy 416.667696 -65.532) (xy 416.667696 -77.677518) (xy 467.2076 -77.677518)
			(xy 467.2076 -67.585082) (xy 467.20799 -67.575008) (xy 467.215732 -67.556409) (xy 467.222586 -67.549014)
			(xy 467.726014 -67.045586) (xy 467.733414 -67.038746) (xy 467.752013 -67.031027) (xy 467.762082 -67.0306)
			(xy 472.698318 -67.0306) (xy 472.708392 -67.03099) (xy 472.726991 -67.038732) (xy 472.734386 -67.045586)
			(xy 473.263214 -67.574414) (xy 473.270054 -67.581814) (xy 473.277773 -67.600413) (xy 473.2782 -67.610482)
			(xy 473.2782 -77.652118) (xy 473.27781 -77.662192) (xy 473.270068 -77.680791) (xy 473.263214 -77.688186)
			(xy 472.658186 -78.293214) (xy 472.650786 -78.300054) (xy 472.632187 -78.307773) (xy 472.622118 -78.3082)
			(xy 467.838282 -78.3082) (xy 467.828208 -78.30781) (xy 467.809609 -78.300068) (xy 467.802214 -78.293214)
			(xy 467.222586 -77.713586) (xy 467.215746 -77.706186) (xy 467.208027 -77.687587) (xy 467.2076 -77.677518)
			(xy 416.667696 -77.677518) (xy 416.667696 -78.232) (xy 455.700382 -78.232) (xy 455.704453 -78.176378)
			(xy 455.716579 -78.121941) (xy 455.736502 -78.06985) (xy 455.763798 -78.021215) (xy 455.797884 -77.977072)
			(xy 455.838033 -77.938363) (xy 455.883391 -77.905912) (xy 455.932991 -77.880411) (xy 455.985775 -77.862404)
			(xy 456.040618 -77.852274) (xy 456.096352 -77.850237) (xy 456.151789 -77.856337) (xy 456.205746 -77.870443)
			(xy 456.257075 -77.892255) (xy 456.304681 -77.921309) (xy 456.347549 -77.956984) (xy 456.384766 -77.998521)
			(xy 456.415539 -78.045034) (xy 456.439211 -78.095531) (xy 456.455279 -78.148938) (xy 456.463399 -78.204114)
			(xy 456.463908 -78.232) (xy 456.463399 -78.259886) (xy 456.455279 -78.315062) (xy 456.439211 -78.368469)
			(xy 456.415539 -78.418966) (xy 456.384766 -78.465479) (xy 456.347549 -78.507016) (xy 456.304681 -78.542691)
			(xy 456.257075 -78.571745) (xy 456.205746 -78.593557) (xy 456.151789 -78.607663) (xy 456.096352 -78.613763)
			(xy 456.040618 -78.611726) (xy 455.985775 -78.601596) (xy 455.932991 -78.583589) (xy 455.883391 -78.558088)
			(xy 455.838033 -78.525637) (xy 455.797884 -78.486928) (xy 455.763798 -78.442785) (xy 455.736502 -78.39415)
			(xy 455.716579 -78.342059) (xy 455.704453 -78.287622) (xy 455.700382 -78.232) (xy 416.667696 -78.232)
			(xy 416.667696 -83.6676) (xy 449.020182 -83.6676) (xy 449.024253 -83.611978) (xy 449.036379 -83.557541)
			(xy 449.056302 -83.50545) (xy 449.083598 -83.456815) (xy 449.117684 -83.412672) (xy 449.157833 -83.373963)
			(xy 449.203191 -83.341512) (xy 449.252791 -83.316011) (xy 449.305575 -83.298004) (xy 449.360418 -83.287874)
			(xy 449.416152 -83.285837) (xy 449.471589 -83.291937) (xy 449.525546 -83.306043) (xy 449.576875 -83.327855)
			(xy 449.624481 -83.356909) (xy 449.667349 -83.392584) (xy 449.704566 -83.434121) (xy 449.735339 -83.480634)
			(xy 449.759011 -83.531131) (xy 449.775079 -83.584538) (xy 449.783199 -83.639714) (xy 449.783708 -83.6676)
			(xy 449.783199 -83.695486) (xy 449.775079 -83.750662) (xy 449.759011 -83.804069) (xy 449.735339 -83.854566)
			(xy 449.704566 -83.901079) (xy 449.667349 -83.942616) (xy 449.624481 -83.978291) (xy 449.576875 -84.007345)
			(xy 449.525546 -84.029157) (xy 449.471589 -84.043263) (xy 449.416152 -84.049363) (xy 449.360418 -84.047326)
			(xy 449.305575 -84.037196) (xy 449.252791 -84.019189) (xy 449.203191 -83.993688) (xy 449.157833 -83.961237)
			(xy 449.117684 -83.922528) (xy 449.083598 -83.878385) (xy 449.056302 -83.82975) (xy 449.036379 -83.777659)
			(xy 449.024253 -83.723222) (xy 449.020182 -83.6676) (xy 416.667696 -83.6676) (xy 416.667696 -85.000846)
			(xy 449.11975 -85.000846) (xy 449.123821 -84.945224) (xy 449.135947 -84.890787) (xy 449.15587 -84.838696)
			(xy 449.183166 -84.790061) (xy 449.217252 -84.745918) (xy 449.257401 -84.707209) (xy 449.302759 -84.674758)
			(xy 449.352359 -84.649257) (xy 449.405143 -84.63125) (xy 449.459986 -84.62112) (xy 449.51572 -84.619083)
			(xy 449.571157 -84.625183) (xy 449.625114 -84.639289) (xy 449.676443 -84.661101) (xy 449.724049 -84.690155)
			(xy 449.766917 -84.72583) (xy 449.804134 -84.767367) (xy 449.834907 -84.81388) (xy 449.858579 -84.864377)
			(xy 449.874647 -84.917784) (xy 449.882767 -84.97296) (xy 449.883276 -85.000846) (xy 449.882767 -85.028732)
			(xy 449.874647 -85.083908) (xy 449.858579 -85.137315) (xy 449.834907 -85.187812) (xy 449.804134 -85.234325)
			(xy 449.766917 -85.275862) (xy 449.724049 -85.311537) (xy 449.676443 -85.340591) (xy 449.625114 -85.362403)
			(xy 449.571157 -85.376509) (xy 449.51572 -85.382609) (xy 449.459986 -85.380572) (xy 449.405143 -85.370442)
			(xy 449.352359 -85.352435) (xy 449.302759 -85.326934) (xy 449.257401 -85.294483) (xy 449.217252 -85.255774)
			(xy 449.183166 -85.211631) (xy 449.15587 -85.162996) (xy 449.135947 -85.110905) (xy 449.123821 -85.056468)
			(xy 449.11975 -85.000846) (xy 416.667696 -85.000846) (xy 416.667696 -86.5124) (xy 449.020182 -86.5124)
			(xy 449.024253 -86.456778) (xy 449.036379 -86.402341) (xy 449.056302 -86.35025) (xy 449.083598 -86.301615)
			(xy 449.117684 -86.257472) (xy 449.157833 -86.218763) (xy 449.203191 -86.186312) (xy 449.252791 -86.160811)
			(xy 449.305575 -86.142804) (xy 449.360418 -86.132674) (xy 449.416152 -86.130637) (xy 449.471589 -86.136737)
			(xy 449.525546 -86.150843) (xy 449.576875 -86.172655) (xy 449.624481 -86.201709) (xy 449.667349 -86.237384)
			(xy 449.704566 -86.278921) (xy 449.735339 -86.325434) (xy 449.759011 -86.375931) (xy 449.775079 -86.429338)
			(xy 449.783199 -86.484514) (xy 449.783708 -86.5124) (xy 449.783199 -86.540286) (xy 449.775079 -86.595462)
			(xy 449.759011 -86.648869) (xy 449.735339 -86.699366) (xy 449.704566 -86.745879) (xy 449.667349 -86.787416)
			(xy 449.624481 -86.823091) (xy 449.576875 -86.852145) (xy 449.525546 -86.873957) (xy 449.471589 -86.888063)
			(xy 449.416152 -86.894163) (xy 449.360418 -86.892126) (xy 449.305575 -86.881996) (xy 449.252791 -86.863989)
			(xy 449.203191 -86.838488) (xy 449.157833 -86.806037) (xy 449.117684 -86.767328) (xy 449.083598 -86.723185)
			(xy 449.056302 -86.67455) (xy 449.036379 -86.622459) (xy 449.024253 -86.568022) (xy 449.020182 -86.5124)
			(xy 416.667696 -86.5124) (xy 416.667696 -87.9348) (xy 448.613782 -87.9348) (xy 448.617853 -87.879178)
			(xy 448.629979 -87.824741) (xy 448.649902 -87.77265) (xy 448.677198 -87.724015) (xy 448.711284 -87.679872)
			(xy 448.751433 -87.641163) (xy 448.796791 -87.608712) (xy 448.846391 -87.583211) (xy 448.899175 -87.565204)
			(xy 448.954018 -87.555074) (xy 449.009752 -87.553037) (xy 449.065189 -87.559137) (xy 449.119146 -87.573243)
			(xy 449.170475 -87.595055) (xy 449.218081 -87.624109) (xy 449.260949 -87.659784) (xy 449.298166 -87.701321)
			(xy 449.328939 -87.747834) (xy 449.352611 -87.798331) (xy 449.368679 -87.851738) (xy 449.376799 -87.906914)
			(xy 449.377308 -87.9348) (xy 449.376799 -87.962686) (xy 449.368679 -88.017862) (xy 449.352611 -88.071269)
			(xy 449.328939 -88.121766) (xy 449.298166 -88.168279) (xy 449.260949 -88.209816) (xy 449.218081 -88.245491)
			(xy 449.170475 -88.274545) (xy 449.119146 -88.296357) (xy 449.065189 -88.310463) (xy 449.009752 -88.316563)
			(xy 448.954018 -88.314526) (xy 448.899175 -88.304396) (xy 448.846391 -88.286389) (xy 448.796791 -88.260888)
			(xy 448.751433 -88.228437) (xy 448.711284 -88.189728) (xy 448.677198 -88.145585) (xy 448.649902 -88.09695)
			(xy 448.629979 -88.044859) (xy 448.617853 -87.990422) (xy 448.613782 -87.9348) (xy 416.667696 -87.9348)
			(xy 416.667696 -88.9) (xy 448.588382 -88.9) (xy 448.592453 -88.844378) (xy 448.604579 -88.789941)
			(xy 448.624502 -88.73785) (xy 448.651798 -88.689215) (xy 448.685884 -88.645072) (xy 448.726033 -88.606363)
			(xy 448.771391 -88.573912) (xy 448.820991 -88.548411) (xy 448.873775 -88.530404) (xy 448.928618 -88.520274)
			(xy 448.984352 -88.518237) (xy 449.039789 -88.524337) (xy 449.093746 -88.538443) (xy 449.145075 -88.560255)
			(xy 449.192681 -88.589309) (xy 449.235549 -88.624984) (xy 449.272766 -88.666521) (xy 449.303539 -88.713034)
			(xy 449.327211 -88.763531) (xy 449.343279 -88.816938) (xy 449.351399 -88.872114) (xy 449.351908 -88.9)
			(xy 449.351399 -88.927886) (xy 449.343279 -88.983062) (xy 449.327211 -89.036469) (xy 449.303539 -89.086966)
			(xy 449.272766 -89.133479) (xy 449.235549 -89.175016) (xy 449.192681 -89.210691) (xy 449.145075 -89.239745)
			(xy 449.093746 -89.261557) (xy 449.039789 -89.275663) (xy 448.984352 -89.281763) (xy 448.928618 -89.279726)
			(xy 448.873775 -89.269596) (xy 448.820991 -89.251589) (xy 448.771391 -89.226088) (xy 448.726033 -89.193637)
			(xy 448.685884 -89.154928) (xy 448.651798 -89.110785) (xy 448.624502 -89.06215) (xy 448.604579 -89.010059)
			(xy 448.592453 -88.955622) (xy 448.588382 -88.9) (xy 416.667696 -88.9) (xy 416.667696 -89.48547)
			(xy 450.565774 -89.48547) (xy 450.566278 -89.443122) (xy 450.574329 -89.358808) (xy 450.590358 -89.275642)
			(xy 450.614219 -89.194375) (xy 450.645698 -89.115745) (xy 450.684509 -89.040464) (xy 450.730299 -88.969212)
			(xy 450.782655 -88.902636) (xy 450.841103 -88.841338) (xy 450.905113 -88.785873) (xy 450.974105 -88.736744)
			(xy 451.047455 -88.694395) (xy 451.124498 -88.659211) (xy 451.204537 -88.631509) (xy 451.286846 -88.611541)
			(xy 451.370681 -88.599488) (xy 451.455282 -88.595458) (xy 451.539883 -88.599488) (xy 451.623718 -88.611541)
			(xy 451.706027 -88.631509) (xy 451.786066 -88.659211) (xy 451.863109 -88.694395) (xy 451.936459 -88.736744)
			(xy 452.005451 -88.785873) (xy 452.069461 -88.841338) (xy 452.127909 -88.902636) (xy 452.180265 -88.969212)
			(xy 452.226055 -89.040464) (xy 452.264866 -89.115745) (xy 452.296345 -89.194375) (xy 452.320206 -89.275642)
			(xy 452.336235 -89.358808) (xy 452.344286 -89.443122) (xy 452.34479 -89.48547) (xy 452.344321 -89.52667)
			(xy 452.336711 -89.608717) (xy 452.321545 -89.689709) (xy 452.298952 -89.76895) (xy 452.269127 -89.845762)
			(xy 452.232324 -89.919486) (xy 452.18886 -89.98949) (xy 452.139106 -90.055173) (xy 452.083491 -90.115972)
			(xy 452.02249 -90.171367) (xy 451.956627 -90.220882) (xy 451.886466 -90.264092) (xy 451.849744 -90.282776)
			(xy 451.841499 -90.287317) (xy 451.828731 -90.301124) (xy 451.824852 -90.3097) (xy 451.813676 -90.338148)
			(xy 451.810747 -90.346716) (xy 451.81048 -90.364808) (xy 451.813168 -90.373454) (xy 451.823254 -90.404164)
			(xy 451.834103 -90.467882) (xy 451.834758 -90.5002) (xy 451.834272 -90.527451) (xy 451.826516 -90.581399)
			(xy 451.811161 -90.633694) (xy 451.788519 -90.683271) (xy 451.759053 -90.729121) (xy 451.723362 -90.770312)
			(xy 451.682171 -90.806003) (xy 451.636321 -90.835469) (xy 451.586744 -90.858111) (xy 451.534449 -90.873466)
			(xy 451.480501 -90.881222) (xy 451.425999 -90.881222) (xy 451.372051 -90.873466) (xy 451.319756 -90.858111)
			(xy 451.270179 -90.835469) (xy 451.224329 -90.806003) (xy 451.183138 -90.770312) (xy 451.147447 -90.729121)
			(xy 451.117981 -90.683271) (xy 451.095339 -90.633694) (xy 451.079984 -90.581399) (xy 451.072228 -90.527451)
			(xy 451.071742 -90.5002) (xy 451.072393 -90.467541) (xy 451.083513 -90.403175) (xy 451.09384 -90.372184)
			(xy 451.096584 -90.363481) (xy 451.096316 -90.345248) (xy 451.093332 -90.336624) (xy 451.08241 -90.30843)
			(xy 451.078645 -90.299794) (xy 451.065991 -90.285858) (xy 451.057772 -90.281252) (xy 451.02127 -90.262453)
			(xy 450.951512 -90.219142) (xy 450.886042 -90.169587) (xy 450.825417 -90.114209) (xy 450.770153 -90.053481)
			(xy 450.72072 -89.987918) (xy 450.677539 -89.918079) (xy 450.640977 -89.844559) (xy 450.611346 -89.767981)
			(xy 450.588897 -89.689) (xy 450.573822 -89.608285) (xy 450.56625 -89.526525) (xy 450.565774 -89.48547)
			(xy 416.667696 -89.48547) (xy 416.667696 -104.549956) (xy 422.484046 -104.549956) (xy 422.488076 -104.407621)
			(xy 422.500151 -104.265741) (xy 422.520234 -104.124773) (xy 422.548261 -103.985166) (xy 422.584141 -103.847368)
			(xy 422.627759 -103.711821) (xy 422.678976 -103.578959) (xy 422.737627 -103.449207) (xy 422.803525 -103.322981)
			(xy 422.876459 -103.200685) (xy 422.956196 -103.082712) (xy 423.042478 -102.969439) (xy 423.135031 -102.861228)
			(xy 423.233558 -102.758427) (xy 423.337743 -102.661365) (xy 423.447252 -102.570353) (xy 423.561735 -102.485681)
			(xy 423.680825 -102.407623) (xy 423.80414 -102.336427) (xy 423.931286 -102.272321) (xy 424.061855 -102.215512)
			(xy 424.195429 -102.16618) (xy 424.33158 -102.124484) (xy 424.469871 -102.090558) (xy 424.609861 -102.06451)
			(xy 424.7511 -102.046424) (xy 424.893136 -102.036357) (xy 425.035514 -102.034342) (xy 425.177778 -102.040385)
			(xy 425.319472 -102.054467) (xy 425.460142 -102.076543) (xy 425.599339 -102.106543) (xy 425.736615 -102.144369)
			(xy 425.871531 -102.189901) (xy 426.003655 -102.242992) (xy 426.132564 -102.303474) (xy 426.257845 -102.371152)
			(xy 426.379096 -102.445809) (xy 426.495929 -102.527207) (xy 426.60797 -102.615084) (xy 426.71486 -102.709159)
			(xy 426.816257 -102.809131) (xy 426.911835 -102.914679) (xy 427.001289 -103.025465) (xy 427.084331 -103.141134)
			(xy 427.160697 -103.261317) (xy 427.230141 -103.385627) (xy 427.292441 -103.513668) (xy 427.347397 -103.645027)
			(xy 427.394834 -103.779286) (xy 427.434598 -103.916013) (xy 427.466564 -104.054771) (xy 427.490629 -104.195115)
			(xy 427.506715 -104.336596) (xy 427.51477 -104.47876) (xy 427.515274 -104.549956) (xy 427.51477 -104.621152)
			(xy 427.506715 -104.763316) (xy 427.490629 -104.904797) (xy 427.466564 -105.045141) (xy 427.434598 -105.183899)
			(xy 427.394834 -105.320626) (xy 427.347397 -105.454885) (xy 427.292441 -105.586244) (xy 427.230141 -105.714285)
			(xy 427.160697 -105.838595) (xy 427.084331 -105.958778) (xy 427.001289 -106.074447) (xy 426.911835 -106.185233)
			(xy 426.816257 -106.290781) (xy 426.71486 -106.390753) (xy 426.60797 -106.484828) (xy 426.495929 -106.572705)
			(xy 426.379096 -106.654103) (xy 426.257845 -106.72876) (xy 426.132564 -106.796438) (xy 426.003655 -106.85692)
			(xy 425.871531 -106.910011) (xy 425.736615 -106.955543) (xy 425.599339 -106.993369) (xy 425.460142 -107.023369)
			(xy 425.319472 -107.045445) (xy 425.177778 -107.059527) (xy 425.035514 -107.06557) (xy 424.893136 -107.063555)
			(xy 424.7511 -107.053488) (xy 424.609861 -107.035402) (xy 424.469871 -107.009354) (xy 424.33158 -106.975428)
			(xy 424.195429 -106.933732) (xy 424.061855 -106.8844) (xy 423.931286 -106.827591) (xy 423.80414 -106.763485)
			(xy 423.680825 -106.692289) (xy 423.561735 -106.614231) (xy 423.447252 -106.529559) (xy 423.337743 -106.438547)
			(xy 423.233558 -106.341485) (xy 423.135031 -106.238684) (xy 423.042478 -106.130473) (xy 422.956196 -106.0172)
			(xy 422.876459 -105.899227) (xy 422.803525 -105.776931) (xy 422.737627 -105.650705) (xy 422.678976 -105.520953)
			(xy 422.627759 -105.388091) (xy 422.584141 -105.252544) (xy 422.548261 -105.114746) (xy 422.520234 -104.975139)
			(xy 422.500151 -104.834171) (xy 422.488076 -104.692291) (xy 422.484046 -104.549956) (xy 416.667696 -104.549956)
			(xy 416.667696 -108.86821) (xy 450.581268 -108.86821) (xy 450.581268 -97.953322) (xy 450.581687 -97.943252)
			(xy 450.58941 -97.924653) (xy 450.596254 -97.917254) (xy 451.856856 -96.656652) (xy 451.864327 -96.649945)
			(xy 451.882894 -96.642363) (xy 451.892924 -96.64192) (xy 455.107802 -96.64192) (xy 455.117806 -96.641451)
			(xy 455.136269 -96.633738) (xy 455.143616 -96.626934) (xy 456.32116 -95.44939) (xy 456.327813 -95.441958)
			(xy 456.335404 -95.423537) (xy 456.335892 -95.413576) (xy 456.335892 -85.355938) (xy 456.336313 -85.345868)
			(xy 456.344034 -85.327269) (xy 456.350878 -85.31987) (xy 459.48727 -82.183478) (xy 459.494684 -82.176655)
			(xy 459.513273 -82.168926) (xy 459.523338 -82.168492) (xy 467.212426 -82.168492) (xy 467.222398 -82.168058)
			(xy 467.240834 -82.160455) (xy 467.24824 -82.15376) (xy 467.472014 -81.929986) (xy 467.478854 -81.922586)
			(xy 467.486573 -81.903987) (xy 467.487 -81.893918) (xy 467.487 -81.287366) (xy 467.48573 -81.281778)
			(xy 467.475045 -81.232045) (xy 467.463584 -81.130965) (xy 467.46287 -81.080102) (xy 467.463564 -81.029237)
			(xy 467.475023 -80.928156) (xy 467.48573 -80.878426) (xy 467.487 -80.872838) (xy 467.487 -80.666082)
			(xy 467.48739 -80.656008) (xy 467.495132 -80.637409) (xy 467.501986 -80.630014) (xy 469.072214 -79.059786)
			(xy 469.079614 -79.052946) (xy 469.098213 -79.045227) (xy 469.108282 -79.0448) (xy 469.149938 -79.0448)
			(xy 469.163146 -79.041244) (xy 469.169242 -79.037434) (xy 469.204426 -79.016776) (xy 469.277825 -78.981131)
			(xy 469.354141 -78.952259) (xy 469.432753 -78.930395) (xy 469.513018 -78.915719) (xy 469.59428 -78.908349)
			(xy 469.635078 -78.907894) (xy 469.677939 -78.908416) (xy 469.763275 -78.916538) (xy 469.847456 -78.932721)
			(xy 469.929721 -78.956818) (xy 470.009329 -78.988613) (xy 470.08556 -79.027818) (xy 470.157728 -79.074079)
			(xy 470.22518 -79.12698) (xy 470.287309 -79.186041) (xy 470.343552 -79.250732) (xy 470.393404 -79.320468)
			(xy 470.436415 -79.394619) (xy 470.472195 -79.472516) (xy 470.500422 -79.553458) (xy 470.511124 -79.594964)
			(xy 470.512902 -79.601822) (xy 470.51976 -79.61376) (xy 471.10142 -80.19542) (xy 471.113358 -80.202278)
			(xy 471.120216 -80.204056) (xy 471.161705 -80.214817) (xy 471.242638 -80.243051) (xy 471.320528 -80.278836)
			(xy 471.394672 -80.321847) (xy 471.464402 -80.371698) (xy 471.529088 -80.427938) (xy 471.588148 -80.490061)
			(xy 471.641049 -80.557506) (xy 471.687313 -80.629666) (xy 471.726524 -80.705888) (xy 471.758327 -80.785486)
			(xy 471.782437 -80.867742) (xy 471.798634 -80.951915) (xy 471.806775 -81.037244) (xy 471.807286 -81.080102)
			(xy 471.806764 -81.123548) (xy 471.798412 -81.210039) (xy 471.781786 -81.295326) (xy 471.75704 -81.378621)
			(xy 471.724402 -81.459151) (xy 471.684175 -81.536172) (xy 471.636732 -81.60897) (xy 471.582511 -81.67687)
			(xy 471.522015 -81.739245) (xy 471.455804 -81.795517) (xy 471.420444 -81.820766) (xy 471.410618 -81.828239)
			(xy 471.399181 -81.850089) (xy 471.3986 -81.862422) (xy 471.3986 -82.837782) (xy 471.399365 -82.850065)
			(xy 471.410774 -82.871826) (xy 471.420444 -82.879438) (xy 471.455808 -82.904682) (xy 471.522019 -82.960954)
			(xy 471.582515 -83.023329) (xy 471.636736 -83.091231) (xy 471.68418 -83.164029) (xy 471.724406 -83.24105)
			(xy 471.757044 -83.321581) (xy 471.78179 -83.404876) (xy 471.798416 -83.490164) (xy 471.806768 -83.576655)
			(xy 471.807286 -83.620102) (xy 471.80663 -83.668574) (xy 471.796218 -83.764957) (xy 471.775547 -83.859672)
			(xy 471.760804 -83.905852) (xy 471.756232 -83.919568) (xy 471.762836 -83.947508) (xy 471.847672 -84.032344)
			(xy 471.875612 -84.038948) (xy 471.889328 -84.034376) (xy 471.935506 -84.019624) (xy 472.030219 -83.998934)
			(xy 472.126605 -83.988532) (xy 472.175078 -83.987894) (xy 472.218033 -83.988384) (xy 472.303553 -83.996548)
			(xy 472.38791 -84.012805) (xy 472.47034 -84.037007) (xy 472.550096 -84.068934) (xy 472.626456 -84.108299)
			(xy 472.698728 -84.154744) (xy 472.766258 -84.207849) (xy 472.828434 -84.267132) (xy 472.884694 -84.332057)
			(xy 472.934527 -84.402037) (xy 472.977482 -84.476436) (xy 473.013171 -84.554581) (xy 473.041269 -84.635766)
			(xy 473.061523 -84.719253) (xy 473.07375 -84.804288) (xy 473.077838 -84.8901) (xy 473.07375 -84.975912)
			(xy 473.061523 -85.060947) (xy 473.041269 -85.144434) (xy 473.013171 -85.225619) (xy 472.977482 -85.303764)
			(xy 472.934527 -85.378163) (xy 472.884694 -85.448143) (xy 472.828434 -85.513068) (xy 472.766258 -85.572351)
			(xy 472.698728 -85.625456) (xy 472.626456 -85.671901) (xy 472.550096 -85.711266) (xy 472.47034 -85.743193)
			(xy 472.38791 -85.767395) (xy 472.303553 -85.783652) (xy 472.218033 -85.791816) (xy 472.175078 -85.79231)
			(xy 472.126606 -85.791658) (xy 472.030223 -85.781244) (xy 471.935508 -85.760571) (xy 471.889328 -85.745828)
			(xy 471.875612 -85.741256) (xy 471.847672 -85.74786) (xy 471.762836 -85.832696) (xy 471.756232 -85.860636)
			(xy 471.760804 -85.874352) (xy 471.775561 -85.920529) (xy 471.79625 -86.015242) (xy 471.806649 -86.111629)
			(xy 471.807286 -86.160102) (xy 471.80663 -86.208574) (xy 471.796218 -86.304957) (xy 471.775547 -86.399672)
			(xy 471.760804 -86.445852) (xy 471.756232 -86.459568) (xy 471.762836 -86.487508) (xy 471.847672 -86.572344)
			(xy 471.875612 -86.578948) (xy 471.889328 -86.574376) (xy 471.935506 -86.559624) (xy 472.030219 -86.538934)
			(xy 472.126605 -86.528532) (xy 472.175078 -86.527894) (xy 472.218033 -86.528384) (xy 472.303553 -86.536548)
			(xy 472.38791 -86.552805) (xy 472.47034 -86.577007) (xy 472.550096 -86.608934) (xy 472.626456 -86.648299)
			(xy 472.698728 -86.694744) (xy 472.766258 -86.747849) (xy 472.828434 -86.807132) (xy 472.884694 -86.872057)
			(xy 472.934527 -86.942037) (xy 472.977482 -87.016436) (xy 473.013171 -87.094581) (xy 473.041269 -87.175766)
			(xy 473.061523 -87.259253) (xy 473.07375 -87.344288) (xy 473.077838 -87.4301) (xy 473.07375 -87.515912)
			(xy 473.061523 -87.600947) (xy 473.041269 -87.684434) (xy 473.013171 -87.765619) (xy 472.977482 -87.843764)
			(xy 472.934527 -87.918163) (xy 472.884694 -87.988143) (xy 472.828434 -88.053068) (xy 472.766258 -88.112351)
			(xy 472.698728 -88.165456) (xy 472.626456 -88.211901) (xy 472.550096 -88.251266) (xy 472.47034 -88.283193)
			(xy 472.38791 -88.307395) (xy 472.303553 -88.323652) (xy 472.218033 -88.331816) (xy 472.175078 -88.33231)
			(xy 472.126606 -88.331658) (xy 472.030223 -88.321244) (xy 471.935508 -88.300571) (xy 471.889328 -88.285828)
			(xy 471.875612 -88.281256) (xy 471.847672 -88.28786) (xy 471.762836 -88.372696) (xy 471.756232 -88.400636)
			(xy 471.760804 -88.414352) (xy 471.775561 -88.460529) (xy 471.79625 -88.555242) (xy 471.806649 -88.651629)
			(xy 471.807286 -88.700102) (xy 471.806843 -88.741793) (xy 471.799149 -88.824818) (xy 471.783828 -88.90678)
			(xy 471.761009 -88.986978) (xy 471.730887 -89.064729) (xy 471.69372 -89.139368) (xy 471.649825 -89.21026)
			(xy 471.599576 -89.276799) (xy 471.543401 -89.338418) (xy 471.481781 -89.394591) (xy 471.41524 -89.444839)
			(xy 471.344347 -89.488732) (xy 471.269707 -89.525897) (xy 471.191955 -89.556016) (xy 471.111757 -89.578833)
			(xy 471.029795 -89.594153) (xy 470.946769 -89.601844) (xy 470.905078 -89.60231) (xy 470.861508 -89.601785)
			(xy 470.774774 -89.593375) (xy 470.689254 -89.576645) (xy 470.605744 -89.551752) (xy 470.525023 -89.518926)
			(xy 470.44784 -89.478474) (xy 470.374916 -89.430771) (xy 470.306928 -89.376262) (xy 470.24451 -89.315455)
			(xy 470.215976 -89.282524) (xy 470.209118 -89.274142) (xy 470.190322 -89.264998) (xy 470.104724 -89.261442)
			(xy 470.094137 -89.261574) (xy 470.074455 -89.269304) (xy 470.066624 -89.276428) (xy 468.22614 -91.116912)
			(xy 468.219486 -91.124343) (xy 468.211896 -91.142765) (xy 468.211408 -91.152726) (xy 468.211408 -91.549982)
			(xy 470.018627 -91.549982) (xy 470.022616 -91.437017) (xy 470.034564 -91.324614) (xy 470.054411 -91.213334)
			(xy 470.082057 -91.103732) (xy 470.117367 -90.996352) (xy 470.160162 -90.891731) (xy 470.210231 -90.790389)
			(xy 470.267324 -90.692831) (xy 470.331157 -90.599544) (xy 470.40141 -90.510991) (xy 470.477735 -90.427615)
			(xy 470.559751 -90.349831) (xy 470.64705 -90.278025) (xy 470.739196 -90.212556) (xy 470.835731 -90.153751)
			(xy 470.936174 -90.101901) (xy 471.040024 -90.057266) (xy 471.146763 -90.020067) (xy 471.255861 -89.99049)
			(xy 471.366773 -89.968682) (xy 471.478947 -89.954753) (xy 471.591825 -89.94877) (xy 471.704843 -89.950765)
			(xy 471.817439 -89.960727) (xy 471.929052 -89.978607) (xy 472.039125 -90.004315) (xy 472.147111 -90.037724)
			(xy 472.252471 -90.078667) (xy 472.354681 -90.126939) (xy 472.453231 -90.182302) (xy 472.547631 -90.244477)
			(xy 472.637409 -90.313157) (xy 472.722119 -90.387999) (xy 472.801339 -90.46863) (xy 472.874674 -90.554647)
			(xy 472.941759 -90.645624) (xy 473.002259 -90.741106) (xy 473.055873 -90.840618) (xy 473.102335 -90.943664)
			(xy 473.141412 -91.04973) (xy 473.172909 -91.158289) (xy 473.196671 -91.268799) (xy 473.212578 -91.38071)
			(xy 473.220551 -91.493464) (xy 473.22105 -91.549982) (xy 473.220551 -91.6065) (xy 473.212578 -91.719254)
			(xy 473.196671 -91.831165) (xy 473.172909 -91.941675) (xy 473.141412 -92.050234) (xy 473.102335 -92.1563)
			(xy 473.055873 -92.259346) (xy 473.002259 -92.358858) (xy 472.941759 -92.45434) (xy 472.874674 -92.545317)
			(xy 472.801339 -92.631334) (xy 472.722119 -92.711965) (xy 472.637409 -92.786807) (xy 472.547631 -92.855487)
			(xy 472.453231 -92.917662) (xy 472.354681 -92.973025) (xy 472.252471 -93.021297) (xy 472.147111 -93.06224)
			(xy 472.039125 -93.095649) (xy 471.929052 -93.121357) (xy 471.817439 -93.139237) (xy 471.704843 -93.149199)
			(xy 471.591825 -93.151194) (xy 471.478947 -93.145211) (xy 471.366773 -93.131282) (xy 471.255861 -93.109474)
			(xy 471.146763 -93.079897) (xy 471.040024 -93.042698) (xy 470.936174 -92.998063) (xy 470.835731 -92.946213)
			(xy 470.739196 -92.887408) (xy 470.64705 -92.821939) (xy 470.559751 -92.750133) (xy 470.477735 -92.672349)
			(xy 470.40141 -92.588973) (xy 470.331157 -92.50042) (xy 470.267324 -92.407133) (xy 470.210231 -92.309575)
			(xy 470.160162 -92.208233) (xy 470.117367 -92.103612) (xy 470.082057 -91.996232) (xy 470.054411 -91.88663)
			(xy 470.034564 -91.77535) (xy 470.022616 -91.662947) (xy 470.018627 -91.549982) (xy 468.211408 -91.549982)
			(xy 468.211408 -102.676452) (xy 468.210982 -102.686522) (xy 468.203264 -102.705121) (xy 468.196422 -102.71252)
			(xy 464.42249 -106.486452) (xy 466.257638 -106.486452) (xy 466.261709 -106.43083) (xy 466.273835 -106.376393)
			(xy 466.293758 -106.324302) (xy 466.321054 -106.275667) (xy 466.35514 -106.231524) (xy 466.395289 -106.192815)
			(xy 466.440647 -106.160364) (xy 466.490247 -106.134863) (xy 466.543031 -106.116856) (xy 466.597874 -106.106726)
			(xy 466.653608 -106.104689) (xy 466.709045 -106.110789) (xy 466.763002 -106.124895) (xy 466.814331 -106.146707)
			(xy 466.861937 -106.175761) (xy 466.904805 -106.211436) (xy 466.942022 -106.252973) (xy 466.972795 -106.299486)
			(xy 466.996467 -106.349983) (xy 467.012535 -106.40339) (xy 467.020655 -106.458566) (xy 467.021164 -106.486452)
			(xy 467.527638 -106.486452) (xy 467.531709 -106.43083) (xy 467.543835 -106.376393) (xy 467.563758 -106.324302)
			(xy 467.591054 -106.275667) (xy 467.62514 -106.231524) (xy 467.665289 -106.192815) (xy 467.710647 -106.160364)
			(xy 467.760247 -106.134863) (xy 467.813031 -106.116856) (xy 467.867874 -106.106726) (xy 467.923608 -106.104689)
			(xy 467.979045 -106.110789) (xy 468.033002 -106.124895) (xy 468.084331 -106.146707) (xy 468.131937 -106.175761)
			(xy 468.174805 -106.211436) (xy 468.212022 -106.252973) (xy 468.242795 -106.299486) (xy 468.266467 -106.349983)
			(xy 468.282535 -106.40339) (xy 468.290655 -106.458566) (xy 468.291164 -106.486452) (xy 468.797638 -106.486452)
			(xy 468.801709 -106.43083) (xy 468.813835 -106.376393) (xy 468.833758 -106.324302) (xy 468.861054 -106.275667)
			(xy 468.89514 -106.231524) (xy 468.935289 -106.192815) (xy 468.980647 -106.160364) (xy 469.030247 -106.134863)
			(xy 469.083031 -106.116856) (xy 469.137874 -106.106726) (xy 469.193608 -106.104689) (xy 469.249045 -106.110789)
			(xy 469.303002 -106.124895) (xy 469.354331 -106.146707) (xy 469.401937 -106.175761) (xy 469.444805 -106.211436)
			(xy 469.482022 -106.252973) (xy 469.512795 -106.299486) (xy 469.536467 -106.349983) (xy 469.552535 -106.40339)
			(xy 469.560655 -106.458566) (xy 469.561164 -106.486452) (xy 470.067638 -106.486452) (xy 470.071709 -106.43083)
			(xy 470.083835 -106.376393) (xy 470.103758 -106.324302) (xy 470.131054 -106.275667) (xy 470.16514 -106.231524)
			(xy 470.205289 -106.192815) (xy 470.250647 -106.160364) (xy 470.300247 -106.134863) (xy 470.353031 -106.116856)
			(xy 470.407874 -106.106726) (xy 470.463608 -106.104689) (xy 470.519045 -106.110789) (xy 470.573002 -106.124895)
			(xy 470.624331 -106.146707) (xy 470.671937 -106.175761) (xy 470.714805 -106.211436) (xy 470.752022 -106.252973)
			(xy 470.782795 -106.299486) (xy 470.806467 -106.349983) (xy 470.822535 -106.40339) (xy 470.830655 -106.458566)
			(xy 470.831164 -106.486452) (xy 470.830655 -106.514338) (xy 470.822535 -106.569514) (xy 470.806467 -106.622921)
			(xy 470.782795 -106.673418) (xy 470.752022 -106.719931) (xy 470.714805 -106.761468) (xy 470.671937 -106.797143)
			(xy 470.624331 -106.826197) (xy 470.573002 -106.848009) (xy 470.519045 -106.862115) (xy 470.463608 -106.868215)
			(xy 470.407874 -106.866178) (xy 470.353031 -106.856048) (xy 470.300247 -106.838041) (xy 470.250647 -106.81254)
			(xy 470.205289 -106.780089) (xy 470.16514 -106.74138) (xy 470.131054 -106.697237) (xy 470.103758 -106.648602)
			(xy 470.083835 -106.596511) (xy 470.071709 -106.542074) (xy 470.067638 -106.486452) (xy 469.561164 -106.486452)
			(xy 469.560655 -106.514338) (xy 469.552535 -106.569514) (xy 469.536467 -106.622921) (xy 469.512795 -106.673418)
			(xy 469.482022 -106.719931) (xy 469.444805 -106.761468) (xy 469.401937 -106.797143) (xy 469.354331 -106.826197)
			(xy 469.303002 -106.848009) (xy 469.249045 -106.862115) (xy 469.193608 -106.868215) (xy 469.137874 -106.866178)
			(xy 469.083031 -106.856048) (xy 469.030247 -106.838041) (xy 468.980647 -106.81254) (xy 468.935289 -106.780089)
			(xy 468.89514 -106.74138) (xy 468.861054 -106.697237) (xy 468.833758 -106.648602) (xy 468.813835 -106.596511)
			(xy 468.801709 -106.542074) (xy 468.797638 -106.486452) (xy 468.291164 -106.486452) (xy 468.290655 -106.514338)
			(xy 468.282535 -106.569514) (xy 468.266467 -106.622921) (xy 468.242795 -106.673418) (xy 468.212022 -106.719931)
			(xy 468.174805 -106.761468) (xy 468.131937 -106.797143) (xy 468.084331 -106.826197) (xy 468.033002 -106.848009)
			(xy 467.979045 -106.862115) (xy 467.923608 -106.868215) (xy 467.867874 -106.866178) (xy 467.813031 -106.856048)
			(xy 467.760247 -106.838041) (xy 467.710647 -106.81254) (xy 467.665289 -106.780089) (xy 467.62514 -106.74138)
			(xy 467.591054 -106.697237) (xy 467.563758 -106.648602) (xy 467.543835 -106.596511) (xy 467.531709 -106.542074)
			(xy 467.527638 -106.486452) (xy 467.021164 -106.486452) (xy 467.020655 -106.514338) (xy 467.012535 -106.569514)
			(xy 466.996467 -106.622921) (xy 466.972795 -106.673418) (xy 466.942022 -106.719931) (xy 466.904805 -106.761468)
			(xy 466.861937 -106.797143) (xy 466.814331 -106.826197) (xy 466.763002 -106.848009) (xy 466.709045 -106.862115)
			(xy 466.653608 -106.868215) (xy 466.597874 -106.866178) (xy 466.543031 -106.856048) (xy 466.490247 -106.838041)
			(xy 466.440647 -106.81254) (xy 466.395289 -106.780089) (xy 466.35514 -106.74138) (xy 466.321054 -106.697237)
			(xy 466.293758 -106.648602) (xy 466.273835 -106.596511) (xy 466.261709 -106.542074) (xy 466.257638 -106.486452)
			(xy 464.42249 -106.486452) (xy 462.13649 -108.772452) (xy 466.257638 -108.772452) (xy 466.261709 -108.71683)
			(xy 466.273835 -108.662393) (xy 466.293758 -108.610302) (xy 466.321054 -108.561667) (xy 466.35514 -108.517524)
			(xy 466.395289 -108.478815) (xy 466.440647 -108.446364) (xy 466.490247 -108.420863) (xy 466.543031 -108.402856)
			(xy 466.597874 -108.392726) (xy 466.653608 -108.390689) (xy 466.709045 -108.396789) (xy 466.763002 -108.410895)
			(xy 466.814331 -108.432707) (xy 466.861937 -108.461761) (xy 466.904805 -108.497436) (xy 466.942022 -108.538973)
			(xy 466.972795 -108.585486) (xy 466.996467 -108.635983) (xy 467.012535 -108.68939) (xy 467.020655 -108.744566)
			(xy 467.021164 -108.772452) (xy 467.020655 -108.800338) (xy 467.012535 -108.855514) (xy 466.996467 -108.908921)
			(xy 466.972795 -108.959418) (xy 466.942022 -109.005931) (xy 466.904805 -109.047468) (xy 466.861937 -109.083143)
			(xy 466.814331 -109.112197) (xy 466.763002 -109.134009) (xy 466.709045 -109.148115) (xy 466.653608 -109.154215)
			(xy 466.597874 -109.152178) (xy 466.543031 -109.142048) (xy 466.490247 -109.124041) (xy 466.440647 -109.09854)
			(xy 466.395289 -109.066089) (xy 466.35514 -109.02738) (xy 466.321054 -108.983237) (xy 466.293758 -108.934602)
			(xy 466.273835 -108.882511) (xy 466.261709 -108.828074) (xy 466.257638 -108.772452) (xy 462.13649 -108.772452)
			(xy 461.54467 -109.364272) (xy 468.797638 -109.364272) (xy 468.801709 -109.30865) (xy 468.813835 -109.254213)
			(xy 468.833758 -109.202122) (xy 468.861054 -109.153487) (xy 468.89514 -109.109344) (xy 468.935289 -109.070635)
			(xy 468.980647 -109.038184) (xy 469.030247 -109.012683) (xy 469.083031 -108.994676) (xy 469.137874 -108.984546)
			(xy 469.193608 -108.982509) (xy 469.249045 -108.988609) (xy 469.303002 -109.002715) (xy 469.354331 -109.024527)
			(xy 469.401937 -109.053581) (xy 469.444805 -109.089256) (xy 469.482022 -109.130793) (xy 469.512795 -109.177306)
			(xy 469.536467 -109.227803) (xy 469.552535 -109.28121) (xy 469.560655 -109.336386) (xy 469.561164 -109.364272)
			(xy 469.560655 -109.392158) (xy 469.552535 -109.447334) (xy 469.536467 -109.500741) (xy 469.512795 -109.551238)
			(xy 469.482022 -109.597751) (xy 469.444805 -109.639288) (xy 469.401937 -109.674963) (xy 469.354331 -109.704017)
			(xy 469.303002 -109.725829) (xy 469.249045 -109.739935) (xy 469.193608 -109.746035) (xy 469.137874 -109.743998)
			(xy 469.083031 -109.733868) (xy 469.030247 -109.715861) (xy 468.980647 -109.69036) (xy 468.935289 -109.657909)
			(xy 468.89514 -109.6192) (xy 468.861054 -109.575057) (xy 468.833758 -109.526422) (xy 468.813835 -109.474331)
			(xy 468.801709 -109.419894) (xy 468.797638 -109.364272) (xy 461.54467 -109.364272) (xy 461.19542 -109.713522)
			(xy 461.18801 -109.720349) (xy 461.169418 -109.728076) (xy 461.159352 -109.728508) (xy 451.441566 -109.728508)
			(xy 451.431492 -109.728125) (xy 451.412893 -109.720377) (xy 451.405498 -109.713522) (xy 450.596254 -108.904278)
			(xy 450.589405 -108.896885) (xy 450.581692 -108.87828) (xy 450.581268 -108.86821) (xy 416.667696 -108.86821)
			(xy 416.667696 -109.813852) (xy 467.527638 -109.813852) (xy 467.531709 -109.75823) (xy 467.543835 -109.703793)
			(xy 467.563758 -109.651702) (xy 467.591054 -109.603067) (xy 467.62514 -109.558924) (xy 467.665289 -109.520215)
			(xy 467.710647 -109.487764) (xy 467.760247 -109.462263) (xy 467.813031 -109.444256) (xy 467.867874 -109.434126)
			(xy 467.923608 -109.432089) (xy 467.979045 -109.438189) (xy 468.033002 -109.452295) (xy 468.084331 -109.474107)
			(xy 468.131937 -109.503161) (xy 468.174805 -109.538836) (xy 468.212022 -109.580373) (xy 468.242795 -109.626886)
			(xy 468.266467 -109.677383) (xy 468.282535 -109.73079) (xy 468.290655 -109.785966) (xy 468.291164 -109.813852)
			(xy 468.290655 -109.841738) (xy 468.282535 -109.896914) (xy 468.266467 -109.950321) (xy 468.242795 -110.000818)
			(xy 468.212022 -110.047331) (xy 468.174805 -110.088868) (xy 468.131937 -110.124543) (xy 468.084331 -110.153597)
			(xy 468.033002 -110.175409) (xy 467.979045 -110.189515) (xy 467.923608 -110.195615) (xy 467.867874 -110.193578)
			(xy 467.813031 -110.183448) (xy 467.760247 -110.165441) (xy 467.710647 -110.13994) (xy 467.665289 -110.107489)
			(xy 467.62514 -110.06878) (xy 467.591054 -110.024637) (xy 467.563758 -109.976002) (xy 467.543835 -109.923911)
			(xy 467.531709 -109.869474) (xy 467.527638 -109.813852) (xy 416.667696 -109.813852) (xy 416.667696 -110.626652)
			(xy 470.067638 -110.626652) (xy 470.071709 -110.57103) (xy 470.083835 -110.516593) (xy 470.103758 -110.464502)
			(xy 470.131054 -110.415867) (xy 470.16514 -110.371724) (xy 470.205289 -110.333015) (xy 470.250647 -110.300564)
			(xy 470.300247 -110.275063) (xy 470.353031 -110.257056) (xy 470.407874 -110.246926) (xy 470.463608 -110.244889)
			(xy 470.519045 -110.250989) (xy 470.573002 -110.265095) (xy 470.624331 -110.286907) (xy 470.671937 -110.315961)
			(xy 470.714805 -110.351636) (xy 470.752022 -110.393173) (xy 470.782795 -110.439686) (xy 470.806467 -110.490183)
			(xy 470.822535 -110.54359) (xy 470.830655 -110.598766) (xy 470.831164 -110.626652) (xy 470.830655 -110.654538)
			(xy 470.822535 -110.709714) (xy 470.806467 -110.763121) (xy 470.782795 -110.813618) (xy 470.752022 -110.860131)
			(xy 470.714805 -110.901668) (xy 470.671937 -110.937343) (xy 470.624331 -110.966397) (xy 470.573002 -110.988209)
			(xy 470.519045 -111.002315) (xy 470.463608 -111.008415) (xy 470.407874 -111.006378) (xy 470.353031 -110.996248)
			(xy 470.300247 -110.978241) (xy 470.250647 -110.95274) (xy 470.205289 -110.920289) (xy 470.16514 -110.88158)
			(xy 470.131054 -110.837437) (xy 470.103758 -110.788802) (xy 470.083835 -110.736711) (xy 470.071709 -110.682274)
			(xy 470.067638 -110.626652) (xy 416.667696 -110.626652) (xy 416.667696 -147.867624) (xy 416.667268 -147.877692)
			(xy 416.659547 -147.89629) (xy 416.65271 -147.903692) (xy 414.731454 -149.824948) (xy 414.724055 -149.831793)
			(xy 414.705457 -149.839519) (xy 414.695386 -149.839934) (xy 403.189186 -149.839934) (xy 403.179118 -149.84036)
			(xy 403.16052 -149.848082) (xy 403.153118 -149.85492) (xy 402.543264 -150.464774) (xy 402.536422 -150.472174)
			(xy 402.528705 -150.490772) (xy 402.528278 -150.500842) (xy 402.528278 -169.1259) (xy 402.5287 -169.135971)
			(xy 402.536412 -169.154577) (xy 402.543264 -169.161968) (xy 402.912834 -169.531538) (xy 402.920231 -169.538386)
			(xy 402.93883 -169.546118) (xy 402.948902 -169.546524)
		)
		(stroke
			(width 0)
			(type solid)
		)
		(fill yes)
		(layer "In2.Cu")
		(net "GND")
	)
	(gr_poly
		(pts
			(xy 37.382958 -169.545) (xy 37.393023 -169.544566) (xy 37.411613 -169.536837) (xy 37.419026 -169.530014)
			(xy 37.62883 -169.32021) (xy 37.635686 -169.312815) (xy 37.643435 -169.294217) (xy 37.643816 -169.284142)
			(xy 37.643816 -151.221186) (xy 37.644242 -151.211117) (xy 37.651962 -151.192518) (xy 37.658802 -151.185118)
			(xy 38.197282 -150.646638) (xy 38.204683 -150.6398) (xy 38.223282 -150.63209) (xy 38.23335 -150.631652)
			(xy 47.243746 -150.631652) (xy 47.253811 -150.632085) (xy 47.272399 -150.639817) (xy 47.279814 -150.646638)
			(xy 47.729648 -151.096472) (xy 47.736489 -151.103872) (xy 47.744205 -151.122471) (xy 47.744634 -151.13254)
			(xy 47.744634 -159.684424) (xy 71.513942 -159.684424) (xy 71.513942 -159.575796) (xy 71.521871 -159.467458)
			(xy 71.537688 -159.359987) (xy 71.561307 -159.253958) (xy 71.592603 -159.149936) (xy 71.631408 -159.048475)
			(xy 71.677516 -158.950118) (xy 71.73068 -158.855389) (xy 71.790618 -158.764794) (xy 71.857008 -158.678815)
			(xy 71.929498 -158.597912) (xy 72.007699 -158.522516) (xy 72.091196 -158.45303) (xy 72.179542 -158.389823)
			(xy 72.272266 -158.333235) (xy 72.368874 -158.283565) (xy 72.468849 -158.24108) (xy 72.571659 -158.206007)
			(xy 72.676755 -158.178531) (xy 72.783576 -158.1588) (xy 72.891552 -158.146919) (xy 73.000108 -158.142952)
			(xy 73.108664 -158.146919) (xy 73.21664 -158.1588) (xy 73.323461 -158.178531) (xy 73.428557 -158.206007)
			(xy 73.531367 -158.24108) (xy 73.631342 -158.283565) (xy 73.72795 -158.333235) (xy 73.820674 -158.389823)
			(xy 73.90902 -158.45303) (xy 73.992517 -158.522516) (xy 74.070718 -158.597912) (xy 74.143208 -158.678815)
			(xy 74.209598 -158.764794) (xy 74.269536 -158.855389) (xy 74.3227 -158.950118) (xy 74.368808 -159.048475)
			(xy 74.407613 -159.149936) (xy 74.438909 -159.253958) (xy 74.462528 -159.359987) (xy 74.478345 -159.467458)
			(xy 74.486274 -159.575796) (xy 74.48677 -159.63011) (xy 74.486274 -159.684424) (xy 74.478345 -159.792762)
			(xy 74.462528 -159.900233) (xy 74.438909 -160.006262) (xy 74.407613 -160.110284) (xy 74.368808 -160.211745)
			(xy 74.3227 -160.310102) (xy 74.269536 -160.404831) (xy 74.209598 -160.495426) (xy 74.143208 -160.581405)
			(xy 74.070718 -160.662308) (xy 73.992517 -160.737704) (xy 73.90902 -160.80719) (xy 73.820674 -160.870397)
			(xy 73.72795 -160.926985) (xy 73.631342 -160.976655) (xy 73.531367 -161.01914) (xy 73.428557 -161.054213)
			(xy 73.323461 -161.081689) (xy 73.21664 -161.10142) (xy 73.108664 -161.113301) (xy 73.000108 -161.117268)
			(xy 72.891552 -161.113301) (xy 72.783576 -161.10142) (xy 72.676755 -161.081689) (xy 72.571659 -161.054213)
			(xy 72.468849 -161.01914) (xy 72.368874 -160.976655) (xy 72.272266 -160.926985) (xy 72.179542 -160.870397)
			(xy 72.091196 -160.80719) (xy 72.007699 -160.737704) (xy 71.929498 -160.662308) (xy 71.857008 -160.581405)
			(xy 71.790618 -160.495426) (xy 71.73068 -160.404831) (xy 71.677516 -160.310102) (xy 71.631408 -160.211745)
			(xy 71.592603 -160.110284) (xy 71.561307 -160.006262) (xy 71.537688 -159.900233) (xy 71.521871 -159.792762)
			(xy 71.513942 -159.684424) (xy 47.744634 -159.684424) (xy 47.744634 -161.007298) (xy 47.745057 -161.017368)
			(xy 47.752775 -161.03597) (xy 47.75962 -161.043366) (xy 48.372268 -161.656014) (xy 48.379666 -161.662859)
			(xy 48.398265 -161.670582) (xy 48.408336 -161.671) (xy 51.465226 -161.671) (xy 51.474385 -161.670566)
			(xy 51.491513 -161.66406) (xy 51.505291 -161.651983) (xy 51.50993 -161.644076) (xy 51.535978 -161.596174)
			(xy 51.594215 -161.503979) (xy 51.659163 -161.416382) (xy 51.730462 -161.333872) (xy 51.807713 -161.256906)
			(xy 51.890488 -161.185914) (xy 51.978324 -161.121291) (xy 52.070735 -161.063397) (xy 52.167204 -161.012553)
			(xy 52.267196 -160.969042) (xy 52.370153 -160.933108) (xy 52.475503 -160.90495) (xy 52.582658 -160.884724)
			(xy 52.691024 -160.872543) (xy 52.799996 -160.868475) (xy 52.908968 -160.872543) (xy 53.017334 -160.884724)
			(xy 53.124489 -160.90495) (xy 53.229839 -160.933108) (xy 53.332796 -160.969042) (xy 53.432788 -161.012553)
			(xy 53.529257 -161.063397) (xy 53.621668 -161.121291) (xy 53.709504 -161.185914) (xy 53.792279 -161.256906)
			(xy 53.86953 -161.333872) (xy 53.940829 -161.416382) (xy 54.005777 -161.503979) (xy 54.064014 -161.596174)
			(xy 54.090062 -161.644076) (xy 54.094693 -161.651998) (xy 54.108443 -161.664126) (xy 54.125598 -161.670598)
			(xy 54.134766 -161.671) (xy 77.57541 -161.671) (xy 77.585479 -161.670575) (xy 77.604081 -161.662858)
			(xy 77.611478 -161.656014) (xy 77.815948 -161.451544) (xy 77.822791 -161.444145) (xy 77.830514 -161.425546)
			(xy 77.830934 -161.415476) (xy 77.830934 -154.94889) (xy 77.830507 -154.938822) (xy 77.822783 -154.920226)
			(xy 77.815948 -154.912822) (xy 73.200514 -150.297388) (xy 73.193668 -150.289989) (xy 73.185936 -150.271391)
			(xy 73.185528 -150.26132) (xy 73.185528 -139.094718) (xy 73.185967 -139.084655) (xy 73.193705 -139.066075)
			(xy 73.200514 -139.05865) (xy 76.41717 -135.841994) (xy 76.424573 -135.835159) (xy 76.443171 -135.827451)
			(xy 76.453238 -135.827008) (xy 83.663282 -135.827008) (xy 83.673346 -135.82657) (xy 83.691929 -135.818836)
			(xy 83.69935 -135.812022) (xy 85.075014 -134.436358) (xy 85.081863 -134.428962) (xy 85.089596 -134.410362)
			(xy 85.09 -134.40029) (xy 85.09 -106.193082) (xy 85.090427 -106.183013) (xy 85.098146 -106.164414)
			(xy 85.104986 -106.157014) (xy 91.171014 -100.090986) (xy 91.178409 -100.084132) (xy 91.197008 -100.07639)
			(xy 91.207082 -100.076) (xy 109.872018 -100.076) (xy 109.882087 -100.075573) (xy 109.900686 -100.067854)
			(xy 109.908086 -100.061014) (xy 112.215422 -97.753678) (xy 112.222273 -97.746282) (xy 112.230012 -97.727683)
			(xy 112.230408 -97.71761) (xy 112.230408 -86.467696) (xy 112.230832 -86.457626) (xy 112.238548 -86.439024)
			(xy 112.245394 -86.431628) (xy 115.565936 -83.111086) (xy 115.573332 -83.104236) (xy 115.591931 -83.096501)
			(xy 115.602004 -83.0961) (xy 118.601236 -83.0961) (xy 118.957852 -82.739484) (xy 118.957852 -53.856128)
			(xy 111.90859 -53.856128) (xy 111.938854 -53.887357) (xy 111.993814 -53.954756) (xy 112.041936 -54.027197)
			(xy 112.08276 -54.103988) (xy 112.115897 -54.184395) (xy 112.14103 -54.267652) (xy 112.15792 -54.352963)
			(xy 112.166405 -54.439516) (xy 112.166908 -54.483) (xy 112.166404 -54.525348) (xy 112.158353 -54.609662)
			(xy 112.142324 -54.692828) (xy 112.118463 -54.774095) (xy 112.086984 -54.852725) (xy 112.048173 -54.928006)
			(xy 112.002383 -54.999258) (xy 111.950027 -55.065834) (xy 111.891579 -55.127132) (xy 111.827569 -55.182597)
			(xy 111.758577 -55.231726) (xy 111.685227 -55.274075) (xy 111.608184 -55.309259) (xy 111.528145 -55.336961)
			(xy 111.445836 -55.356929) (xy 111.362001 -55.368982) (xy 111.2774 -55.373013) (xy 111.192799 -55.368982)
			(xy 111.108964 -55.356929) (xy 111.026655 -55.336961) (xy 110.946616 -55.309259) (xy 110.869573 -55.274075)
			(xy 110.796223 -55.231726) (xy 110.727231 -55.182597) (xy 110.663221 -55.127132) (xy 110.604773 -55.065834)
			(xy 110.552417 -54.999258) (xy 110.506627 -54.928006) (xy 110.467816 -54.852725) (xy 110.436337 -54.774095)
			(xy 110.412476 -54.692828) (xy 110.396447 -54.609662) (xy 110.388396 -54.525348) (xy 110.387892 -54.483)
			(xy 110.388418 -54.439517) (xy 110.396902 -54.352965) (xy 110.41379 -54.267655) (xy 110.438921 -54.184398)
			(xy 110.472054 -54.103991) (xy 110.512874 -54.0272) (xy 110.56099 -53.954757) (xy 110.615945 -53.887354)
			(xy 110.64621 -53.856128) (xy 110.2487 -53.856128) (xy 110.240714 -53.896455) (xy 110.218252 -53.975543)
			(xy 110.188585 -54.052219) (xy 110.151966 -54.12583) (xy 110.108708 -54.195745) (xy 110.059181 -54.261368)
			(xy 110.003807 -54.32214) (xy 109.943059 -54.377539) (xy 109.877457 -54.427095) (xy 109.80756 -54.470382)
			(xy 109.733965 -54.507032) (xy 109.657301 -54.536732) (xy 109.578223 -54.559228) (xy 109.497406 -54.574327)
			(xy 109.41554 -54.581901) (xy 109.374432 -54.582314) (xy 109.333328 -54.581855) (xy 109.25147 -54.574273)
			(xy 109.170661 -54.55917) (xy 109.09159 -54.536675) (xy 109.014932 -54.50698) (xy 108.941341 -54.470338)
			(xy 108.871445 -54.427063) (xy 108.80584 -54.377523) (xy 108.745086 -54.322141) (xy 108.689701 -54.261389)
			(xy 108.640158 -54.195787) (xy 108.59688 -54.125892) (xy 108.560235 -54.052303) (xy 108.530537 -53.975646)
			(xy 108.508039 -53.896576) (xy 108.492932 -53.815768) (xy 108.485346 -53.73391) (xy 108.484924 -53.692806)
			(xy 108.485446 -53.64941) (xy 108.493898 -53.56303) (xy 108.510723 -53.477884) (xy 108.53576 -53.394781)
			(xy 108.568771 -53.314512) (xy 108.609443 -53.23784) (xy 108.65739 -53.165493) (xy 108.712154 -53.098159)
			(xy 108.773215 -53.036479) (xy 108.839993 -52.98104) (xy 108.911853 -52.932367) (xy 108.988112 -52.890924)
			(xy 109.068045 -52.857105) (xy 109.150891 -52.831232) (xy 109.235863 -52.81355) (xy 109.322153 -52.804228)
			(xy 109.365542 -52.803298) (xy 109.58322 -52.58562) (xy 118.957852 -52.58562) (xy 118.957852 -42.517822)
			(xy 111.871252 -42.517822) (xy 111.901839 -42.545883) (xy 111.958219 -42.60681) (xy 112.008675 -42.672727)
			(xy 112.052767 -42.743061) (xy 112.090111 -42.817198) (xy 112.120382 -42.894493) (xy 112.143317 -42.974273)
			(xy 112.158716 -43.055843) (xy 112.166444 -43.138494) (xy 112.166908 -43.18) (xy 112.166404 -43.222348)
			(xy 112.158353 -43.306662) (xy 112.142324 -43.389828) (xy 112.118463 -43.471095) (xy 112.086984 -43.549725)
			(xy 112.048173 -43.625006) (xy 112.002383 -43.696258) (xy 111.950027 -43.762834) (xy 111.891579 -43.824132)
			(xy 111.827569 -43.879597) (xy 111.758577 -43.928726) (xy 111.685227 -43.971075) (xy 111.608184 -44.006259)
			(xy 111.528145 -44.033961) (xy 111.445836 -44.053929) (xy 111.362001 -44.065982) (xy 111.2774 -44.070013)
			(xy 111.192799 -44.065982) (xy 111.108964 -44.053929) (xy 111.026655 -44.033961) (xy 110.946616 -44.006259)
			(xy 110.869573 -43.971075) (xy 110.796223 -43.928726) (xy 110.727231 -43.879597) (xy 110.663221 -43.824132)
			(xy 110.604773 -43.762834) (xy 110.552417 -43.696258) (xy 110.506627 -43.625006) (xy 110.467816 -43.549725)
			(xy 110.436337 -43.471095) (xy 110.412476 -43.389828) (xy 110.396447 -43.306662) (xy 110.388396 -43.222348)
			(xy 110.387892 -43.18) (xy 110.388371 -43.138495) (xy 110.396105 -43.055845) (xy 110.411506 -42.974275)
			(xy 110.434439 -42.894495) (xy 110.464706 -42.817199) (xy 110.502043 -42.743059) (xy 110.546126 -42.67272)
			(xy 110.59657 -42.606794) (xy 110.652936 -42.545854) (xy 110.683548 -42.517822) (xy 109.667802 -42.517822)
			(xy 109.663393 -42.558581) (xy 109.648032 -42.639119) (xy 109.625323 -42.7179) (xy 109.595461 -42.794258)
			(xy 109.558697 -42.867543) (xy 109.515345 -42.937133) (xy 109.465772 -43.002438) (xy 109.4104 -43.062904)
			(xy 109.349697 -43.118016) (xy 109.284179 -43.167308) (xy 109.214403 -43.210361) (xy 109.140961 -43.246809)
			(xy 109.064476 -43.276343) (xy 108.985598 -43.298712) (xy 108.904995 -43.313727) (xy 108.823353 -43.32126)
			(xy 108.782358 -43.321732) (xy 108.741256 -43.321255) (xy 108.659404 -43.313667) (xy 108.578601 -43.298559)
			(xy 108.499536 -43.276061) (xy 108.422885 -43.246363) (xy 108.349301 -43.20972) (xy 108.279411 -43.166444)
			(xy 108.213812 -43.116904) (xy 108.153064 -43.061524) (xy 108.097684 -43.000774) (xy 108.048146 -42.935174)
			(xy 108.004871 -42.865284) (xy 107.96823 -42.791698) (xy 107.938534 -42.715046) (xy 107.916037 -42.635982)
			(xy 107.90093 -42.555178) (xy 107.893344 -42.473326) (xy 107.89285 -42.432224) (xy 107.893376 -42.388831)
			(xy 107.901835 -42.302458) (xy 107.918666 -42.217319) (xy 107.943708 -42.134224) (xy 107.976723 -42.053963)
			(xy 108.017398 -41.977299) (xy 108.065346 -41.90496) (xy 108.12011 -41.837635) (xy 108.181171 -41.775963)
			(xy 108.247948 -41.720531) (xy 108.319806 -41.671865) (xy 108.396062 -41.630429) (xy 108.47599 -41.596616)
			(xy 108.558832 -41.570748) (xy 108.643798 -41.553071) (xy 108.730083 -41.543752) (xy 108.773468 -41.542716)
			(xy 109.06887 -41.247314) (xy 118.957852 -41.247314) (xy 118.957852 -13.585444) (xy 118.682516 -13.310108)
			(xy 101.446584 -13.310108) (xy 92.438544 -22.318148) (xy 111.363248 -22.318148) (xy 111.363248 -22.233452)
			(xy 111.371299 -22.149138) (xy 111.387328 -22.065972) (xy 111.411189 -21.984705) (xy 111.442668 -21.906075)
			(xy 111.481479 -21.830794) (xy 111.527269 -21.759542) (xy 111.579625 -21.692966) (xy 111.638073 -21.631668)
			(xy 111.702083 -21.576203) (xy 111.771075 -21.527074) (xy 111.844425 -21.484725) (xy 111.921468 -21.449541)
			(xy 112.001507 -21.421839) (xy 112.083816 -21.401871) (xy 112.167651 -21.389818) (xy 112.252252 -21.385788)
			(xy 112.336853 -21.389818) (xy 112.420688 -21.401871) (xy 112.502997 -21.421839) (xy 112.583036 -21.449541)
			(xy 112.660079 -21.484725) (xy 112.733429 -21.527074) (xy 112.802421 -21.576203) (xy 112.866431 -21.631668)
			(xy 112.924879 -21.692966) (xy 112.977235 -21.759542) (xy 113.023025 -21.830794) (xy 113.061836 -21.906075)
			(xy 113.093315 -21.984705) (xy 113.117176 -22.065972) (xy 113.133205 -22.149138) (xy 113.141256 -22.233452)
			(xy 113.14176 -22.2758) (xy 113.141256 -22.318148) (xy 113.133205 -22.402462) (xy 113.117176 -22.485628)
			(xy 113.093315 -22.566895) (xy 113.061836 -22.645525) (xy 113.023025 -22.720806) (xy 112.977235 -22.792058)
			(xy 112.924879 -22.858634) (xy 112.866431 -22.919932) (xy 112.802421 -22.975397) (xy 112.733429 -23.024526)
			(xy 112.660079 -23.066875) (xy 112.583036 -23.102059) (xy 112.502997 -23.129761) (xy 112.420688 -23.149729)
			(xy 112.336853 -23.161782) (xy 112.252252 -23.165813) (xy 112.167651 -23.161782) (xy 112.083816 -23.149729)
			(xy 112.001507 -23.129761) (xy 111.921468 -23.102059) (xy 111.844425 -23.066875) (xy 111.771075 -23.024526)
			(xy 111.702083 -22.975397) (xy 111.638073 -22.919932) (xy 111.579625 -22.858634) (xy 111.527269 -22.792058)
			(xy 111.481479 -22.720806) (xy 111.442668 -22.645525) (xy 111.411189 -22.566895) (xy 111.387328 -22.485628)
			(xy 111.371299 -22.402462) (xy 111.363248 -22.318148) (xy 92.438544 -22.318148) (xy 90.508074 -24.248618)
			(xy 90.500678 -24.255469) (xy 90.482079 -24.263207) (xy 90.472006 -24.263604) (xy 81.92008 -24.263604)
			(xy 81.910012 -24.264031) (xy 81.891413 -24.271751) (xy 81.884012 -24.27859) (xy 72.566854 -33.595748)
			(xy 111.363248 -33.595748) (xy 111.363248 -33.511052) (xy 111.371299 -33.426738) (xy 111.387328 -33.343572)
			(xy 111.411189 -33.262305) (xy 111.442668 -33.183675) (xy 111.481479 -33.108394) (xy 111.527269 -33.037142)
			(xy 111.579625 -32.970566) (xy 111.638073 -32.909268) (xy 111.702083 -32.853803) (xy 111.771075 -32.804674)
			(xy 111.844425 -32.762325) (xy 111.921468 -32.727141) (xy 112.001507 -32.699439) (xy 112.083816 -32.679471)
			(xy 112.167651 -32.667418) (xy 112.252252 -32.663388) (xy 112.336853 -32.667418) (xy 112.420688 -32.679471)
			(xy 112.502997 -32.699439) (xy 112.583036 -32.727141) (xy 112.660079 -32.762325) (xy 112.733429 -32.804674)
			(xy 112.802421 -32.853803) (xy 112.866431 -32.909268) (xy 112.924879 -32.970566) (xy 112.977235 -33.037142)
			(xy 113.023025 -33.108394) (xy 113.061836 -33.183675) (xy 113.093315 -33.262305) (xy 113.117176 -33.343572)
			(xy 113.133205 -33.426738) (xy 113.141256 -33.511052) (xy 113.14176 -33.5534) (xy 113.141256 -33.595748)
			(xy 113.133205 -33.680062) (xy 113.117176 -33.763228) (xy 113.093315 -33.844495) (xy 113.061836 -33.923125)
			(xy 113.023025 -33.998406) (xy 112.977235 -34.069658) (xy 112.924879 -34.136234) (xy 112.866431 -34.197532)
			(xy 112.802421 -34.252997) (xy 112.733429 -34.302126) (xy 112.660079 -34.344475) (xy 112.583036 -34.379659)
			(xy 112.502997 -34.407361) (xy 112.420688 -34.427329) (xy 112.336853 -34.439382) (xy 112.252252 -34.443413)
			(xy 112.167651 -34.439382) (xy 112.083816 -34.427329) (xy 112.001507 -34.407361) (xy 111.921468 -34.379659)
			(xy 111.844425 -34.344475) (xy 111.771075 -34.302126) (xy 111.702083 -34.252997) (xy 111.638073 -34.197532)
			(xy 111.579625 -34.136234) (xy 111.527269 -34.069658) (xy 111.481479 -33.998406) (xy 111.442668 -33.923125)
			(xy 111.411189 -33.844495) (xy 111.387328 -33.763228) (xy 111.371299 -33.680062) (xy 111.363248 -33.595748)
			(xy 72.566854 -33.595748) (xy 72.126602 -34.036) (xy 40.280082 -34.036) (xy 34.057082 -40.259) (xy 34.050227 -40.266395)
			(xy 34.042479 -40.284994) (xy 34.042096 -40.295068) (xy 34.042096 -45.787748) (xy 102.768396 -45.787748)
			(xy 102.768396 -45.703052) (xy 102.776447 -45.618738) (xy 102.792476 -45.535572) (xy 102.816337 -45.454305)
			(xy 102.847816 -45.375675) (xy 102.886627 -45.300394) (xy 102.932417 -45.229142) (xy 102.984773 -45.162566)
			(xy 103.043221 -45.101268) (xy 103.107231 -45.045803) (xy 103.176223 -44.996674) (xy 103.249573 -44.954325)
			(xy 103.326616 -44.919141) (xy 103.406655 -44.891439) (xy 103.488964 -44.871471) (xy 103.572799 -44.859418)
			(xy 103.6574 -44.855388) (xy 103.742001 -44.859418) (xy 103.825836 -44.871471) (xy 103.833573 -44.873348)
			(xy 111.363248 -44.873348) (xy 111.363248 -44.788652) (xy 111.371299 -44.704338) (xy 111.387328 -44.621172)
			(xy 111.411189 -44.539905) (xy 111.442668 -44.461275) (xy 111.481479 -44.385994) (xy 111.527269 -44.314742)
			(xy 111.579625 -44.248166) (xy 111.638073 -44.186868) (xy 111.702083 -44.131403) (xy 111.771075 -44.082274)
			(xy 111.844425 -44.039925) (xy 111.921468 -44.004741) (xy 112.001507 -43.977039) (xy 112.083816 -43.957071)
			(xy 112.167651 -43.945018) (xy 112.252252 -43.940988) (xy 112.336853 -43.945018) (xy 112.420688 -43.957071)
			(xy 112.502997 -43.977039) (xy 112.583036 -44.004741) (xy 112.660079 -44.039925) (xy 112.733429 -44.082274)
			(xy 112.802421 -44.131403) (xy 112.866431 -44.186868) (xy 112.924879 -44.248166) (xy 112.977235 -44.314742)
			(xy 113.023025 -44.385994) (xy 113.061836 -44.461275) (xy 113.093315 -44.539905) (xy 113.117176 -44.621172)
			(xy 113.133205 -44.704338) (xy 113.141256 -44.788652) (xy 113.14176 -44.831) (xy 113.141256 -44.873348)
			(xy 113.133205 -44.957662) (xy 113.117176 -45.040828) (xy 113.093315 -45.122095) (xy 113.061836 -45.200725)
			(xy 113.023025 -45.276006) (xy 112.977235 -45.347258) (xy 112.924879 -45.413834) (xy 112.866431 -45.475132)
			(xy 112.802421 -45.530597) (xy 112.733429 -45.579726) (xy 112.660079 -45.622075) (xy 112.583036 -45.657259)
			(xy 112.502997 -45.684961) (xy 112.420688 -45.704929) (xy 112.336853 -45.716982) (xy 112.252252 -45.721013)
			(xy 112.167651 -45.716982) (xy 112.083816 -45.704929) (xy 112.001507 -45.684961) (xy 111.921468 -45.657259)
			(xy 111.844425 -45.622075) (xy 111.771075 -45.579726) (xy 111.702083 -45.530597) (xy 111.638073 -45.475132)
			(xy 111.579625 -45.413834) (xy 111.527269 -45.347258) (xy 111.481479 -45.276006) (xy 111.442668 -45.200725)
			(xy 111.411189 -45.122095) (xy 111.387328 -45.040828) (xy 111.371299 -44.957662) (xy 111.363248 -44.873348)
			(xy 103.833573 -44.873348) (xy 103.908145 -44.891439) (xy 103.988184 -44.919141) (xy 104.065227 -44.954325)
			(xy 104.138577 -44.996674) (xy 104.207569 -45.045803) (xy 104.271579 -45.101268) (xy 104.330027 -45.162566)
			(xy 104.382383 -45.229142) (xy 104.428173 -45.300394) (xy 104.466984 -45.375675) (xy 104.498463 -45.454305)
			(xy 104.522324 -45.535572) (xy 104.538353 -45.618738) (xy 104.546404 -45.703052) (xy 104.546908 -45.7454)
			(xy 104.546404 -45.787748) (xy 104.538353 -45.872062) (xy 104.522324 -45.955228) (xy 104.498463 -46.036495)
			(xy 104.466984 -46.115125) (xy 104.428173 -46.190406) (xy 104.382383 -46.261658) (xy 104.330027 -46.328234)
			(xy 104.271579 -46.389532) (xy 104.207569 -46.444997) (xy 104.138577 -46.494126) (xy 104.065227 -46.536475)
			(xy 103.988184 -46.571659) (xy 103.908145 -46.599361) (xy 103.825836 -46.619329) (xy 103.742001 -46.631382)
			(xy 103.6574 -46.635413) (xy 103.572799 -46.631382) (xy 103.488964 -46.619329) (xy 103.406655 -46.599361)
			(xy 103.326616 -46.571659) (xy 103.249573 -46.536475) (xy 103.176223 -46.494126) (xy 103.107231 -46.444997)
			(xy 103.043221 -46.389532) (xy 102.984773 -46.328234) (xy 102.932417 -46.261658) (xy 102.886627 -46.190406)
			(xy 102.847816 -46.115125) (xy 102.816337 -46.036495) (xy 102.792476 -45.955228) (xy 102.776447 -45.872062)
			(xy 102.768396 -45.787748) (xy 34.042096 -45.787748) (xy 34.042096 -50.919888) (xy 40.838385 -50.919888)
			(xy 40.84236 -50.809847) (xy 40.854266 -50.70038) (xy 40.874039 -50.592057) (xy 40.901577 -50.485443)
			(xy 40.936736 -50.381095) (xy 40.979333 -50.279555) (xy 41.029146 -50.181354) (xy 41.085915 -50.087003)
			(xy 41.149344 -49.996994) (xy 41.219103 -49.911797) (xy 41.294827 -49.831856) (xy 41.376123 -49.757587)
			(xy 41.462565 -49.689378) (xy 41.553704 -49.627584) (xy 41.649065 -49.572528) (xy 41.748149 -49.524496)
			(xy 41.850442 -49.483739) (xy 41.955408 -49.450469) (xy 42.062501 -49.424861) (xy 42.171164 -49.407047)
			(xy 42.280828 -49.39712) (xy 42.390923 -49.395132) (xy 42.500874 -49.401093) (xy 42.610108 -49.414973)
			(xy 42.718057 -49.436698) (xy 42.824156 -49.466157) (xy 42.927853 -49.503194) (xy 43.028607 -49.547617)
			(xy 43.125893 -49.599195) (xy 43.219203 -49.657658) (xy 43.308052 -49.722702) (xy 43.391976 -49.793987)
			(xy 43.470537 -49.871143) (xy 43.543326 -49.953766) (xy 43.609963 -50.041426) (xy 43.670101 -50.133666)
			(xy 43.723427 -50.230005) (xy 43.769662 -50.32994) (xy 43.808566 -50.432952) (xy 43.839935 -50.538502)
			(xy 43.863606 -50.64604) (xy 43.879455 -50.755006) (xy 43.887401 -50.864832) (xy 43.887898 -50.919888)
			(xy 60.396385 -50.919888) (xy 60.40036 -50.809847) (xy 60.412266 -50.70038) (xy 60.432039 -50.592057)
			(xy 60.459577 -50.485443) (xy 60.494736 -50.381095) (xy 60.537333 -50.279555) (xy 60.587146 -50.181354)
			(xy 60.643915 -50.087003) (xy 60.707344 -49.996994) (xy 60.777103 -49.911797) (xy 60.852827 -49.831856)
			(xy 60.934123 -49.757587) (xy 61.020565 -49.689378) (xy 61.111704 -49.627584) (xy 61.207065 -49.572528)
			(xy 61.306149 -49.524496) (xy 61.408442 -49.483739) (xy 61.513408 -49.450469) (xy 61.620501 -49.424861)
			(xy 61.729164 -49.407047) (xy 61.838828 -49.39712) (xy 61.948923 -49.395132) (xy 62.058874 -49.401093)
			(xy 62.168108 -49.414973) (xy 62.276057 -49.436698) (xy 62.382156 -49.466157) (xy 62.485853 -49.503194)
			(xy 62.586607 -49.547617) (xy 62.683893 -49.599195) (xy 62.777203 -49.657658) (xy 62.866052 -49.722702)
			(xy 62.949976 -49.793987) (xy 63.028537 -49.871143) (xy 63.101326 -49.953766) (xy 63.167963 -50.041426)
			(xy 63.228101 -50.133666) (xy 63.281427 -50.230005) (xy 63.327662 -50.32994) (xy 63.366566 -50.432952)
			(xy 63.397935 -50.538502) (xy 63.421606 -50.64604) (xy 63.437455 -50.755006) (xy 63.445401 -50.864832)
			(xy 63.445898 -50.919888) (xy 63.445401 -50.974944) (xy 63.437455 -51.08477) (xy 63.421606 -51.193736)
			(xy 63.397935 -51.301274) (xy 63.366566 -51.406824) (xy 63.327662 -51.509836) (xy 63.281427 -51.609771)
			(xy 63.228101 -51.70611) (xy 63.167963 -51.79835) (xy 63.101326 -51.88601) (xy 63.028537 -51.968633)
			(xy 62.949976 -52.045789) (xy 62.866052 -52.117074) (xy 62.777203 -52.182118) (xy 62.683893 -52.240581)
			(xy 62.586607 -52.292159) (xy 62.485853 -52.336582) (xy 62.382156 -52.373619) (xy 62.276057 -52.403078)
			(xy 62.168108 -52.424803) (xy 62.058874 -52.438683) (xy 61.948923 -52.444644) (xy 61.838828 -52.442656)
			(xy 61.729164 -52.432729) (xy 61.620501 -52.414915) (xy 61.513408 -52.389307) (xy 61.408442 -52.356037)
			(xy 61.306149 -52.31528) (xy 61.207065 -52.267248) (xy 61.111704 -52.212192) (xy 61.020565 -52.150398)
			(xy 60.934123 -52.082189) (xy 60.852827 -52.00792) (xy 60.777103 -51.927979) (xy 60.707344 -51.842782)
			(xy 60.643915 -51.752773) (xy 60.587146 -51.658422) (xy 60.537333 -51.560221) (xy 60.494736 -51.458681)
			(xy 60.459577 -51.354333) (xy 60.432039 -51.247719) (xy 60.412266 -51.139396) (xy 60.40036 -51.029929)
			(xy 60.396385 -50.919888) (xy 43.887898 -50.919888) (xy 43.887401 -50.974944) (xy 43.879455 -51.08477)
			(xy 43.863606 -51.193736) (xy 43.839935 -51.301274) (xy 43.808566 -51.406824) (xy 43.769662 -51.509836)
			(xy 43.723427 -51.609771) (xy 43.670101 -51.70611) (xy 43.609963 -51.79835) (xy 43.543326 -51.88601)
			(xy 43.470537 -51.968633) (xy 43.391976 -52.045789) (xy 43.308052 -52.117074) (xy 43.219203 -52.182118)
			(xy 43.125893 -52.240581) (xy 43.028607 -52.292159) (xy 42.927853 -52.336582) (xy 42.824156 -52.373619)
			(xy 42.718057 -52.403078) (xy 42.610108 -52.424803) (xy 42.500874 -52.438683) (xy 42.390923 -52.444644)
			(xy 42.280828 -52.442656) (xy 42.171164 -52.432729) (xy 42.062501 -52.414915) (xy 41.955408 -52.389307)
			(xy 41.850442 -52.356037) (xy 41.748149 -52.31528) (xy 41.649065 -52.267248) (xy 41.553704 -52.212192)
			(xy 41.462565 -52.150398) (xy 41.376123 -52.082189) (xy 41.294827 -52.00792) (xy 41.219103 -51.927979)
			(xy 41.149344 -51.842782) (xy 41.085915 -51.752773) (xy 41.029146 -51.658422) (xy 40.979333 -51.560221)
			(xy 40.936736 -51.458681) (xy 40.901577 -51.354333) (xy 40.874039 -51.247719) (xy 40.854266 -51.139396)
			(xy 40.84236 -51.029929) (xy 40.838385 -50.919888) (xy 34.042096 -50.919888) (xy 34.042096 -57.065348)
			(xy 102.768396 -57.065348) (xy 102.768396 -56.980652) (xy 102.776447 -56.896338) (xy 102.792476 -56.813172)
			(xy 102.816337 -56.731905) (xy 102.847816 -56.653275) (xy 102.886627 -56.577994) (xy 102.932417 -56.506742)
			(xy 102.984773 -56.440166) (xy 103.043221 -56.378868) (xy 103.107231 -56.323403) (xy 103.176223 -56.274274)
			(xy 103.249573 -56.231925) (xy 103.326616 -56.196741) (xy 103.406655 -56.169039) (xy 103.488964 -56.149071)
			(xy 103.572799 -56.137018) (xy 103.6574 -56.132988) (xy 103.742001 -56.137018) (xy 103.825836 -56.149071)
			(xy 103.833573 -56.150948) (xy 111.363248 -56.150948) (xy 111.363248 -56.066252) (xy 111.371299 -55.981938)
			(xy 111.387328 -55.898772) (xy 111.411189 -55.817505) (xy 111.442668 -55.738875) (xy 111.481479 -55.663594)
			(xy 111.527269 -55.592342) (xy 111.579625 -55.525766) (xy 111.638073 -55.464468) (xy 111.702083 -55.409003)
			(xy 111.771075 -55.359874) (xy 111.844425 -55.317525) (xy 111.921468 -55.282341) (xy 112.001507 -55.254639)
			(xy 112.083816 -55.234671) (xy 112.167651 -55.222618) (xy 112.252252 -55.218588) (xy 112.336853 -55.222618)
			(xy 112.420688 -55.234671) (xy 112.502997 -55.254639) (xy 112.583036 -55.282341) (xy 112.660079 -55.317525)
			(xy 112.733429 -55.359874) (xy 112.802421 -55.409003) (xy 112.866431 -55.464468) (xy 112.924879 -55.525766)
			(xy 112.977235 -55.592342) (xy 113.023025 -55.663594) (xy 113.061836 -55.738875) (xy 113.093315 -55.817505)
			(xy 113.117176 -55.898772) (xy 113.133205 -55.981938) (xy 113.141256 -56.066252) (xy 113.14176 -56.1086)
			(xy 113.141256 -56.150948) (xy 113.133205 -56.235262) (xy 113.117176 -56.318428) (xy 113.093315 -56.399695)
			(xy 113.061836 -56.478325) (xy 113.023025 -56.553606) (xy 112.977235 -56.624858) (xy 112.924879 -56.691434)
			(xy 112.866431 -56.752732) (xy 112.802421 -56.808197) (xy 112.733429 -56.857326) (xy 112.660079 -56.899675)
			(xy 112.583036 -56.934859) (xy 112.502997 -56.962561) (xy 112.420688 -56.982529) (xy 112.336853 -56.994582)
			(xy 112.252252 -56.998613) (xy 112.167651 -56.994582) (xy 112.083816 -56.982529) (xy 112.001507 -56.962561)
			(xy 111.921468 -56.934859) (xy 111.844425 -56.899675) (xy 111.771075 -56.857326) (xy 111.702083 -56.808197)
			(xy 111.638073 -56.752732) (xy 111.579625 -56.691434) (xy 111.527269 -56.624858) (xy 111.481479 -56.553606)
			(xy 111.442668 -56.478325) (xy 111.411189 -56.399695) (xy 111.387328 -56.318428) (xy 111.371299 -56.235262)
			(xy 111.363248 -56.150948) (xy 103.833573 -56.150948) (xy 103.908145 -56.169039) (xy 103.988184 -56.196741)
			(xy 104.065227 -56.231925) (xy 104.138577 -56.274274) (xy 104.207569 -56.323403) (xy 104.271579 -56.378868)
			(xy 104.330027 -56.440166) (xy 104.382383 -56.506742) (xy 104.428173 -56.577994) (xy 104.466984 -56.653275)
			(xy 104.498463 -56.731905) (xy 104.522324 -56.813172) (xy 104.538353 -56.896338) (xy 104.546404 -56.980652)
			(xy 104.546908 -57.023) (xy 104.546404 -57.065348) (xy 104.538353 -57.149662) (xy 104.522324 -57.232828)
			(xy 104.498463 -57.314095) (xy 104.466984 -57.392725) (xy 104.428173 -57.468006) (xy 104.382383 -57.539258)
			(xy 104.330027 -57.605834) (xy 104.271579 -57.667132) (xy 104.207569 -57.722597) (xy 104.138577 -57.771726)
			(xy 104.065227 -57.814075) (xy 103.988184 -57.849259) (xy 103.908145 -57.876961) (xy 103.825836 -57.896929)
			(xy 103.742001 -57.908982) (xy 103.6574 -57.913013) (xy 103.572799 -57.908982) (xy 103.488964 -57.896929)
			(xy 103.406655 -57.876961) (xy 103.326616 -57.849259) (xy 103.249573 -57.814075) (xy 103.176223 -57.771726)
			(xy 103.107231 -57.722597) (xy 103.043221 -57.667132) (xy 102.984773 -57.605834) (xy 102.932417 -57.539258)
			(xy 102.886627 -57.468006) (xy 102.847816 -57.392725) (xy 102.816337 -57.314095) (xy 102.792476 -57.232828)
			(xy 102.776447 -57.149662) (xy 102.768396 -57.065348) (xy 34.042096 -57.065348) (xy 34.042096 -58.42)
			(xy 41.346384 -58.42) (xy 41.350364 -58.330117) (xy 41.362272 -58.240937) (xy 41.382015 -58.153159)
			(xy 41.409439 -58.067469) (xy 41.444328 -57.984538) (xy 41.486411 -57.905016) (xy 41.535357 -57.829523)
			(xy 41.590784 -57.758652) (xy 41.652257 -57.692957) (xy 41.719296 -57.632952) (xy 41.791376 -57.579107)
			(xy 41.867932 -57.531843) (xy 41.948367 -57.49153) (xy 42.032049 -57.458483) (xy 42.118324 -57.432962)
			(xy 42.206518 -57.415166) (xy 42.295939 -57.405233) (xy 42.385888 -57.403243) (xy 42.475661 -57.40921)
			(xy 42.564556 -57.423088) (xy 42.651876 -57.444768) (xy 42.736938 -57.474081) (xy 42.819077 -57.510797)
			(xy 42.897649 -57.554628) (xy 42.97204 -57.605232) (xy 43.041667 -57.662213) (xy 43.105986 -57.725125)
			(xy 43.164494 -57.793475) (xy 43.216731 -57.866728) (xy 43.26229 -57.944311) (xy 43.300814 -58.025618)
			(xy 43.332001 -58.110011) (xy 43.355608 -58.19683) (xy 43.371449 -58.285395) (xy 43.379401 -58.375014)
			(xy 43.379898 -58.42) (xy 60.904384 -58.42) (xy 60.908364 -58.330117) (xy 60.920272 -58.240937) (xy 60.940015 -58.153159)
			(xy 60.967439 -58.067469) (xy 61.002328 -57.984538) (xy 61.044411 -57.905016) (xy 61.093357 -57.829523)
			(xy 61.148784 -57.758652) (xy 61.210257 -57.692957) (xy 61.277296 -57.632952) (xy 61.349376 -57.579107)
			(xy 61.425932 -57.531843) (xy 61.506367 -57.49153) (xy 61.590049 -57.458483) (xy 61.676324 -57.432962)
			(xy 61.764518 -57.415166) (xy 61.853939 -57.405233) (xy 61.943888 -57.403243) (xy 62.033661 -57.40921)
			(xy 62.122556 -57.423088) (xy 62.209876 -57.444768) (xy 62.294938 -57.474081) (xy 62.377077 -57.510797)
			(xy 62.455649 -57.554628) (xy 62.53004 -57.605232) (xy 62.599667 -57.662213) (xy 62.663986 -57.725125)
			(xy 62.722494 -57.793475) (xy 62.774731 -57.866728) (xy 62.82029 -57.944311) (xy 62.858814 -58.025618)
			(xy 62.890001 -58.110011) (xy 62.913608 -58.19683) (xy 62.929449 -58.285395) (xy 62.937401 -58.375014)
			(xy 62.937898 -58.42) (xy 62.937401 -58.464986) (xy 62.929449 -58.554605) (xy 62.913608 -58.64317)
			(xy 62.890001 -58.729989) (xy 62.858814 -58.814382) (xy 62.82029 -58.895689) (xy 62.774731 -58.973272)
			(xy 62.722494 -59.046525) (xy 62.663986 -59.114875) (xy 62.599667 -59.177787) (xy 62.53004 -59.234768)
			(xy 62.455649 -59.285372) (xy 62.377077 -59.329203) (xy 62.294938 -59.365919) (xy 62.209876 -59.395232)
			(xy 62.122556 -59.416912) (xy 62.033661 -59.43079) (xy 61.943888 -59.436757) (xy 61.853939 -59.434767)
			(xy 61.764518 -59.424834) (xy 61.676324 -59.407038) (xy 61.590049 -59.381517) (xy 61.506367 -59.34847)
			(xy 61.425932 -59.308157) (xy 61.349376 -59.260893) (xy 61.277296 -59.207048) (xy 61.210257 -59.147043)
			(xy 61.148784 -59.081348) (xy 61.093357 -59.010477) (xy 61.044411 -58.934984) (xy 61.002328 -58.855462)
			(xy 60.967439 -58.772531) (xy 60.940015 -58.686841) (xy 60.920272 -58.599063) (xy 60.908364 -58.509883)
			(xy 60.904384 -58.42) (xy 43.379898 -58.42) (xy 43.379401 -58.464986) (xy 43.371449 -58.554605) (xy 43.355608 -58.64317)
			(xy 43.332001 -58.729989) (xy 43.300814 -58.814382) (xy 43.26229 -58.895689) (xy 43.216731 -58.973272)
			(xy 43.164494 -59.046525) (xy 43.105986 -59.114875) (xy 43.041667 -59.177787) (xy 42.97204 -59.234768)
			(xy 42.897649 -59.285372) (xy 42.819077 -59.329203) (xy 42.736938 -59.365919) (xy 42.651876 -59.395232)
			(xy 42.564556 -59.416912) (xy 42.475661 -59.43079) (xy 42.385888 -59.436757) (xy 42.295939 -59.434767)
			(xy 42.206518 -59.424834) (xy 42.118324 -59.407038) (xy 42.032049 -59.381517) (xy 41.948367 -59.34847)
			(xy 41.867932 -59.308157) (xy 41.791376 -59.260893) (xy 41.719296 -59.207048) (xy 41.652257 -59.147043)
			(xy 41.590784 -59.081348) (xy 41.535357 -59.010477) (xy 41.486411 -58.934984) (xy 41.444328 -58.855462)
			(xy 41.409439 -58.772531) (xy 41.382015 -58.686841) (xy 41.362272 -58.599063) (xy 41.350364 -58.509883)
			(xy 41.346384 -58.42) (xy 34.042096 -58.42) (xy 34.042096 -67.428548) (xy 111.363248 -67.428548)
			(xy 111.363248 -67.343852) (xy 111.371299 -67.259538) (xy 111.387328 -67.176372) (xy 111.411189 -67.095105)
			(xy 111.442668 -67.016475) (xy 111.481479 -66.941194) (xy 111.527269 -66.869942) (xy 111.579625 -66.803366)
			(xy 111.638073 -66.742068) (xy 111.702083 -66.686603) (xy 111.771075 -66.637474) (xy 111.844425 -66.595125)
			(xy 111.921468 -66.559941) (xy 112.001507 -66.532239) (xy 112.083816 -66.512271) (xy 112.167651 -66.500218)
			(xy 112.252252 -66.496188) (xy 112.336853 -66.500218) (xy 112.420688 -66.512271) (xy 112.502997 -66.532239)
			(xy 112.583036 -66.559941) (xy 112.660079 -66.595125) (xy 112.733429 -66.637474) (xy 112.802421 -66.686603)
			(xy 112.866431 -66.742068) (xy 112.924879 -66.803366) (xy 112.977235 -66.869942) (xy 113.023025 -66.941194)
			(xy 113.061836 -67.016475) (xy 113.093315 -67.095105) (xy 113.117176 -67.176372) (xy 113.133205 -67.259538)
			(xy 113.141256 -67.343852) (xy 113.14176 -67.3862) (xy 113.141256 -67.428548) (xy 113.133205 -67.512862)
			(xy 113.117176 -67.596028) (xy 113.093315 -67.677295) (xy 113.061836 -67.755925) (xy 113.023025 -67.831206)
			(xy 112.977235 -67.902458) (xy 112.924879 -67.969034) (xy 112.866431 -68.030332) (xy 112.802421 -68.085797)
			(xy 112.733429 -68.134926) (xy 112.660079 -68.177275) (xy 112.583036 -68.212459) (xy 112.502997 -68.240161)
			(xy 112.420688 -68.260129) (xy 112.336853 -68.272182) (xy 112.252252 -68.276213) (xy 112.167651 -68.272182)
			(xy 112.083816 -68.260129) (xy 112.001507 -68.240161) (xy 111.921468 -68.212459) (xy 111.844425 -68.177275)
			(xy 111.771075 -68.134926) (xy 111.702083 -68.085797) (xy 111.638073 -68.030332) (xy 111.579625 -67.969034)
			(xy 111.527269 -67.902458) (xy 111.481479 -67.831206) (xy 111.442668 -67.755925) (xy 111.411189 -67.677295)
			(xy 111.387328 -67.596028) (xy 111.371299 -67.512862) (xy 111.363248 -67.428548) (xy 34.042096 -67.428548)
			(xy 34.042096 -71.239888) (xy 40.838385 -71.239888) (xy 40.84236 -71.129847) (xy 40.854266 -71.02038)
			(xy 40.874039 -70.912057) (xy 40.901577 -70.805443) (xy 40.936736 -70.701095) (xy 40.979333 -70.599555)
			(xy 41.029146 -70.501354) (xy 41.085915 -70.407003) (xy 41.149344 -70.316994) (xy 41.219103 -70.231797)
			(xy 41.294827 -70.151856) (xy 41.376123 -70.077587) (xy 41.462565 -70.009378) (xy 41.553704 -69.947584)
			(xy 41.649065 -69.892528) (xy 41.748149 -69.844496) (xy 41.850442 -69.803739) (xy 41.955408 -69.770469)
			(xy 42.062501 -69.744861) (xy 42.171164 -69.727047) (xy 42.280828 -69.71712) (xy 42.390923 -69.715132)
			(xy 42.500874 -69.721093) (xy 42.610108 -69.734973) (xy 42.718057 -69.756698) (xy 42.824156 -69.786157)
			(xy 42.927853 -69.823194) (xy 43.028607 -69.867617) (xy 43.125893 -69.919195) (xy 43.219203 -69.977658)
			(xy 43.308052 -70.042702) (xy 43.391976 -70.113987) (xy 43.470537 -70.191143) (xy 43.543326 -70.273766)
			(xy 43.609963 -70.361426) (xy 43.670101 -70.453666) (xy 43.723427 -70.550005) (xy 43.769662 -70.64994)
			(xy 43.808566 -70.752952) (xy 43.839935 -70.858502) (xy 43.863606 -70.96604) (xy 43.879455 -71.075006)
			(xy 43.887401 -71.184832) (xy 43.887898 -71.239888) (xy 60.396385 -71.239888) (xy 60.40036 -71.129847)
			(xy 60.412266 -71.02038) (xy 60.432039 -70.912057) (xy 60.459577 -70.805443) (xy 60.494736 -70.701095)
			(xy 60.537333 -70.599555) (xy 60.587146 -70.501354) (xy 60.643915 -70.407003) (xy 60.707344 -70.316994)
			(xy 60.777103 -70.231797) (xy 60.852827 -70.151856) (xy 60.934123 -70.077587) (xy 61.020565 -70.009378)
			(xy 61.111704 -69.947584) (xy 61.207065 -69.892528) (xy 61.306149 -69.844496) (xy 61.408442 -69.803739)
			(xy 61.513408 -69.770469) (xy 61.620501 -69.744861) (xy 61.729164 -69.727047) (xy 61.838828 -69.71712)
			(xy 61.948923 -69.715132) (xy 62.058874 -69.721093) (xy 62.168108 -69.734973) (xy 62.276057 -69.756698)
			(xy 62.382156 -69.786157) (xy 62.485853 -69.823194) (xy 62.586607 -69.867617) (xy 62.683893 -69.919195)
			(xy 62.777203 -69.977658) (xy 62.866052 -70.042702) (xy 62.949976 -70.113987) (xy 63.028537 -70.191143)
			(xy 63.101326 -70.273766) (xy 63.167963 -70.361426) (xy 63.228101 -70.453666) (xy 63.281427 -70.550005)
			(xy 63.327662 -70.64994) (xy 63.366566 -70.752952) (xy 63.397935 -70.858502) (xy 63.421606 -70.96604)
			(xy 63.437455 -71.075006) (xy 63.445401 -71.184832) (xy 63.445898 -71.239888) (xy 63.445401 -71.294944)
			(xy 63.437455 -71.40477) (xy 63.421606 -71.513736) (xy 63.397935 -71.621274) (xy 63.366566 -71.726824)
			(xy 63.327662 -71.829836) (xy 63.281427 -71.929771) (xy 63.228101 -72.02611) (xy 63.167963 -72.11835)
			(xy 63.101326 -72.20601) (xy 63.028537 -72.288633) (xy 62.949976 -72.365789) (xy 62.866052 -72.437074)
			(xy 62.777203 -72.502118) (xy 62.683893 -72.560581) (xy 62.586607 -72.612159) (xy 62.485853 -72.656582)
			(xy 62.382156 -72.693619) (xy 62.276057 -72.723078) (xy 62.168108 -72.744803) (xy 62.058874 -72.758683)
			(xy 61.948923 -72.764644) (xy 61.838828 -72.762656) (xy 61.729164 -72.752729) (xy 61.620501 -72.734915)
			(xy 61.513408 -72.709307) (xy 61.408442 -72.676037) (xy 61.306149 -72.63528) (xy 61.207065 -72.587248)
			(xy 61.111704 -72.532192) (xy 61.020565 -72.470398) (xy 60.934123 -72.402189) (xy 60.852827 -72.32792)
			(xy 60.777103 -72.247979) (xy 60.707344 -72.162782) (xy 60.643915 -72.072773) (xy 60.587146 -71.978422)
			(xy 60.537333 -71.880221) (xy 60.494736 -71.778681) (xy 60.459577 -71.674333) (xy 60.432039 -71.567719)
			(xy 60.412266 -71.459396) (xy 60.40036 -71.349929) (xy 60.396385 -71.239888) (xy 43.887898 -71.239888)
			(xy 43.887401 -71.294944) (xy 43.879455 -71.40477) (xy 43.863606 -71.513736) (xy 43.839935 -71.621274)
			(xy 43.808566 -71.726824) (xy 43.769662 -71.829836) (xy 43.723427 -71.929771) (xy 43.670101 -72.02611)
			(xy 43.609963 -72.11835) (xy 43.543326 -72.20601) (xy 43.470537 -72.288633) (xy 43.391976 -72.365789)
			(xy 43.308052 -72.437074) (xy 43.219203 -72.502118) (xy 43.125893 -72.560581) (xy 43.028607 -72.612159)
			(xy 42.927853 -72.656582) (xy 42.824156 -72.693619) (xy 42.718057 -72.723078) (xy 42.610108 -72.744803)
			(xy 42.500874 -72.758683) (xy 42.390923 -72.764644) (xy 42.280828 -72.762656) (xy 42.171164 -72.752729)
			(xy 42.062501 -72.734915) (xy 41.955408 -72.709307) (xy 41.850442 -72.676037) (xy 41.748149 -72.63528)
			(xy 41.649065 -72.587248) (xy 41.553704 -72.532192) (xy 41.462565 -72.470398) (xy 41.376123 -72.402189)
			(xy 41.294827 -72.32792) (xy 41.219103 -72.247979) (xy 41.149344 -72.162782) (xy 41.085915 -72.072773)
			(xy 41.029146 -71.978422) (xy 40.979333 -71.880221) (xy 40.936736 -71.778681) (xy 40.901577 -71.674333)
			(xy 40.874039 -71.567719) (xy 40.854266 -71.459396) (xy 40.84236 -71.349929) (xy 40.838385 -71.239888)
			(xy 34.042096 -71.239888) (xy 34.042096 -78.74) (xy 41.346384 -78.74) (xy 41.350364 -78.650117) (xy 41.362272 -78.560937)
			(xy 41.382015 -78.473159) (xy 41.409439 -78.387469) (xy 41.444328 -78.304538) (xy 41.486411 -78.225016)
			(xy 41.535357 -78.149523) (xy 41.590784 -78.078652) (xy 41.652257 -78.012957) (xy 41.719296 -77.952952)
			(xy 41.791376 -77.899107) (xy 41.867932 -77.851843) (xy 41.948367 -77.81153) (xy 42.032049 -77.778483)
			(xy 42.118324 -77.752962) (xy 42.206518 -77.735166) (xy 42.295939 -77.725233) (xy 42.385888 -77.723243)
			(xy 42.475661 -77.72921) (xy 42.564556 -77.743088) (xy 42.651876 -77.764768) (xy 42.736938 -77.794081)
			(xy 42.819077 -77.830797) (xy 42.897649 -77.874628) (xy 42.97204 -77.925232) (xy 43.041667 -77.982213)
			(xy 43.105986 -78.045125) (xy 43.164494 -78.113475) (xy 43.216731 -78.186728) (xy 43.26229 -78.264311)
			(xy 43.300814 -78.345618) (xy 43.332001 -78.430011) (xy 43.355608 -78.51683) (xy 43.371449 -78.605395)
			(xy 43.379401 -78.695014) (xy 43.379898 -78.74) (xy 60.904384 -78.74) (xy 60.908364 -78.650117) (xy 60.920272 -78.560937)
			(xy 60.940015 -78.473159) (xy 60.967439 -78.387469) (xy 61.002328 -78.304538) (xy 61.044411 -78.225016)
			(xy 61.093357 -78.149523) (xy 61.148784 -78.078652) (xy 61.210257 -78.012957) (xy 61.277296 -77.952952)
			(xy 61.349376 -77.899107) (xy 61.425932 -77.851843) (xy 61.506367 -77.81153) (xy 61.590049 -77.778483)
			(xy 61.676324 -77.752962) (xy 61.764518 -77.735166) (xy 61.853939 -77.725233) (xy 61.943888 -77.723243)
			(xy 62.033661 -77.72921) (xy 62.122556 -77.743088) (xy 62.209876 -77.764768) (xy 62.294938 -77.794081)
			(xy 62.377077 -77.830797) (xy 62.455649 -77.874628) (xy 62.53004 -77.925232) (xy 62.599667 -77.982213)
			(xy 62.663986 -78.045125) (xy 62.722494 -78.113475) (xy 62.774731 -78.186728) (xy 62.82029 -78.264311)
			(xy 62.858814 -78.345618) (xy 62.890001 -78.430011) (xy 62.913608 -78.51683) (xy 62.929449 -78.605395)
			(xy 62.937401 -78.695014) (xy 62.937524 -78.706148) (xy 111.363248 -78.706148) (xy 111.363248 -78.621452)
			(xy 111.371299 -78.537138) (xy 111.387328 -78.453972) (xy 111.411189 -78.372705) (xy 111.442668 -78.294075)
			(xy 111.481479 -78.218794) (xy 111.527269 -78.147542) (xy 111.579625 -78.080966) (xy 111.638073 -78.019668)
			(xy 111.702083 -77.964203) (xy 111.771075 -77.915074) (xy 111.844425 -77.872725) (xy 111.921468 -77.837541)
			(xy 112.001507 -77.809839) (xy 112.083816 -77.789871) (xy 112.167651 -77.777818) (xy 112.252252 -77.773788)
			(xy 112.336853 -77.777818) (xy 112.420688 -77.789871) (xy 112.502997 -77.809839) (xy 112.583036 -77.837541)
			(xy 112.660079 -77.872725) (xy 112.733429 -77.915074) (xy 112.802421 -77.964203) (xy 112.866431 -78.019668)
			(xy 112.924879 -78.080966) (xy 112.977235 -78.147542) (xy 113.023025 -78.218794) (xy 113.061836 -78.294075)
			(xy 113.093315 -78.372705) (xy 113.117176 -78.453972) (xy 113.133205 -78.537138) (xy 113.141256 -78.621452)
			(xy 113.14176 -78.6638) (xy 113.141256 -78.706148) (xy 113.133205 -78.790462) (xy 113.117176 -78.873628)
			(xy 113.093315 -78.954895) (xy 113.061836 -79.033525) (xy 113.023025 -79.108806) (xy 112.977235 -79.180058)
			(xy 112.924879 -79.246634) (xy 112.866431 -79.307932) (xy 112.802421 -79.363397) (xy 112.733429 -79.412526)
			(xy 112.660079 -79.454875) (xy 112.583036 -79.490059) (xy 112.502997 -79.517761) (xy 112.420688 -79.537729)
			(xy 112.336853 -79.549782) (xy 112.252252 -79.553813) (xy 112.167651 -79.549782) (xy 112.083816 -79.537729)
			(xy 112.001507 -79.517761) (xy 111.921468 -79.490059) (xy 111.844425 -79.454875) (xy 111.771075 -79.412526)
			(xy 111.702083 -79.363397) (xy 111.638073 -79.307932) (xy 111.579625 -79.246634) (xy 111.527269 -79.180058)
			(xy 111.481479 -79.108806) (xy 111.442668 -79.033525) (xy 111.411189 -78.954895) (xy 111.387328 -78.873628)
			(xy 111.371299 -78.790462) (xy 111.363248 -78.706148) (xy 62.937524 -78.706148) (xy 62.937898 -78.74)
			(xy 62.937401 -78.784986) (xy 62.929449 -78.874605) (xy 62.913608 -78.96317) (xy 62.890001 -79.049989)
			(xy 62.858814 -79.134382) (xy 62.82029 -79.215689) (xy 62.774731 -79.293272) (xy 62.722494 -79.366525)
			(xy 62.663986 -79.434875) (xy 62.599667 -79.497787) (xy 62.53004 -79.554768) (xy 62.455649 -79.605372)
			(xy 62.377077 -79.649203) (xy 62.294938 -79.685919) (xy 62.209876 -79.715232) (xy 62.122556 -79.736912)
			(xy 62.033661 -79.75079) (xy 61.943888 -79.756757) (xy 61.853939 -79.754767) (xy 61.764518 -79.744834)
			(xy 61.676324 -79.727038) (xy 61.590049 -79.701517) (xy 61.506367 -79.66847) (xy 61.425932 -79.628157)
			(xy 61.349376 -79.580893) (xy 61.277296 -79.527048) (xy 61.210257 -79.467043) (xy 61.148784 -79.401348)
			(xy 61.093357 -79.330477) (xy 61.044411 -79.254984) (xy 61.002328 -79.175462) (xy 60.967439 -79.092531)
			(xy 60.940015 -79.006841) (xy 60.920272 -78.919063) (xy 60.908364 -78.829883) (xy 60.904384 -78.74)
			(xy 43.379898 -78.74) (xy 43.379401 -78.784986) (xy 43.371449 -78.874605) (xy 43.355608 -78.96317)
			(xy 43.332001 -79.049989) (xy 43.300814 -79.134382) (xy 43.26229 -79.215689) (xy 43.216731 -79.293272)
			(xy 43.164494 -79.366525) (xy 43.105986 -79.434875) (xy 43.041667 -79.497787) (xy 42.97204 -79.554768)
			(xy 42.897649 -79.605372) (xy 42.819077 -79.649203) (xy 42.736938 -79.685919) (xy 42.651876 -79.715232)
			(xy 42.564556 -79.736912) (xy 42.475661 -79.75079) (xy 42.385888 -79.756757) (xy 42.295939 -79.754767)
			(xy 42.206518 -79.744834) (xy 42.118324 -79.727038) (xy 42.032049 -79.701517) (xy 41.948367 -79.66847)
			(xy 41.867932 -79.628157) (xy 41.791376 -79.580893) (xy 41.719296 -79.527048) (xy 41.652257 -79.467043)
			(xy 41.590784 -79.401348) (xy 41.535357 -79.330477) (xy 41.486411 -79.254984) (xy 41.444328 -79.175462)
			(xy 41.409439 -79.092531) (xy 41.382015 -79.006841) (xy 41.362272 -78.919063) (xy 41.350364 -78.829883)
			(xy 41.346384 -78.74) (xy 34.042096 -78.74) (xy 34.042096 -91.559888) (xy 40.838385 -91.559888) (xy 40.84236 -91.449847)
			(xy 40.854266 -91.34038) (xy 40.874039 -91.232057) (xy 40.901577 -91.125443) (xy 40.936736 -91.021095)
			(xy 40.979333 -90.919555) (xy 41.029146 -90.821354) (xy 41.085915 -90.727003) (xy 41.149344 -90.636994)
			(xy 41.219103 -90.551797) (xy 41.294827 -90.471856) (xy 41.376123 -90.397587) (xy 41.462565 -90.329378)
			(xy 41.553704 -90.267584) (xy 41.649065 -90.212528) (xy 41.748149 -90.164496) (xy 41.850442 -90.123739)
			(xy 41.955408 -90.090469) (xy 42.062501 -90.064861) (xy 42.171164 -90.047047) (xy 42.280828 -90.03712)
			(xy 42.390923 -90.035132) (xy 42.500874 -90.041093) (xy 42.610108 -90.054973) (xy 42.718057 -90.076698)
			(xy 42.824156 -90.106157) (xy 42.927853 -90.143194) (xy 43.028607 -90.187617) (xy 43.125893 -90.239195)
			(xy 43.219203 -90.297658) (xy 43.308052 -90.362702) (xy 43.391976 -90.433987) (xy 43.470537 -90.511143)
			(xy 43.543326 -90.593766) (xy 43.609963 -90.681426) (xy 43.670101 -90.773666) (xy 43.723427 -90.870005)
			(xy 43.769662 -90.96994) (xy 43.808566 -91.072952) (xy 43.839935 -91.178502) (xy 43.863606 -91.28604)
			(xy 43.879455 -91.395006) (xy 43.887401 -91.504832) (xy 43.887898 -91.559888) (xy 60.396385 -91.559888)
			(xy 60.40036 -91.449847) (xy 60.412266 -91.34038) (xy 60.432039 -91.232057) (xy 60.459577 -91.125443)
			(xy 60.494736 -91.021095) (xy 60.537333 -90.919555) (xy 60.587146 -90.821354) (xy 60.643915 -90.727003)
			(xy 60.707344 -90.636994) (xy 60.777103 -90.551797) (xy 60.852827 -90.471856) (xy 60.934123 -90.397587)
			(xy 61.020565 -90.329378) (xy 61.111704 -90.267584) (xy 61.207065 -90.212528) (xy 61.306149 -90.164496)
			(xy 61.408442 -90.123739) (xy 61.513408 -90.090469) (xy 61.620501 -90.064861) (xy 61.729164 -90.047047)
			(xy 61.838828 -90.03712) (xy 61.948923 -90.035132) (xy 62.058874 -90.041093) (xy 62.168108 -90.054973)
			(xy 62.276057 -90.076698) (xy 62.382156 -90.106157) (xy 62.485853 -90.143194) (xy 62.586607 -90.187617)
			(xy 62.683893 -90.239195) (xy 62.777203 -90.297658) (xy 62.866052 -90.362702) (xy 62.949976 -90.433987)
			(xy 63.028537 -90.511143) (xy 63.101326 -90.593766) (xy 63.167963 -90.681426) (xy 63.228101 -90.773666)
			(xy 63.281427 -90.870005) (xy 63.327662 -90.96994) (xy 63.366566 -91.072952) (xy 63.397935 -91.178502)
			(xy 63.421606 -91.28604) (xy 63.437455 -91.395006) (xy 63.445401 -91.504832) (xy 63.445898 -91.559888)
			(xy 63.445401 -91.614944) (xy 63.437455 -91.72477) (xy 63.421606 -91.833736) (xy 63.397935 -91.941274)
			(xy 63.366566 -92.046824) (xy 63.327662 -92.149836) (xy 63.281427 -92.249771) (xy 63.228101 -92.34611)
			(xy 63.167963 -92.43835) (xy 63.120949 -92.500196) (xy 94.864936 -92.500196) (xy 94.864936 -87.500206)
			(xy 94.865431 -87.399365) (xy 94.873349 -87.197838) (xy 94.889173 -86.996778) (xy 94.912878 -86.796494)
			(xy 94.944428 -86.597295) (xy 94.983774 -86.399488) (xy 95.030856 -86.203379) (xy 95.085601 -86.009269)
			(xy 95.147924 -85.817458) (xy 95.217729 -85.628241) (xy 95.29491 -85.441912) (xy 95.379346 -85.258755)
			(xy 95.470908 -85.079055) (xy 95.569454 -84.903089) (xy 95.674832 -84.731126) (xy 95.786881 -84.563434)
			(xy 95.905427 -84.40027) (xy 96.030287 -84.241885) (xy 96.161269 -84.088525) (xy 96.298171 -83.940425)
			(xy 96.440781 -83.797815) (xy 96.588881 -83.660913) (xy 96.742241 -83.529931) (xy 96.900626 -83.405071)
			(xy 97.06379 -83.286525) (xy 97.231482 -83.174476) (xy 97.403445 -83.069098) (xy 97.579411 -82.970552)
			(xy 97.759111 -82.87899) (xy 97.942268 -82.794554) (xy 98.128597 -82.717373) (xy 98.317814 -82.647568)
			(xy 98.509625 -82.585245) (xy 98.703735 -82.5305) (xy 98.899844 -82.483418) (xy 99.097651 -82.444072)
			(xy 99.29685 -82.412522) (xy 99.497134 -82.388817) (xy 99.698194 -82.372993) (xy 99.899721 -82.365075)
			(xy 100.101403 -82.365075) (xy 100.30293 -82.372993) (xy 100.50399 -82.388817) (xy 100.704274 -82.412522)
			(xy 100.903473 -82.444072) (xy 101.10128 -82.483418) (xy 101.297389 -82.5305) (xy 101.491499 -82.585245)
			(xy 101.68331 -82.647568) (xy 101.872527 -82.717373) (xy 102.058856 -82.794554) (xy 102.242013 -82.87899)
			(xy 102.421713 -82.970552) (xy 102.597679 -83.069098) (xy 102.769642 -83.174476) (xy 102.937334 -83.286525)
			(xy 103.100498 -83.405071) (xy 103.258883 -83.529931) (xy 103.412243 -83.660913) (xy 103.560343 -83.797815)
			(xy 103.702953 -83.940425) (xy 103.839855 -84.088525) (xy 103.970837 -84.241885) (xy 104.095697 -84.40027)
			(xy 104.214243 -84.563434) (xy 104.326292 -84.731126) (xy 104.43167 -84.903089) (xy 104.530216 -85.079055)
			(xy 104.621778 -85.258755) (xy 104.706214 -85.441912) (xy 104.783395 -85.628241) (xy 104.8532 -85.817458)
			(xy 104.915523 -86.009269) (xy 104.970268 -86.203379) (xy 105.01735 -86.399488) (xy 105.056696 -86.597295)
			(xy 105.088246 -86.796494) (xy 105.111951 -86.996778) (xy 105.127775 -87.197838) (xy 105.135693 -87.399365)
			(xy 105.136188 -87.500206) (xy 105.136188 -92.500196) (xy 105.135693 -92.601037) (xy 105.127775 -92.802564)
			(xy 105.111951 -93.003624) (xy 105.088246 -93.203908) (xy 105.056696 -93.403107) (xy 105.01735 -93.600914)
			(xy 104.970268 -93.797023) (xy 104.915523 -93.991133) (xy 104.8532 -94.182944) (xy 104.783395 -94.372161)
			(xy 104.706214 -94.55849) (xy 104.621778 -94.741647) (xy 104.530216 -94.921347) (xy 104.43167 -95.097313)
			(xy 104.326292 -95.269276) (xy 104.214243 -95.436968) (xy 104.095697 -95.600132) (xy 103.970837 -95.758517)
			(xy 103.839855 -95.911877) (xy 103.702953 -96.059977) (xy 103.560343 -96.202587) (xy 103.412243 -96.339489)
			(xy 103.258883 -96.470471) (xy 103.100498 -96.595331) (xy 102.937334 -96.713877) (xy 102.769642 -96.825926)
			(xy 102.597679 -96.931304) (xy 102.421713 -97.02985) (xy 102.242013 -97.121412) (xy 102.058856 -97.205848)
			(xy 101.872527 -97.283029) (xy 101.68331 -97.352834) (xy 101.491499 -97.415157) (xy 101.297389 -97.469902)
			(xy 101.10128 -97.516984) (xy 100.903473 -97.55633) (xy 100.704274 -97.58788) (xy 100.50399 -97.611585)
			(xy 100.30293 -97.627409) (xy 100.101403 -97.635327) (xy 99.899721 -97.635327) (xy 99.698194 -97.627409)
			(xy 99.497134 -97.611585) (xy 99.29685 -97.58788) (xy 99.097651 -97.55633) (xy 98.899844 -97.516984)
			(xy 98.703735 -97.469902) (xy 98.509625 -97.415157) (xy 98.317814 -97.352834) (xy 98.128597 -97.283029)
			(xy 97.942268 -97.205848) (xy 97.759111 -97.121412) (xy 97.579411 -97.02985) (xy 97.403445 -96.931304)
			(xy 97.231482 -96.825926) (xy 97.06379 -96.713877) (xy 96.900626 -96.595331) (xy 96.742241 -96.470471)
			(xy 96.588881 -96.339489) (xy 96.440781 -96.202587) (xy 96.298171 -96.059977) (xy 96.161269 -95.911877)
			(xy 96.030287 -95.758517) (xy 95.905427 -95.600132) (xy 95.786881 -95.436968) (xy 95.674832 -95.269276)
			(xy 95.569454 -95.097313) (xy 95.470908 -94.921347) (xy 95.379346 -94.741647) (xy 95.29491 -94.55849)
			(xy 95.217729 -94.372161) (xy 95.147924 -94.182944) (xy 95.085601 -93.991133) (xy 95.030856 -93.797023)
			(xy 94.983774 -93.600914) (xy 94.944428 -93.403107) (xy 94.912878 -93.203908) (xy 94.889173 -93.003624)
			(xy 94.873349 -92.802564) (xy 94.865431 -92.601037) (xy 94.864936 -92.500196) (xy 63.120949 -92.500196)
			(xy 63.101326 -92.52601) (xy 63.028537 -92.608633) (xy 62.949976 -92.685789) (xy 62.866052 -92.757074)
			(xy 62.777203 -92.822118) (xy 62.683893 -92.880581) (xy 62.586607 -92.932159) (xy 62.485853 -92.976582)
			(xy 62.382156 -93.013619) (xy 62.276057 -93.043078) (xy 62.168108 -93.064803) (xy 62.058874 -93.078683)
			(xy 61.948923 -93.084644) (xy 61.838828 -93.082656) (xy 61.729164 -93.072729) (xy 61.620501 -93.054915)
			(xy 61.513408 -93.029307) (xy 61.408442 -92.996037) (xy 61.306149 -92.95528) (xy 61.207065 -92.907248)
			(xy 61.111704 -92.852192) (xy 61.020565 -92.790398) (xy 60.934123 -92.722189) (xy 60.852827 -92.64792)
			(xy 60.777103 -92.567979) (xy 60.707344 -92.482782) (xy 60.643915 -92.392773) (xy 60.587146 -92.298422)
			(xy 60.537333 -92.200221) (xy 60.494736 -92.098681) (xy 60.459577 -91.994333) (xy 60.432039 -91.887719)
			(xy 60.412266 -91.779396) (xy 60.40036 -91.669929) (xy 60.396385 -91.559888) (xy 43.887898 -91.559888)
			(xy 43.887401 -91.614944) (xy 43.879455 -91.72477) (xy 43.863606 -91.833736) (xy 43.839935 -91.941274)
			(xy 43.808566 -92.046824) (xy 43.769662 -92.149836) (xy 43.723427 -92.249771) (xy 43.670101 -92.34611)
			(xy 43.609963 -92.43835) (xy 43.543326 -92.52601) (xy 43.470537 -92.608633) (xy 43.391976 -92.685789)
			(xy 43.308052 -92.757074) (xy 43.219203 -92.822118) (xy 43.125893 -92.880581) (xy 43.028607 -92.932159)
			(xy 42.927853 -92.976582) (xy 42.824156 -93.013619) (xy 42.718057 -93.043078) (xy 42.610108 -93.064803)
			(xy 42.500874 -93.078683) (xy 42.390923 -93.084644) (xy 42.280828 -93.082656) (xy 42.171164 -93.072729)
			(xy 42.062501 -93.054915) (xy 41.955408 -93.029307) (xy 41.850442 -92.996037) (xy 41.748149 -92.95528)
			(xy 41.649065 -92.907248) (xy 41.553704 -92.852192) (xy 41.462565 -92.790398) (xy 41.376123 -92.722189)
			(xy 41.294827 -92.64792) (xy 41.219103 -92.567979) (xy 41.149344 -92.482782) (xy 41.085915 -92.392773)
			(xy 41.029146 -92.298422) (xy 40.979333 -92.200221) (xy 40.936736 -92.098681) (xy 40.901577 -91.994333)
			(xy 40.874039 -91.887719) (xy 40.854266 -91.779396) (xy 40.84236 -91.669929) (xy 40.838385 -91.559888)
			(xy 34.042096 -91.559888) (xy 34.042096 -99.06) (xy 41.346384 -99.06) (xy 41.350364 -98.970117) (xy 41.362272 -98.880937)
			(xy 41.382015 -98.793159) (xy 41.409439 -98.707469) (xy 41.444328 -98.624538) (xy 41.486411 -98.545016)
			(xy 41.535357 -98.469523) (xy 41.590784 -98.398652) (xy 41.652257 -98.332957) (xy 41.719296 -98.272952)
			(xy 41.791376 -98.219107) (xy 41.867932 -98.171843) (xy 41.948367 -98.13153) (xy 42.032049 -98.098483)
			(xy 42.118324 -98.072962) (xy 42.206518 -98.055166) (xy 42.295939 -98.045233) (xy 42.385888 -98.043243)
			(xy 42.475661 -98.04921) (xy 42.564556 -98.063088) (xy 42.651876 -98.084768) (xy 42.736938 -98.114081)
			(xy 42.819077 -98.150797) (xy 42.897649 -98.194628) (xy 42.97204 -98.245232) (xy 43.041667 -98.302213)
			(xy 43.105986 -98.365125) (xy 43.164494 -98.433475) (xy 43.216731 -98.506728) (xy 43.26229 -98.584311)
			(xy 43.300814 -98.665618) (xy 43.332001 -98.750011) (xy 43.355608 -98.83683) (xy 43.371449 -98.925395)
			(xy 43.379401 -99.015014) (xy 43.379898 -99.06) (xy 60.904384 -99.06) (xy 60.908364 -98.970117) (xy 60.920272 -98.880937)
			(xy 60.940015 -98.793159) (xy 60.967439 -98.707469) (xy 61.002328 -98.624538) (xy 61.044411 -98.545016)
			(xy 61.093357 -98.469523) (xy 61.148784 -98.398652) (xy 61.210257 -98.332957) (xy 61.277296 -98.272952)
			(xy 61.349376 -98.219107) (xy 61.425932 -98.171843) (xy 61.506367 -98.13153) (xy 61.590049 -98.098483)
			(xy 61.676324 -98.072962) (xy 61.764518 -98.055166) (xy 61.853939 -98.045233) (xy 61.943888 -98.043243)
			(xy 62.033661 -98.04921) (xy 62.122556 -98.063088) (xy 62.209876 -98.084768) (xy 62.294938 -98.114081)
			(xy 62.377077 -98.150797) (xy 62.455649 -98.194628) (xy 62.53004 -98.245232) (xy 62.599667 -98.302213)
			(xy 62.663986 -98.365125) (xy 62.722494 -98.433475) (xy 62.774731 -98.506728) (xy 62.82029 -98.584311)
			(xy 62.858814 -98.665618) (xy 62.890001 -98.750011) (xy 62.913608 -98.83683) (xy 62.929449 -98.925395)
			(xy 62.937401 -99.015014) (xy 62.937898 -99.06) (xy 62.937401 -99.104986) (xy 62.929449 -99.194605)
			(xy 62.913608 -99.28317) (xy 62.890001 -99.369989) (xy 62.858814 -99.454382) (xy 62.82029 -99.535689)
			(xy 62.774731 -99.613272) (xy 62.722494 -99.686525) (xy 62.663986 -99.754875) (xy 62.599667 -99.817787)
			(xy 62.53004 -99.874768) (xy 62.455649 -99.925372) (xy 62.377077 -99.969203) (xy 62.294938 -100.005919)
			(xy 62.209876 -100.035232) (xy 62.122556 -100.056912) (xy 62.033661 -100.07079) (xy 61.943888 -100.076757)
			(xy 61.853939 -100.074767) (xy 61.764518 -100.064834) (xy 61.676324 -100.047038) (xy 61.590049 -100.021517)
			(xy 61.506367 -99.98847) (xy 61.425932 -99.948157) (xy 61.349376 -99.900893) (xy 61.277296 -99.847048)
			(xy 61.210257 -99.787043) (xy 61.148784 -99.721348) (xy 61.093357 -99.650477) (xy 61.044411 -99.574984)
			(xy 61.002328 -99.495462) (xy 60.967439 -99.412531) (xy 60.940015 -99.326841) (xy 60.920272 -99.239063)
			(xy 60.908364 -99.149883) (xy 60.904384 -99.06) (xy 43.379898 -99.06) (xy 43.379401 -99.104986) (xy 43.371449 -99.194605)
			(xy 43.355608 -99.28317) (xy 43.332001 -99.369989) (xy 43.300814 -99.454382) (xy 43.26229 -99.535689)
			(xy 43.216731 -99.613272) (xy 43.164494 -99.686525) (xy 43.105986 -99.754875) (xy 43.041667 -99.817787)
			(xy 42.97204 -99.874768) (xy 42.897649 -99.925372) (xy 42.819077 -99.969203) (xy 42.736938 -100.005919)
			(xy 42.651876 -100.035232) (xy 42.564556 -100.056912) (xy 42.475661 -100.07079) (xy 42.385888 -100.076757)
			(xy 42.295939 -100.074767) (xy 42.206518 -100.064834) (xy 42.118324 -100.047038) (xy 42.032049 -100.021517)
			(xy 41.948367 -99.98847) (xy 41.867932 -99.948157) (xy 41.791376 -99.900893) (xy 41.719296 -99.847048)
			(xy 41.652257 -99.787043) (xy 41.590784 -99.721348) (xy 41.535357 -99.650477) (xy 41.486411 -99.574984)
			(xy 41.444328 -99.495462) (xy 41.409439 -99.412531) (xy 41.382015 -99.326841) (xy 41.362272 -99.239063)
			(xy 41.350364 -99.149883) (xy 41.346384 -99.06) (xy 34.042096 -99.06) (xy 34.042096 -111.879888)
			(xy 40.838385 -111.879888) (xy 40.84236 -111.769847) (xy 40.854266 -111.66038) (xy 40.874039 -111.552057)
			(xy 40.901577 -111.445443) (xy 40.936736 -111.341095) (xy 40.979333 -111.239555) (xy 41.029146 -111.141354)
			(xy 41.085915 -111.047003) (xy 41.149344 -110.956994) (xy 41.219103 -110.871797) (xy 41.294827 -110.791856)
			(xy 41.376123 -110.717587) (xy 41.462565 -110.649378) (xy 41.553704 -110.587584) (xy 41.649065 -110.532528)
			(xy 41.748149 -110.484496) (xy 41.850442 -110.443739) (xy 41.955408 -110.410469) (xy 42.062501 -110.384861)
			(xy 42.171164 -110.367047) (xy 42.280828 -110.35712) (xy 42.390923 -110.355132) (xy 42.500874 -110.361093)
			(xy 42.610108 -110.374973) (xy 42.718057 -110.396698) (xy 42.824156 -110.426157) (xy 42.927853 -110.463194)
			(xy 43.028607 -110.507617) (xy 43.125893 -110.559195) (xy 43.219203 -110.617658) (xy 43.308052 -110.682702)
			(xy 43.391976 -110.753987) (xy 43.470537 -110.831143) (xy 43.543326 -110.913766) (xy 43.609963 -111.001426)
			(xy 43.670101 -111.093666) (xy 43.723427 -111.190005) (xy 43.769662 -111.28994) (xy 43.808566 -111.392952)
			(xy 43.839935 -111.498502) (xy 43.863606 -111.60604) (xy 43.879455 -111.715006) (xy 43.887401 -111.824832)
			(xy 43.887898 -111.879888) (xy 60.396385 -111.879888) (xy 60.40036 -111.769847) (xy 60.412266 -111.66038)
			(xy 60.432039 -111.552057) (xy 60.459577 -111.445443) (xy 60.494736 -111.341095) (xy 60.537333 -111.239555)
			(xy 60.587146 -111.141354) (xy 60.643915 -111.047003) (xy 60.707344 -110.956994) (xy 60.777103 -110.871797)
			(xy 60.852827 -110.791856) (xy 60.934123 -110.717587) (xy 61.020565 -110.649378) (xy 61.111704 -110.587584)
			(xy 61.207065 -110.532528) (xy 61.306149 -110.484496) (xy 61.408442 -110.443739) (xy 61.513408 -110.410469)
			(xy 61.620501 -110.384861) (xy 61.729164 -110.367047) (xy 61.838828 -110.35712) (xy 61.948923 -110.355132)
			(xy 62.058874 -110.361093) (xy 62.168108 -110.374973) (xy 62.276057 -110.396698) (xy 62.382156 -110.426157)
			(xy 62.485853 -110.463194) (xy 62.586607 -110.507617) (xy 62.683893 -110.559195) (xy 62.777203 -110.617658)
			(xy 62.866052 -110.682702) (xy 62.949976 -110.753987) (xy 63.028537 -110.831143) (xy 63.101326 -110.913766)
			(xy 63.167963 -111.001426) (xy 63.228101 -111.093666) (xy 63.281427 -111.190005) (xy 63.327662 -111.28994)
			(xy 63.366566 -111.392952) (xy 63.397935 -111.498502) (xy 63.421606 -111.60604) (xy 63.437455 -111.715006)
			(xy 63.445401 -111.824832) (xy 63.445898 -111.879888) (xy 63.445401 -111.934944) (xy 63.437455 -112.04477)
			(xy 63.421606 -112.153736) (xy 63.397935 -112.261274) (xy 63.366566 -112.366824) (xy 63.327662 -112.469836)
			(xy 63.281427 -112.569771) (xy 63.228101 -112.66611) (xy 63.167963 -112.75835) (xy 63.101326 -112.84601)
			(xy 63.028537 -112.928633) (xy 62.949976 -113.005789) (xy 62.866052 -113.077074) (xy 62.777203 -113.142118)
			(xy 62.683893 -113.200581) (xy 62.586607 -113.252159) (xy 62.485853 -113.296582) (xy 62.382156 -113.333619)
			(xy 62.276057 -113.363078) (xy 62.168108 -113.384803) (xy 62.058874 -113.398683) (xy 61.948923 -113.404644)
			(xy 61.838828 -113.402656) (xy 61.729164 -113.392729) (xy 61.620501 -113.374915) (xy 61.513408 -113.349307)
			(xy 61.408442 -113.316037) (xy 61.306149 -113.27528) (xy 61.207065 -113.227248) (xy 61.111704 -113.172192)
			(xy 61.020565 -113.110398) (xy 60.934123 -113.042189) (xy 60.852827 -112.96792) (xy 60.777103 -112.887979)
			(xy 60.707344 -112.802782) (xy 60.643915 -112.712773) (xy 60.587146 -112.618422) (xy 60.537333 -112.520221)
			(xy 60.494736 -112.418681) (xy 60.459577 -112.314333) (xy 60.432039 -112.207719) (xy 60.412266 -112.099396)
			(xy 60.40036 -111.989929) (xy 60.396385 -111.879888) (xy 43.887898 -111.879888) (xy 43.887401 -111.934944)
			(xy 43.879455 -112.04477) (xy 43.863606 -112.153736) (xy 43.839935 -112.261274) (xy 43.808566 -112.366824)
			(xy 43.769662 -112.469836) (xy 43.723427 -112.569771) (xy 43.670101 -112.66611) (xy 43.609963 -112.75835)
			(xy 43.543326 -112.84601) (xy 43.470537 -112.928633) (xy 43.391976 -113.005789) (xy 43.308052 -113.077074)
			(xy 43.219203 -113.142118) (xy 43.125893 -113.200581) (xy 43.028607 -113.252159) (xy 42.927853 -113.296582)
			(xy 42.824156 -113.333619) (xy 42.718057 -113.363078) (xy 42.610108 -113.384803) (xy 42.500874 -113.398683)
			(xy 42.390923 -113.404644) (xy 42.280828 -113.402656) (xy 42.171164 -113.392729) (xy 42.062501 -113.374915)
			(xy 41.955408 -113.349307) (xy 41.850442 -113.316037) (xy 41.748149 -113.27528) (xy 41.649065 -113.227248)
			(xy 41.553704 -113.172192) (xy 41.462565 -113.110398) (xy 41.376123 -113.042189) (xy 41.294827 -112.96792)
			(xy 41.219103 -112.887979) (xy 41.149344 -112.802782) (xy 41.085915 -112.712773) (xy 41.029146 -112.618422)
			(xy 40.979333 -112.520221) (xy 40.936736 -112.418681) (xy 40.901577 -112.314333) (xy 40.874039 -112.207719)
			(xy 40.854266 -112.099396) (xy 40.84236 -111.989929) (xy 40.838385 -111.879888) (xy 34.042096 -111.879888)
			(xy 34.042096 -119.38) (xy 41.346384 -119.38) (xy 41.350364 -119.290117) (xy 41.362272 -119.200937)
			(xy 41.382015 -119.113159) (xy 41.409439 -119.027469) (xy 41.444328 -118.944538) (xy 41.486411 -118.865016)
			(xy 41.535357 -118.789523) (xy 41.590784 -118.718652) (xy 41.652257 -118.652957) (xy 41.719296 -118.592952)
			(xy 41.791376 -118.539107) (xy 41.867932 -118.491843) (xy 41.948367 -118.45153) (xy 42.032049 -118.418483)
			(xy 42.118324 -118.392962) (xy 42.206518 -118.375166) (xy 42.295939 -118.365233) (xy 42.385888 -118.363243)
			(xy 42.475661 -118.36921) (xy 42.564556 -118.383088) (xy 42.651876 -118.404768) (xy 42.736938 -118.434081)
			(xy 42.819077 -118.470797) (xy 42.897649 -118.514628) (xy 42.97204 -118.565232) (xy 43.041667 -118.622213)
			(xy 43.105986 -118.685125) (xy 43.164494 -118.753475) (xy 43.216731 -118.826728) (xy 43.26229 -118.904311)
			(xy 43.300814 -118.985618) (xy 43.332001 -119.070011) (xy 43.355608 -119.15683) (xy 43.371449 -119.245395)
			(xy 43.379401 -119.335014) (xy 43.379898 -119.38) (xy 60.904384 -119.38) (xy 60.908364 -119.290117)
			(xy 60.920272 -119.200937) (xy 60.940015 -119.113159) (xy 60.967439 -119.027469) (xy 61.002328 -118.944538)
			(xy 61.044411 -118.865016) (xy 61.093357 -118.789523) (xy 61.148784 -118.718652) (xy 61.210257 -118.652957)
			(xy 61.277296 -118.592952) (xy 61.349376 -118.539107) (xy 61.425932 -118.491843) (xy 61.506367 -118.45153)
			(xy 61.590049 -118.418483) (xy 61.676324 -118.392962) (xy 61.764518 -118.375166) (xy 61.853939 -118.365233)
			(xy 61.943888 -118.363243) (xy 62.033661 -118.36921) (xy 62.122556 -118.383088) (xy 62.209876 -118.404768)
			(xy 62.294938 -118.434081) (xy 62.377077 -118.470797) (xy 62.455649 -118.514628) (xy 62.53004 -118.565232)
			(xy 62.599667 -118.622213) (xy 62.663986 -118.685125) (xy 62.722494 -118.753475) (xy 62.774731 -118.826728)
			(xy 62.82029 -118.904311) (xy 62.858814 -118.985618) (xy 62.890001 -119.070011) (xy 62.913608 -119.15683)
			(xy 62.929449 -119.245395) (xy 62.937401 -119.335014) (xy 62.937898 -119.38) (xy 62.937401 -119.424986)
			(xy 62.929449 -119.514605) (xy 62.913608 -119.60317) (xy 62.890001 -119.689989) (xy 62.858814 -119.774382)
			(xy 62.82029 -119.855689) (xy 62.774731 -119.933272) (xy 62.722494 -120.006525) (xy 62.663986 -120.074875)
			(xy 62.599667 -120.137787) (xy 62.53004 -120.194768) (xy 62.455649 -120.245372) (xy 62.377077 -120.289203)
			(xy 62.294938 -120.325919) (xy 62.209876 -120.355232) (xy 62.122556 -120.376912) (xy 62.033661 -120.39079)
			(xy 61.943888 -120.396757) (xy 61.853939 -120.394767) (xy 61.764518 -120.384834) (xy 61.676324 -120.367038)
			(xy 61.590049 -120.341517) (xy 61.506367 -120.30847) (xy 61.425932 -120.268157) (xy 61.349376 -120.220893)
			(xy 61.277296 -120.167048) (xy 61.210257 -120.107043) (xy 61.148784 -120.041348) (xy 61.093357 -119.970477)
			(xy 61.044411 -119.894984) (xy 61.002328 -119.815462) (xy 60.967439 -119.732531) (xy 60.940015 -119.646841)
			(xy 60.920272 -119.559063) (xy 60.908364 -119.469883) (xy 60.904384 -119.38) (xy 43.379898 -119.38)
			(xy 43.379401 -119.424986) (xy 43.371449 -119.514605) (xy 43.355608 -119.60317) (xy 43.332001 -119.689989)
			(xy 43.300814 -119.774382) (xy 43.26229 -119.855689) (xy 43.216731 -119.933272) (xy 43.164494 -120.006525)
			(xy 43.105986 -120.074875) (xy 43.041667 -120.137787) (xy 42.97204 -120.194768) (xy 42.897649 -120.245372)
			(xy 42.819077 -120.289203) (xy 42.736938 -120.325919) (xy 42.651876 -120.355232) (xy 42.564556 -120.376912)
			(xy 42.475661 -120.39079) (xy 42.385888 -120.396757) (xy 42.295939 -120.394767) (xy 42.206518 -120.384834)
			(xy 42.118324 -120.367038) (xy 42.032049 -120.341517) (xy 41.948367 -120.30847) (xy 41.867932 -120.268157)
			(xy 41.791376 -120.220893) (xy 41.719296 -120.167048) (xy 41.652257 -120.107043) (xy 41.590784 -120.041348)
			(xy 41.535357 -119.970477) (xy 41.486411 -119.894984) (xy 41.444328 -119.815462) (xy 41.409439 -119.732531)
			(xy 41.382015 -119.646841) (xy 41.362272 -119.559063) (xy 41.350364 -119.469883) (xy 41.346384 -119.38)
			(xy 34.042096 -119.38) (xy 34.042096 -132.199888) (xy 40.838385 -132.199888) (xy 40.84236 -132.089847)
			(xy 40.854266 -131.98038) (xy 40.874039 -131.872057) (xy 40.901577 -131.765443) (xy 40.936736 -131.661095)
			(xy 40.979333 -131.559555) (xy 41.029146 -131.461354) (xy 41.085915 -131.367003) (xy 41.149344 -131.276994)
			(xy 41.219103 -131.191797) (xy 41.294827 -131.111856) (xy 41.376123 -131.037587) (xy 41.462565 -130.969378)
			(xy 41.553704 -130.907584) (xy 41.649065 -130.852528) (xy 41.748149 -130.804496) (xy 41.850442 -130.763739)
			(xy 41.955408 -130.730469) (xy 42.062501 -130.704861) (xy 42.171164 -130.687047) (xy 42.280828 -130.67712)
			(xy 42.390923 -130.675132) (xy 42.500874 -130.681093) (xy 42.610108 -130.694973) (xy 42.718057 -130.716698)
			(xy 42.824156 -130.746157) (xy 42.927853 -130.783194) (xy 43.028607 -130.827617) (xy 43.125893 -130.879195)
			(xy 43.219203 -130.937658) (xy 43.308052 -131.002702) (xy 43.391976 -131.073987) (xy 43.470537 -131.151143)
			(xy 43.543326 -131.233766) (xy 43.609963 -131.321426) (xy 43.670101 -131.413666) (xy 43.723427 -131.510005)
			(xy 43.769662 -131.60994) (xy 43.808566 -131.712952) (xy 43.839935 -131.818502) (xy 43.863606 -131.92604)
			(xy 43.879455 -132.035006) (xy 43.887401 -132.144832) (xy 43.887898 -132.199888) (xy 60.396385 -132.199888)
			(xy 60.40036 -132.089847) (xy 60.412266 -131.98038) (xy 60.432039 -131.872057) (xy 60.459577 -131.765443)
			(xy 60.494736 -131.661095) (xy 60.537333 -131.559555) (xy 60.587146 -131.461354) (xy 60.643915 -131.367003)
			(xy 60.707344 -131.276994) (xy 60.777103 -131.191797) (xy 60.852827 -131.111856) (xy 60.934123 -131.037587)
			(xy 61.020565 -130.969378) (xy 61.111704 -130.907584) (xy 61.207065 -130.852528) (xy 61.306149 -130.804496)
			(xy 61.408442 -130.763739) (xy 61.513408 -130.730469) (xy 61.620501 -130.704861) (xy 61.729164 -130.687047)
			(xy 61.838828 -130.67712) (xy 61.948923 -130.675132) (xy 62.058874 -130.681093) (xy 62.168108 -130.694973)
			(xy 62.276057 -130.716698) (xy 62.382156 -130.746157) (xy 62.485853 -130.783194) (xy 62.586607 -130.827617)
			(xy 62.683893 -130.879195) (xy 62.777203 -130.937658) (xy 62.866052 -131.002702) (xy 62.949976 -131.073987)
			(xy 63.028537 -131.151143) (xy 63.101326 -131.233766) (xy 63.167963 -131.321426) (xy 63.228101 -131.413666)
			(xy 63.281427 -131.510005) (xy 63.327662 -131.60994) (xy 63.366566 -131.712952) (xy 63.397935 -131.818502)
			(xy 63.421606 -131.92604) (xy 63.437455 -132.035006) (xy 63.445401 -132.144832) (xy 63.445898 -132.199888)
			(xy 63.445401 -132.254944) (xy 63.437455 -132.36477) (xy 63.421606 -132.473736) (xy 63.397935 -132.581274)
			(xy 63.366566 -132.686824) (xy 63.327662 -132.789836) (xy 63.281427 -132.889771) (xy 63.228101 -132.98611)
			(xy 63.167963 -133.07835) (xy 63.101326 -133.16601) (xy 63.028537 -133.248633) (xy 62.949976 -133.325789)
			(xy 62.866052 -133.397074) (xy 62.777203 -133.462118) (xy 62.683893 -133.520581) (xy 62.586607 -133.572159)
			(xy 62.485853 -133.616582) (xy 62.382156 -133.653619) (xy 62.276057 -133.683078) (xy 62.168108 -133.704803)
			(xy 62.058874 -133.718683) (xy 61.948923 -133.724644) (xy 61.838828 -133.722656) (xy 61.729164 -133.712729)
			(xy 61.620501 -133.694915) (xy 61.513408 -133.669307) (xy 61.408442 -133.636037) (xy 61.306149 -133.59528)
			(xy 61.207065 -133.547248) (xy 61.111704 -133.492192) (xy 61.020565 -133.430398) (xy 60.934123 -133.362189)
			(xy 60.852827 -133.28792) (xy 60.777103 -133.207979) (xy 60.707344 -133.122782) (xy 60.643915 -133.032773)
			(xy 60.587146 -132.938422) (xy 60.537333 -132.840221) (xy 60.494736 -132.738681) (xy 60.459577 -132.634333)
			(xy 60.432039 -132.527719) (xy 60.412266 -132.419396) (xy 60.40036 -132.309929) (xy 60.396385 -132.199888)
			(xy 43.887898 -132.199888) (xy 43.887401 -132.254944) (xy 43.879455 -132.36477) (xy 43.863606 -132.473736)
			(xy 43.839935 -132.581274) (xy 43.808566 -132.686824) (xy 43.769662 -132.789836) (xy 43.723427 -132.889771)
			(xy 43.670101 -132.98611) (xy 43.609963 -133.07835) (xy 43.543326 -133.16601) (xy 43.470537 -133.248633)
			(xy 43.391976 -133.325789) (xy 43.308052 -133.397074) (xy 43.219203 -133.462118) (xy 43.125893 -133.520581)
			(xy 43.028607 -133.572159) (xy 42.927853 -133.616582) (xy 42.824156 -133.653619) (xy 42.718057 -133.683078)
			(xy 42.610108 -133.704803) (xy 42.500874 -133.718683) (xy 42.390923 -133.724644) (xy 42.280828 -133.722656)
			(xy 42.171164 -133.712729) (xy 42.062501 -133.694915) (xy 41.955408 -133.669307) (xy 41.850442 -133.636037)
			(xy 41.748149 -133.59528) (xy 41.649065 -133.547248) (xy 41.553704 -133.492192) (xy 41.462565 -133.430398)
			(xy 41.376123 -133.362189) (xy 41.294827 -133.28792) (xy 41.219103 -133.207979) (xy 41.149344 -133.122782)
			(xy 41.085915 -133.032773) (xy 41.029146 -132.938422) (xy 40.979333 -132.840221) (xy 40.936736 -132.738681)
			(xy 40.901577 -132.634333) (xy 40.874039 -132.527719) (xy 40.854266 -132.419396) (xy 40.84236 -132.309929)
			(xy 40.838385 -132.199888) (xy 34.042096 -132.199888) (xy 34.042096 -139.7) (xy 41.346384 -139.7)
			(xy 41.350364 -139.610117) (xy 41.362272 -139.520937) (xy 41.382015 -139.433159) (xy 41.409439 -139.347469)
			(xy 41.444328 -139.264538) (xy 41.486411 -139.185016) (xy 41.535357 -139.109523) (xy 41.590784 -139.038652)
			(xy 41.652257 -138.972957) (xy 41.719296 -138.912952) (xy 41.791376 -138.859107) (xy 41.867932 -138.811843)
			(xy 41.948367 -138.77153) (xy 42.032049 -138.738483) (xy 42.118324 -138.712962) (xy 42.206518 -138.695166)
			(xy 42.295939 -138.685233) (xy 42.385888 -138.683243) (xy 42.475661 -138.68921) (xy 42.564556 -138.703088)
			(xy 42.651876 -138.724768) (xy 42.736938 -138.754081) (xy 42.819077 -138.790797) (xy 42.897649 -138.834628)
			(xy 42.97204 -138.885232) (xy 43.041667 -138.942213) (xy 43.105986 -139.005125) (xy 43.164494 -139.073475)
			(xy 43.216731 -139.146728) (xy 43.26229 -139.224311) (xy 43.300814 -139.305618) (xy 43.332001 -139.390011)
			(xy 43.355608 -139.47683) (xy 43.371449 -139.565395) (xy 43.379401 -139.655014) (xy 43.379898 -139.7)
			(xy 60.904384 -139.7) (xy 60.908364 -139.610117) (xy 60.920272 -139.520937) (xy 60.940015 -139.433159)
			(xy 60.967439 -139.347469) (xy 61.002328 -139.264538) (xy 61.044411 -139.185016) (xy 61.093357 -139.109523)
			(xy 61.148784 -139.038652) (xy 61.210257 -138.972957) (xy 61.277296 -138.912952) (xy 61.349376 -138.859107)
			(xy 61.425932 -138.811843) (xy 61.506367 -138.77153) (xy 61.590049 -138.738483) (xy 61.676324 -138.712962)
			(xy 61.764518 -138.695166) (xy 61.853939 -138.685233) (xy 61.943888 -138.683243) (xy 62.033661 -138.68921)
			(xy 62.122556 -138.703088) (xy 62.209876 -138.724768) (xy 62.294938 -138.754081) (xy 62.377077 -138.790797)
			(xy 62.455649 -138.834628) (xy 62.53004 -138.885232) (xy 62.599667 -138.942213) (xy 62.663986 -139.005125)
			(xy 62.722494 -139.073475) (xy 62.774731 -139.146728) (xy 62.82029 -139.224311) (xy 62.858814 -139.305618)
			(xy 62.890001 -139.390011) (xy 62.913608 -139.47683) (xy 62.929449 -139.565395) (xy 62.937401 -139.655014)
			(xy 62.937898 -139.7) (xy 62.937401 -139.744986) (xy 62.929449 -139.834605) (xy 62.913608 -139.92317)
			(xy 62.890001 -140.009989) (xy 62.858814 -140.094382) (xy 62.82029 -140.175689) (xy 62.774731 -140.253272)
			(xy 62.722494 -140.326525) (xy 62.663986 -140.394875) (xy 62.599667 -140.457787) (xy 62.53004 -140.514768)
			(xy 62.455649 -140.565372) (xy 62.377077 -140.609203) (xy 62.294938 -140.645919) (xy 62.209876 -140.675232)
			(xy 62.122556 -140.696912) (xy 62.033661 -140.71079) (xy 61.943888 -140.716757) (xy 61.853939 -140.714767)
			(xy 61.764518 -140.704834) (xy 61.676324 -140.687038) (xy 61.590049 -140.661517) (xy 61.506367 -140.62847)
			(xy 61.425932 -140.588157) (xy 61.349376 -140.540893) (xy 61.277296 -140.487048) (xy 61.210257 -140.427043)
			(xy 61.148784 -140.361348) (xy 61.093357 -140.290477) (xy 61.044411 -140.214984) (xy 61.002328 -140.135462)
			(xy 60.967439 -140.052531) (xy 60.940015 -139.966841) (xy 60.920272 -139.879063) (xy 60.908364 -139.789883)
			(xy 60.904384 -139.7) (xy 43.379898 -139.7) (xy 43.379401 -139.744986) (xy 43.371449 -139.834605)
			(xy 43.355608 -139.92317) (xy 43.332001 -140.009989) (xy 43.300814 -140.094382) (xy 43.26229 -140.175689)
			(xy 43.216731 -140.253272) (xy 43.164494 -140.326525) (xy 43.105986 -140.394875) (xy 43.041667 -140.457787)
			(xy 42.97204 -140.514768) (xy 42.897649 -140.565372) (xy 42.819077 -140.609203) (xy 42.736938 -140.645919)
			(xy 42.651876 -140.675232) (xy 42.564556 -140.696912) (xy 42.475661 -140.71079) (xy 42.385888 -140.716757)
			(xy 42.295939 -140.714767) (xy 42.206518 -140.704834) (xy 42.118324 -140.687038) (xy 42.032049 -140.661517)
			(xy 41.948367 -140.62847) (xy 41.867932 -140.588157) (xy 41.791376 -140.540893) (xy 41.719296 -140.487048)
			(xy 41.652257 -140.427043) (xy 41.590784 -140.361348) (xy 41.535357 -140.290477) (xy 41.486411 -140.214984)
			(xy 41.444328 -140.135462) (xy 41.409439 -140.052531) (xy 41.382015 -139.966841) (xy 41.362272 -139.879063)
			(xy 41.350364 -139.789883) (xy 41.346384 -139.7) (xy 34.042096 -139.7) (xy 34.042096 -149.315932)
			(xy 34.042525 -149.326) (xy 34.050247 -149.344596) (xy 34.057082 -149.352) (xy 34.057082 -169.142918)
			(xy 34.057508 -169.152987) (xy 34.065225 -169.171589) (xy 34.072068 -169.178986) (xy 34.423096 -169.530014)
			(xy 34.43049 -169.53687) (xy 34.449089 -169.54462) (xy 34.459164 -169.545)
		)
		(stroke
			(width 0)
			(type solid)
		)
		(fill yes)
		(layer "In2.Cu")
		(net "P52V_HS2")
	)
	(gr_poly
		(pts
			(arc
				(start 192.800224 -51.05908)
				(mid 192.819747 -51.055179)
				(end 192.836292 -51.044094)
			)
			(arc
				(start 193.053462 -50.826924)
				(mid 193.064573 -50.81039)
				(end 193.068448 -50.790856)
			)
			(arc
				(start 193.068448 -46.88586)
				(mid 193.064547 -46.866337)
				(end 193.053462 -46.849792)
			)
			(arc
				(start 189.652656 -43.448986)
				(mid 189.636122 -43.437875)
				(end 189.616588 -43.434)
			)
			(arc
				(start 186.057794 -43.434)
				(mid 186.038271 -43.437901)
				(end 186.021726 -43.448986)
			)
			(arc
				(start 182.666386 -46.804326)
				(mid 182.655275 -46.82086)
				(end 182.6514 -46.840394)
			)
			(arc
				(start 182.6514 -50.663602)
				(mid 182.655301 -50.683125)
				(end 182.666386 -50.69967)
			)
			(arc
				(start 183.01081 -51.044094)
				(mid 183.027344 -51.055205)
				(end 183.046878 -51.05908)
			)
		)
		(stroke
			(width 0)
			(type solid)
		)
		(fill yes)
		(layer "In3.Cu")
		(net "P52V_2_FUSE_1")
	)
	(gr_poly
		(pts
			(arc
				(start 257.287522 -51.05908)
				(mid 257.307045 -51.055179)
				(end 257.32359 -51.044094)
			)
			(arc
				(start 257.668014 -50.69967)
				(mid 257.679125 -50.683136)
				(end 257.683 -50.663602)
			)
			(arc
				(start 257.683 -46.840394)
				(mid 257.679099 -46.820871)
				(end 257.668014 -46.804326)
			)
			(arc
				(start 254.312674 -43.448986)
				(mid 254.29614 -43.437875)
				(end 254.276606 -43.434)
			)
			(arc
				(start 250.717812 -43.434)
				(mid 250.698289 -43.437901)
				(end 250.681744 -43.448986)
			)
			(arc
				(start 247.280938 -46.849792)
				(mid 247.269827 -46.866326)
				(end 247.265952 -46.88586)
			)
			(arc
				(start 247.265952 -50.790856)
				(mid 247.269853 -50.810379)
				(end 247.280938 -50.826924)
			)
			(arc
				(start 247.498108 -51.044094)
				(mid 247.514642 -51.055205)
				(end 247.534176 -51.05908)
			)
		)
		(stroke
			(width 0)
			(type solid)
		)
		(fill yes)
		(layer "In3.Cu")
		(net "P52V_1_FUSE_1")
	)
	(gr_poly
		(pts
			(arc
				(start 136.007856 -80.01)
				(mid 136.027379 -80.006099)
				(end 136.043924 -79.995014)
			)
			(arc
				(start 136.343644 -79.695294)
				(mid 136.354755 -79.67876)
				(end 136.35863 -79.659226)
			)
			(arc
				(start 136.35863 -68.303902)
				(mid 136.397314 -68.109513)
				(end 136.507474 -67.944746)
			)
			(arc
				(start 137.49655 -66.95567)
				(mid 137.661318 -66.845512)
				(end 137.855706 -66.806826)
			)
			(arc
				(start 139.442444 -66.806826)
				(mid 139.460379 -66.803555)
				(end 139.475972 -66.794126)
			)
			(arc
				(start 139.475972 -66.794126)
				(mid 139.749442 -66.630021)
				(end 140.06322 -66.572892)
			)
			(arc
				(start 140.06322 -66.572892)
				(mid 140.377013 -66.629983)
				(end 140.650468 -66.794126)
			)
			(arc
				(start 140.650468 -66.794126)
				(mid 140.666078 -66.80351)
				(end 140.683996 -66.806826)
			)
			(arc
				(start 142.0876 -66.806826)
				(mid 142.123521 -66.791947)
				(end 142.1384 -66.756026)
			)
			(xy 142.1384 -64.131698)
			(arc
				(start 142.13713 -64.12611)
				(mid 142.120011 -64.026684)
				(end 142.11427 -63.925958)
			)
			(arc
				(start 142.11427 -63.925958)
				(mid 142.12002 -63.825234)
				(end 142.13713 -63.725806)
			)
			(xy 142.1384 -63.720218) (xy 142.1384 -63.025782)
			(arc
				(start 142.13713 -63.020194)
				(mid 142.120011 -62.920768)
				(end 142.11427 -62.820042)
			)
			(arc
				(start 142.11427 -62.820042)
				(mid 142.12002 -62.719318)
				(end 142.13713 -62.61989)
			)
			(xy 142.1384 -62.614302)
			(arc
				(start 142.1384 -47.729394)
				(mid 142.134499 -47.709871)
				(end 142.123414 -47.693326)
			)
			(arc
				(start 141.308074 -46.877986)
				(mid 141.29154 -46.866875)
				(end 141.272006 -46.863)
			)
			(arc
				(start 123.573794 -46.863)
				(mid 123.554271 -46.866901)
				(end 123.537726 -46.877986)
			)
			(arc
				(start 123.357386 -47.058326)
				(mid 123.346275 -47.07486)
				(end 123.3424 -47.094394)
			)
			(arc
				(start 123.3424 -79.651606)
				(mid 123.346301 -79.671129)
				(end 123.357386 -79.687674)
			)
			(arc
				(start 123.664726 -79.995014)
				(mid 123.68126 -80.006125)
				(end 123.700794 -80.01)
			)
		)
		(stroke
			(width 0)
			(type solid)
		)
		(fill yes)
		(layer "In3.Cu")
		(net "P52V_HS2_DRAIN_1")
	)
	(gr_poly
		(pts
			(arc
				(start 323.745606 -80.01)
				(mid 323.765129 -80.006099)
				(end 323.781674 -79.995014)
			)
			(arc
				(start 324.089014 -79.687674)
				(mid 324.100125 -79.67114)
				(end 324.104 -79.651606)
			)
			(arc
				(start 324.104 -47.094394)
				(mid 324.100099 -47.074871)
				(end 324.089014 -47.058326)
			)
			(arc
				(start 323.908674 -46.877986)
				(mid 323.89214 -46.866875)
				(end 323.872606 -46.863)
			)
			(arc
				(start 305.894994 -46.863)
				(mid 305.875471 -46.866901)
				(end 305.858926 -46.877986)
			)
			(arc
				(start 305.322986 -47.413926)
				(mid 305.311875 -47.43046)
				(end 305.308 -47.449994)
			)
			(arc
				(start 305.308 -62.242954)
				(mid 305.310753 -62.259451)
				(end 305.318668 -62.274196)
			)
			(arc
				(start 305.318668 -62.274196)
				(mid 305.457751 -62.531519)
				(end 305.505866 -62.820042)
			)
			(arc
				(start 305.505866 -62.820042)
				(mid 305.462214 -63.095019)
				(end 305.335686 -63.343028)
			)
			(arc
				(start 305.335686 -63.343028)
				(mid 305.325927 -63.373)
				(end 305.335686 -63.402972)
			)
			(arc
				(start 305.335686 -63.402972)
				(mid 305.462208 -63.650983)
				(end 305.505866 -63.925958)
			)
			(arc
				(start 305.505866 -63.925958)
				(mid 305.45777 -64.214488)
				(end 305.318668 -64.471804)
			)
			(arc
				(start 305.318668 -64.471804)
				(mid 305.310697 -64.48653)
				(end 305.308 -64.503046)
			)
			(arc
				(start 305.308 -66.113406)
				(mid 305.311901 -66.132929)
				(end 305.322986 -66.149474)
			)
			(arc
				(start 305.994816 -66.821304)
				(mid 306.01135 -66.832415)
				(end 306.030884 -66.83629)
			)
			(arc
				(start 306.81422 -66.83629)
				(mid 306.833245 -66.832593)
				(end 306.849526 -66.822066)
			)
			(arc
				(start 306.849526 -66.822066)
				(mid 307.467 -66.57292)
				(end 308.084474 -66.822066)
			)
			(arc
				(start 308.084474 -66.822066)
				(mid 308.100741 -66.832627)
				(end 308.11978 -66.83629)
			)
			(arc
				(start 309.808372 -66.83629)
				(mid 310.002761 -66.874974)
				(end 310.167528 -66.985134)
			)
			(arc
				(start 311.081166 -67.898772)
				(mid 311.191324 -68.06354)
				(end 311.23001 -68.257928)
			)
			(arc
				(start 311.23001 -79.613252)
				(mid 311.233911 -79.632775)
				(end 311.244996 -79.64932)
			)
			(arc
				(start 311.59069 -79.995014)
				(mid 311.607224 -80.006125)
				(end 311.626758 -80.01)
			)
		)
		(stroke
			(width 0)
			(type solid)
		)
		(fill yes)
		(layer "In3.Cu")
		(net "P52V_HS1_DRAIN_1")
	)
	(gr_poly
		(pts
			(arc
				(start 141.221206 -45.847)
				(mid 141.240729 -45.843099)
				(end 141.257274 -45.832014)
			)
			(arc
				(start 142.123414 -44.965874)
				(mid 142.134525 -44.94934)
				(end 142.1384 -44.929806)
			)
			(arc
				(start 142.1384 -41.667176)
				(mid 142.131291 -41.641003)
				(end 142.11173 -41.622218)
			)
			(arc
				(start 142.11173 -41.622218)
				(mid 141.769734 -41.29524)
				(end 141.643862 -40.839136)
			)
			(arc
				(start 141.643862 -40.839136)
				(mid 141.647416 -40.759442)
				(end 141.658086 -40.680386)
			)
			(xy 141.660372 -40.66794) (xy 141.653006 -40.644318)
			(arc
				(start 141.511274 -40.502586)
				(mid 141.49474 -40.491475)
				(end 141.475206 -40.4876)
			)
			(arc
				(start 139.1666 -40.4876)
				(mid 138.972211 -40.448916)
				(end 138.807444 -40.338756)
			)
			(arc
				(start 137.689844 -39.221156)
				(mid 137.579686 -39.056388)
				(end 137.541 -38.862)
			)
			(arc
				(start 137.541 -33.8328)
				(mid 137.579684 -33.638411)
				(end 137.689844 -33.473644)
			)
			(arc
				(start 137.989564 -33.173924)
				(mid 138.154332 -33.063766)
				(end 138.34872 -33.02508)
			)
			(arc
				(start 139.38885 -33.02508)
				(mid 139.408704 -33.02104)
				(end 139.425426 -33.009586)
			)
			(arc
				(start 139.425426 -33.009586)
				(mid 140.06322 -32.740107)
				(end 140.701014 -33.009586)
			)
			(arc
				(start 140.701014 -33.009586)
				(mid 140.717722 -33.021073)
				(end 140.73759 -33.02508)
			)
			(arc
				(start 141.520926 -33.02508)
				(mid 141.540449 -33.021179)
				(end 141.556994 -33.010094)
			)
			(arc
				(start 142.123414 -32.443674)
				(mid 142.134525 -32.42714)
				(end 142.1384 -32.407606)
			)
			(xy 142.1384 -30.298898)
			(arc
				(start 142.13713 -30.29331)
				(mid 142.120011 -30.193884)
				(end 142.11427 -30.093158)
			)
			(arc
				(start 142.11427 -30.093158)
				(mid 142.12002 -29.992434)
				(end 142.13713 -29.893006)
			)
			(xy 142.1384 -29.887418) (xy 142.1384 -29.192982)
			(arc
				(start 142.13713 -29.187394)
				(mid 142.120011 -29.087968)
				(end 142.11427 -28.987242)
			)
			(arc
				(start 142.11427 -28.987242)
				(mid 142.12002 -28.886518)
				(end 142.13713 -28.78709)
			)
			(xy 142.1384 -28.781502)
			(arc
				(start 142.1384 -13.439394)
				(mid 142.134499 -13.419871)
				(end 142.123414 -13.403326)
			)
			(arc
				(start 141.689074 -12.968986)
				(mid 141.67254 -12.957875)
				(end 141.653006 -12.954)
			)
			(arc
				(start 123.700794 -12.954)
				(mid 123.681271 -12.957901)
				(end 123.664726 -12.968986)
			)
			(arc
				(start 123.357386 -13.276326)
				(mid 123.346275 -13.29286)
				(end 123.3424 -13.312394)
			)
			(arc
				(start 123.3424 -45.615606)
				(mid 123.346301 -45.635129)
				(end 123.357386 -45.651674)
			)
			(arc
				(start 123.537726 -45.832014)
				(mid 123.55426 -45.843125)
				(end 123.573794 -45.847)
			)
		)
		(stroke
			(width 0)
			(type solid)
		)
		(fill yes)
		(layer "In3.Cu")
		(net "P52V_HS2_DRAIN_2")
	)
	(gr_poly
		(pts
			(arc
				(start 323.872606 -45.847)
				(mid 323.892129 -45.843099)
				(end 323.908674 -45.832014)
			)
			(arc
				(start 324.089014 -45.651674)
				(mid 324.100125 -45.63514)
				(end 324.104 -45.615606)
			)
			(arc
				(start 324.104 -13.312394)
				(mid 324.100099 -13.292871)
				(end 324.089014 -13.276326)
			)
			(arc
				(start 323.781674 -12.968986)
				(mid 323.76514 -12.957875)
				(end 323.745606 -12.954)
			)
			(arc
				(start 305.793394 -12.954)
				(mid 305.773871 -12.957901)
				(end 305.757326 -12.968986)
			)
			(arc
				(start 305.322986 -13.403326)
				(mid 305.311875 -13.41986)
				(end 305.308 -13.439394)
			)
			(arc
				(start 305.308 -28.410154)
				(mid 305.310753 -28.426651)
				(end 305.318668 -28.441396)
			)
			(arc
				(start 305.318668 -28.441396)
				(mid 305.457751 -28.698719)
				(end 305.505866 -28.987242)
			)
			(arc
				(start 305.505866 -28.987242)
				(mid 305.462214 -29.262219)
				(end 305.335686 -29.510228)
			)
			(arc
				(start 305.335686 -29.510228)
				(mid 305.325927 -29.5402)
				(end 305.335686 -29.570172)
			)
			(arc
				(start 305.335686 -29.570172)
				(mid 305.462208 -29.818183)
				(end 305.505866 -30.093158)
			)
			(arc
				(start 305.505866 -30.093158)
				(mid 305.45777 -30.381688)
				(end 305.318668 -30.639004)
			)
			(arc
				(start 305.318668 -30.639004)
				(mid 305.310697 -30.65373)
				(end 305.308 -30.670246)
			)
			(arc
				(start 305.308 -32.712406)
				(mid 305.311901 -32.731929)
				(end 305.322986 -32.748474)
			)
			(arc
				(start 305.53152 -32.957008)
				(mid 305.548054 -32.968119)
				(end 305.567588 -32.971994)
			)
			(arc
				(start 306.848764 -32.971994)
				(mid 306.866531 -32.968786)
				(end 306.882038 -32.959548)
			)
			(arc
				(start 306.882038 -32.959548)
				(mid 307.467 -32.740071)
				(end 308.051962 -32.959548)
			)
			(arc
				(start 308.051962 -32.959548)
				(mid 308.067477 -32.968763)
				(end 308.085236 -32.971994)
			)
			(arc
				(start 309.723028 -32.971994)
				(mid 309.917417 -33.010678)
				(end 310.082184 -33.120838)
			)
			(arc
				(start 311.103518 -34.142172)
				(mid 311.213676 -34.30694)
				(end 311.252362 -34.501328)
			)
			(arc
				(start 311.252362 -39.039038)
				(mid 311.213678 -39.233427)
				(end 311.103518 -39.398194)
			)
			(arc
				(start 309.629556 -40.872156)
				(mid 309.464788 -40.982314)
				(end 309.2704 -41.021)
			)
			(arc
				(start 305.844194 -41.021)
				(mid 305.824671 -41.024901)
				(end 305.808126 -41.035986)
			)
			(xy 305.748944 -41.095168)
			(arc
				(start 305.745134 -41.102788)
				(mid 305.574995 -41.341081)
				(end 305.336702 -41.51122)
			)
			(xy 305.329082 -41.51503)
			(arc
				(start 305.322986 -41.521126)
				(mid 305.311875 -41.53766)
				(end 305.308 -41.557194)
			)
			(arc
				(start 305.308 -45.158406)
				(mid 305.311901 -45.177929)
				(end 305.322986 -45.194474)
			)
			(arc
				(start 305.960526 -45.832014)
				(mid 305.97706 -45.843125)
				(end 305.996594 -45.847)
			)
		)
		(stroke
			(width 0)
			(type solid)
		)
		(fill yes)
		(layer "In3.Cu")
		(net "P52V_HS1_DRAIN_2")
	)
	(gr_poly
		(pts
			(arc
				(start 301.02302 -66.83629)
				(mid 301.042045 -66.832593)
				(end 301.058326 -66.822066)
			)
			(arc
				(start 301.058326 -66.822066)
				(mid 301.6758 -66.57292)
				(end 302.293274 -66.822066)
			)
			(arc
				(start 302.293274 -66.822066)
				(mid 302.309541 -66.832627)
				(end 302.32858 -66.83629)
			)
			(arc
				(start 303.619916 -66.83629)
				(mid 303.639439 -66.832389)
				(end 303.655984 -66.821304)
			)
			(arc
				(start 304.277014 -66.200274)
				(mid 304.288125 -66.18374)
				(end 304.292 -66.164206)
			)
			(arc
				(start 304.292 -64.788288)
				(mid 304.283781 -64.760329)
				(end 304.26152 -64.741552)
			)
			(arc
				(start 304.26152 -64.741552)
				(mid 303.872479 -64.413552)
				(end 303.72685 -63.925958)
			)
			(arc
				(start 303.72685 -63.925958)
				(mid 303.770502 -63.650981)
				(end 303.89703 -63.402972)
			)
			(arc
				(start 303.89703 -63.402972)
				(mid 303.906789 -63.373)
				(end 303.89703 -63.343028)
			)
			(arc
				(start 303.89703 -63.343028)
				(mid 303.770508 -63.095017)
				(end 303.72685 -62.820042)
			)
			(arc
				(start 303.72685 -62.820042)
				(mid 303.872423 -62.33241)
				(end 304.26152 -62.004448)
			)
			(arc
				(start 304.26152 -62.004448)
				(mid 304.283721 -61.985633)
				(end 304.292 -61.957712)
			)
			(arc
				(start 304.292 -42.065194)
				(mid 304.288099 -42.045671)
				(end 304.277014 -42.029126)
			)
			(xy 303.762918 -41.51503)
			(arc
				(start 303.755298 -41.51122)
				(mid 303.517005 -41.341081)
				(end 303.346866 -41.102788)
			)
			(arc
				(start 303.346866 -41.102788)
				(mid 303.342572 -41.095678)
				(end 303.337214 -41.089326)
			)
			(arc
				(start 303.283874 -41.035986)
				(mid 303.26734 -41.024875)
				(end 303.247806 -41.021)
			)
			(arc
				(start 300.6852 -41.021)
				(mid 300.490811 -40.982316)
				(end 300.326044 -40.872156)
			)
			(arc
				(start 298.809156 -39.355268)
				(mid 298.698998 -39.1905)
				(end 298.660312 -38.996112)
			)
			(arc
				(start 298.660312 -33.576768)
				(mid 298.698996 -33.382379)
				(end 298.809156 -33.217612)
			)
			(arc
				(start 298.90593 -33.120838)
				(mid 299.070698 -33.01068)
				(end 299.265086 -32.971994)
			)
			(arc
				(start 301.057564 -32.971994)
				(mid 301.075331 -32.968786)
				(end 301.090838 -32.959548)
			)
			(arc
				(start 301.090838 -32.959548)
				(mid 301.6758 -32.740071)
				(end 302.260762 -32.959548)
			)
			(arc
				(start 302.260762 -32.959548)
				(mid 302.276277 -32.968763)
				(end 302.294036 -32.971994)
			)
			(arc
				(start 304.007012 -32.971994)
				(mid 304.026535 -32.968093)
				(end 304.04308 -32.957008)
			)
			(arc
				(start 304.277014 -32.723074)
				(mid 304.288125 -32.70654)
				(end 304.292 -32.687006)
			)
			(arc
				(start 304.292 -30.955488)
				(mid 304.283781 -30.927529)
				(end 304.26152 -30.908752)
			)
			(arc
				(start 304.26152 -30.908752)
				(mid 303.872479 -30.580752)
				(end 303.72685 -30.093158)
			)
			(arc
				(start 303.72685 -30.093158)
				(mid 303.770502 -29.818181)
				(end 303.89703 -29.570172)
			)
			(arc
				(start 303.89703 -29.570172)
				(mid 303.906789 -29.5402)
				(end 303.89703 -29.510228)
			)
			(arc
				(start 303.89703 -29.510228)
				(mid 303.770508 -29.262217)
				(end 303.72685 -28.987242)
			)
			(arc
				(start 303.72685 -28.987242)
				(mid 303.872423 -28.49961)
				(end 304.26152 -28.171648)
			)
			(arc
				(start 304.26152 -28.171648)
				(mid 304.283721 -28.152833)
				(end 304.292 -28.124912)
			)
			(arc
				(start 304.292 -13.439394)
				(mid 304.288099 -13.419871)
				(end 304.277014 -13.403326)
			)
			(arc
				(start 303.842674 -12.968986)
				(mid 303.82614 -12.957875)
				(end 303.806606 -12.954)
			)
			(arc
				(start 283.585412 -12.954)
				(mid 283.565889 -12.957901)
				(end 283.549344 -12.968986)
			)
			(arc
				(start 280.176986 -16.341344)
				(mid 280.165875 -16.357878)
				(end 280.162 -16.377412)
			)
			(arc
				(start 280.162 -27.182318)
				(mid 280.123316 -27.376707)
				(end 280.013156 -27.541474)
			)
			(arc
				(start 278.747474 -28.807156)
				(mid 278.582706 -28.917314)
				(end 278.388318 -28.956)
			)
			(arc
				(start 231.371394 -28.956)
				(mid 231.351871 -28.959901)
				(end 231.335326 -28.970986)
			)
			(arc
				(start 229.884986 -30.421326)
				(mid 229.873875 -30.43786)
				(end 229.87 -30.457394)
			)
			(arc
				(start 229.87 -46.758606)
				(mid 229.873901 -46.778129)
				(end 229.884986 -46.794674)
			)
			(arc
				(start 230.446326 -47.356014)
				(mid 230.46286 -47.367125)
				(end 230.482394 -47.371)
			)
			(arc
				(start 242.73256 -47.371)
				(mid 242.752083 -47.367099)
				(end 242.768628 -47.356014)
			)
			(arc
				(start 248.63425 -41.490392)
				(mid 248.799018 -41.380234)
				(end 248.993406 -41.341548)
			)
			(arc
				(start 255.891538 -41.341548)
				(mid 256.085927 -41.380232)
				(end 256.250694 -41.490392)
			)
			(arc
				(start 258.814316 -44.054014)
				(mid 258.83085 -44.065125)
				(end 258.850384 -44.069)
			)
			(arc
				(start 268.097 -44.069)
				(mid 268.291389 -44.107684)
				(end 268.456156 -44.217844)
			)
			(arc
				(start 282.440126 -58.201814)
				(mid 282.45666 -58.212925)
				(end 282.476194 -58.2168)
			)
			(arc
				(start 293.4208 -58.2168)
				(mid 293.615189 -58.255484)
				(end 293.779956 -58.365644)
			)
			(arc
				(start 297.081956 -61.667644)
				(mid 297.192114 -61.832412)
				(end 297.2308 -62.0268)
			)
			(arc
				(start 297.2308 -65.478406)
				(mid 297.234701 -65.497929)
				(end 297.245786 -65.514474)
			)
			(arc
				(start 298.552616 -66.821304)
				(mid 298.56915 -66.832415)
				(end 298.588684 -66.83629)
			)
		)
		(stroke
			(width 0)
			(type solid)
		)
		(fill yes)
		(layer "In3.Cu")
		(net "P52V_1")
	)
	(gr_poly
		(pts
			(xy 145.83537 -66.794126) (xy 145.867831 -66.766277) (xy 145.937206 -66.716243) (xy 146.011062 -66.673098)
			(xy 146.088718 -66.637241) (xy 146.169458 -66.609003) (xy 146.252535 -66.588645) (xy 146.337182 -66.576355)
			(xy 146.422618 -66.572245) (xy 146.508054 -66.576355) (xy 146.592701 -66.588645) (xy 146.675778 -66.609003)
			(xy 146.756518 -66.637241) (xy 146.834174 -66.673098) (xy 146.90803 -66.716243) (xy 146.977405 -66.766277)
			(xy 147.009866 -66.794126) (xy 147.043394 -66.806826) (xy 148.436838 -66.806826) (xy 148.446906 -66.806397)
			(xy 148.465503 -66.798675) (xy 148.472906 -66.79184) (xy 160.253934 -55.010812) (xy 160.277812 -54.987653)
			(xy 160.330574 -54.94714) (xy 160.388174 -54.913864) (xy 160.449626 -54.888395) (xy 160.513878 -54.871169)
			(xy 160.579829 -54.862481) (xy 160.61309 -54.861968) (xy 175.379888 -54.861968) (xy 175.389959 -54.861546)
			(xy 175.408563 -54.853831) (xy 175.415956 -54.846982) (xy 175.779176 -54.483762) (xy 175.786019 -54.476363)
			(xy 175.793744 -54.457764) (xy 175.794162 -54.447694) (xy 175.794162 -53.658516) (xy 175.793723 -53.648453)
			(xy 175.785983 -53.629875) (xy 175.779176 -53.622448) (xy 173.785022 -51.628294) (xy 173.777619 -51.62146)
			(xy 173.759021 -51.613755) (xy 173.748954 -51.613308) (xy 172.583348 -51.613308) (xy 172.550087 -51.61279)
			(xy 172.484133 -51.604108) (xy 172.419878 -51.586888) (xy 172.358423 -51.561423) (xy 172.300819 -51.528151)
			(xy 172.248054 -51.48764) (xy 172.224192 -51.464464) (xy 171.815506 -51.055778) (xy 171.792346 -51.0319)
			(xy 171.751833 -50.979138) (xy 171.718556 -50.921538) (xy 171.693086 -50.860086) (xy 171.675859 -50.795834)
			(xy 171.667169 -50.729883) (xy 171.666662 -50.696622) (xy 171.666662 -43.570398) (xy 171.667183 -43.537138)
			(xy 171.67587 -43.471187) (xy 171.693095 -43.406936) (xy 171.718563 -43.345483) (xy 171.751837 -43.287883)
			(xy 171.792348 -43.235122) (xy 171.815506 -43.211242) (xy 173.556676 -41.470072) (xy 173.580556 -41.446916)
			(xy 173.63332 -41.406411) (xy 173.690921 -41.373143) (xy 173.752373 -41.347681) (xy 173.816624 -41.330462)
			(xy 173.882573 -41.32178) (xy 173.915832 -41.321228) (xy 191.747394 -41.321228) (xy 191.780655 -41.321749)
			(xy 191.846606 -41.330434) (xy 191.910859 -41.347657) (xy 191.972313 -41.373123) (xy 192.029915 -41.406395)
			(xy 192.08268 -41.446904) (xy 192.10655 -41.470072) (xy 197.992492 -47.356014) (xy 197.999886 -47.362871)
			(xy 198.018485 -47.370622) (xy 198.02856 -47.371) (xy 209.852006 -47.371) (xy 209.862076 -47.370576)
			(xy 209.880679 -47.36286) (xy 209.888074 -47.356014) (xy 210.449414 -46.794674) (xy 210.456266 -46.787278)
			(xy 210.464004 -46.768679) (xy 210.4644 -46.758606) (xy 210.4644 -30.457394) (xy 210.463976 -30.447324)
			(xy 210.45626 -30.428721) (xy 210.449414 -30.421326) (xy 208.999074 -28.970986) (xy 208.991678 -28.964134)
			(xy 208.973079 -28.956396) (xy 208.963006 -28.956) (xy 161.946082 -28.956) (xy 161.912822 -28.955477)
			(xy 161.846873 -28.946788) (xy 161.782624 -28.929561) (xy 161.721174 -28.90409) (xy 161.663577 -28.870813)
			(xy 161.610819 -28.830299) (xy 161.586926 -28.807156) (xy 160.321244 -27.541474) (xy 160.298087 -27.517595)
			(xy 160.257578 -27.464831) (xy 160.224306 -27.407231) (xy 160.19884 -27.345779) (xy 160.181615 -27.281528)
			(xy 160.172927 -27.215578) (xy 160.1724 -27.182318) (xy 160.1724 -16.377412) (xy 160.171979 -16.367341)
			(xy 160.164268 -16.348733) (xy 160.157414 -16.341344) (xy 156.785056 -12.968986) (xy 156.777659 -12.962137)
			(xy 156.75906 -12.954405) (xy 156.748988 -12.954) (xy 143.639794 -12.954) (xy 143.629724 -12.954424)
			(xy 143.611121 -12.96214) (xy 143.603726 -12.968986) (xy 143.169386 -13.403326) (xy 143.162534 -13.410722)
			(xy 143.154796 -13.429321) (xy 143.1544 -13.439394) (xy 143.1544 -28.086812) (xy 143.176752 -28.114498)
			(xy 143.194278 -28.118308) (xy 143.236229 -28.128019) (xy 143.318173 -28.154495) (xy 143.397174 -28.188768)
			(xy 143.472493 -28.230517) (xy 143.543424 -28.279349) (xy 143.609303 -28.334808) (xy 143.669514 -28.396375)
			(xy 143.723492 -28.463473) (xy 143.770733 -28.535474) (xy 143.810793 -28.611704) (xy 143.843298 -28.691449)
			(xy 143.867943 -28.773962) (xy 143.884498 -28.858471) (xy 143.892807 -28.944184) (xy 143.893286 -28.987242)
			(xy 143.892835 -29.027187) (xy 143.885642 -29.106753) (xy 143.871344 -29.185353) (xy 143.850056 -29.262355)
			(xy 143.821949 -29.337138) (xy 143.787251 -29.4091) (xy 143.746241 -29.477661) (xy 143.723106 -29.510228)
			(xy 143.717172 -29.519192) (xy 143.712701 -29.5402) (xy 143.717172 -29.561208) (xy 143.723106 -29.570172)
			(xy 143.746258 -29.602728) (xy 143.787281 -29.671284) (xy 143.821987 -29.743245) (xy 143.850094 -29.81803)
			(xy 143.871376 -29.895036) (xy 143.885662 -29.973642) (xy 143.892835 -30.053212) (xy 143.893286 -30.093158)
			(xy 143.892778 -30.136213) (xy 143.884453 -30.22192) (xy 143.867886 -30.306421) (xy 143.843233 -30.388926)
			(xy 143.810723 -30.468664) (xy 143.770662 -30.544888) (xy 143.723424 -30.616884) (xy 143.669451 -30.68398)
			(xy 143.609247 -30.745547) (xy 143.543378 -30.80101) (xy 143.472457 -30.849849) (xy 143.39715 -30.891608)
			(xy 143.318161 -30.925895) (xy 143.236229 -30.95239) (xy 143.194278 -30.962092) (xy 143.176752 -30.965902)
			(xy 143.1544 -30.993588) (xy 143.1544 -32.458406) (xy 143.154824 -32.468476) (xy 143.16254 -32.487079)
			(xy 143.169386 -32.494474) (xy 143.685006 -33.010094) (xy 143.692405 -33.01694) (xy 143.711003 -33.024673)
			(xy 143.721074 -33.02508) (xy 145.18005 -33.02508) (xy 145.190294 -33.024611) (xy 145.209156 -33.016612)
			(xy 145.216626 -33.009586) (xy 145.246136 -32.979918) (xy 145.309846 -32.925658) (xy 145.37837 -32.877621)
			(xy 145.451103 -32.836233) (xy 145.527403 -32.801859) (xy 145.606593 -32.774803) (xy 145.687975 -32.755305)
			(xy 145.770828 -32.743537) (xy 145.85442 -32.739602) (xy 145.938012 -32.743537) (xy 146.020865 -32.755305)
			(xy 146.102247 -32.774803) (xy 146.181437 -32.801859) (xy 146.257737 -32.836233) (xy 146.33047 -32.877621)
			(xy 146.398994 -32.925658) (xy 146.462704 -32.979918) (xy 146.492214 -33.009586) (xy 146.499661 -33.016649)
			(xy 146.518536 -33.024665) (xy 146.52879 -33.02508) (xy 147.35048 -33.02508) (xy 147.383741 -33.0256)
			(xy 147.449692 -33.034285) (xy 147.513945 -33.051508) (xy 147.575399 -33.076974) (xy 147.633 -33.110248)
			(xy 147.685763 -33.150759) (xy 147.709636 -33.173924) (xy 148.212556 -33.676844) (xy 148.235712 -33.700724)
			(xy 148.276218 -33.753488) (xy 148.309489 -33.811089) (xy 148.334953 -33.87254) (xy 148.352175 -33.936791)
			(xy 148.360861 -34.002741) (xy 148.3614 -34.036) (xy 148.3614 -38.3794) (xy 148.360879 -38.41266)
			(xy 148.352191 -38.47861) (xy 148.334966 -38.542861) (xy 148.309497 -38.604312) (xy 148.276221 -38.661911)
			(xy 148.235708 -38.714671) (xy 148.212556 -38.738556) (xy 146.612356 -40.338756) (xy 146.588476 -40.361912)
			(xy 146.535712 -40.402418) (xy 146.478111 -40.435689) (xy 146.41666 -40.461153) (xy 146.352409 -40.478375)
			(xy 146.286459 -40.487061) (xy 146.2532 -40.4876) (xy 144.292574 -40.4876) (xy 144.280913 -40.48818)
			(xy 144.260011 -40.49852) (xy 144.252442 -40.507412) (xy 144.1958 -40.580564) (xy 144.191228 -40.60317)
			(xy 144.194276 -40.614854) (xy 144.203395 -40.651489) (xy 144.216151 -40.725904) (xy 144.222566 -40.801132)
			(xy 144.222978 -40.838882) (xy 144.222978 -40.839136) (xy 144.222502 -40.880237) (xy 144.214914 -40.962088)
			(xy 144.199806 -41.042889) (xy 144.177307 -41.121952) (xy 144.14761 -41.198602) (xy 144.110966 -41.272185)
			(xy 144.06769 -41.342073) (xy 144.01815 -41.407669) (xy 143.962768 -41.468415) (xy 143.902019 -41.523792)
			(xy 143.836418 -41.573327) (xy 143.766527 -41.616598) (xy 143.692942 -41.653236) (xy 143.61629 -41.682928)
			(xy 143.537225 -41.705421) (xy 143.456422 -41.720523) (xy 143.374571 -41.728105) (xy 143.33347 -41.728644)
			(xy 143.316052 -41.728547) (xy 143.281244 -41.727151) (xy 143.263874 -41.72585) (xy 143.253206 -41.725088)
			(xy 143.233394 -41.731946) (xy 143.170656 -41.790112) (xy 143.163326 -41.797585) (xy 143.15494 -41.816741)
			(xy 143.1544 -41.827196) (xy 143.1544 -60.8863) (xy 149.598403 -60.8863) (xy 149.602436 -60.801653)
			(xy 149.614496 -60.717772) (xy 149.634475 -60.635417) (xy 149.662192 -60.555335) (xy 149.697396 -60.47825)
			(xy 149.739767 -60.40486) (xy 149.788924 -60.33583) (xy 149.844419 -60.271786) (xy 149.90575 -60.213306)
			(xy 149.972363 -60.160922) (xy 150.043654 -60.115106) (xy 150.118977 -60.076275) (xy 150.19765 -60.044779)
			(xy 150.278961 -60.020904) (xy 150.362173 -60.004867) (xy 150.446532 -59.996812) (xy 150.488904 -59.996324)
			(xy 150.52977 -59.996769) (xy 150.611158 -60.004255) (xy 150.691516 -60.01918) (xy 150.730966 -60.029852)
			(xy 150.73884 -60.029852) (xy 150.754569 -60.028859) (xy 150.786072 -60.027841) (xy 150.801832 -60.02782)
			(xy 150.831775 -60.028149) (xy 150.891516 -60.032344) (xy 150.921212 -60.036202) (xy 150.926645 -60.036819)
			(xy 150.937541 -60.035916) (xy 150.942802 -60.034424) (xy 150.984607 -60.022329) (xy 151.069974 -60.005385)
			(xy 151.156588 -59.996862) (xy 151.200104 -59.996324) (xy 151.241943 -59.996835) (xy 151.325246 -60.004741)
			(xy 151.40744 -60.020426) (xy 151.447754 -60.03163) (xy 151.452605 -60.032865) (xy 151.462584 -60.033638)
			(xy 151.467566 -60.033154) (xy 151.491555 -60.030673) (xy 151.539715 -60.028007) (xy 151.563832 -60.02782)
			(xy 151.606191 -60.028361) (xy 151.690524 -60.036417) (xy 151.77371 -60.052453) (xy 151.854996 -60.076323)
			(xy 151.933644 -60.107811) (xy 152.008943 -60.146633) (xy 152.080211 -60.192436) (xy 152.146802 -60.244807)
			(xy 152.208114 -60.303269) (xy 152.263591 -60.367296) (xy 152.312731 -60.436305) (xy 152.355089 -60.509673)
			(xy 152.390281 -60.586735) (xy 152.417989 -60.666794) (xy 152.437961 -60.749123) (xy 152.450018 -60.832978)
			(xy 152.454049 -60.9176) (xy 152.450018 -61.002222) (xy 152.437961 -61.086077) (xy 152.417989 -61.168406)
			(xy 152.390281 -61.248465) (xy 152.355089 -61.325527) (xy 152.312731 -61.398895) (xy 152.263591 -61.467904)
			(xy 152.208114 -61.531931) (xy 152.146802 -61.590393) (xy 152.080211 -61.642764) (xy 152.008943 -61.688567)
			(xy 151.933644 -61.727389) (xy 151.854996 -61.758877) (xy 151.77371 -61.782747) (xy 151.690524 -61.798783)
			(xy 151.606191 -61.806839) (xy 151.563832 -61.807344) (xy 151.522302 -61.806838) (xy 151.439608 -61.799047)
			(xy 151.357999 -61.783584) (xy 151.31796 -61.772546) (xy 151.313172 -61.771327) (xy 151.303322 -61.770568)
			(xy 151.298402 -61.771022) (xy 151.273906 -61.773544) (xy 151.224729 -61.776215) (xy 151.200104 -61.776356)
			(xy 151.169652 -61.776085) (xy 151.108892 -61.771892) (xy 151.078692 -61.767974) (xy 151.073259 -61.767359)
			(xy 151.062363 -61.768262) (xy 151.057102 -61.769752) (xy 151.015613 -61.781676) (xy 150.930916 -61.798391)
			(xy 150.844997 -61.80681) (xy 150.801832 -61.807344) (xy 150.801578 -61.807344) (xy 150.761588 -61.806903)
			(xy 150.681934 -61.799687) (xy 150.603251 -61.785342) (xy 150.564596 -61.775086) (xy 150.557738 -61.773562)
			(xy 150.540558 -61.774847) (xy 150.506131 -61.776245) (xy 150.488904 -61.776356) (xy 150.446532 -61.775788)
			(xy 150.362173 -61.767733) (xy 150.278961 -61.751696) (xy 150.19765 -61.727821) (xy 150.118977 -61.696325)
			(xy 150.043654 -61.657494) (xy 149.972363 -61.611678) (xy 149.90575 -61.559294) (xy 149.844419 -61.500814)
			(xy 149.788924 -61.43677) (xy 149.739767 -61.36774) (xy 149.697396 -61.29435) (xy 149.662192 -61.217265)
			(xy 149.634475 -61.137183) (xy 149.614496 -61.054828) (xy 149.602436 -60.970947) (xy 149.598403 -60.8863)
			(xy 143.1544 -60.8863) (xy 143.1544 -61.919612) (xy 143.176752 -61.947298) (xy 143.194278 -61.951108)
			(xy 143.236229 -61.960819) (xy 143.318173 -61.987295) (xy 143.397174 -62.021568) (xy 143.472493 -62.063317)
			(xy 143.543424 -62.112149) (xy 143.609303 -62.167608) (xy 143.669514 -62.229175) (xy 143.723492 -62.296273)
			(xy 143.770733 -62.368274) (xy 143.810793 -62.444504) (xy 143.843298 -62.524249) (xy 143.867943 -62.606762)
			(xy 143.884498 -62.691271) (xy 143.892807 -62.776984) (xy 143.893286 -62.820042) (xy 143.892835 -62.859987)
			(xy 143.885642 -62.939553) (xy 143.871344 -63.018153) (xy 143.850056 -63.095155) (xy 143.821949 -63.169938)
			(xy 143.787251 -63.2419) (xy 143.746241 -63.310461) (xy 143.723106 -63.343028) (xy 143.717172 -63.351992)
			(xy 143.712701 -63.373) (xy 143.717172 -63.394008) (xy 143.723106 -63.402972) (xy 143.746258 -63.435528)
			(xy 143.787281 -63.504084) (xy 143.821987 -63.576045) (xy 143.850094 -63.65083) (xy 143.871376 -63.727836)
			(xy 143.885662 -63.806442) (xy 143.892835 -63.886012) (xy 143.893286 -63.925958) (xy 143.892778 -63.969013)
			(xy 143.884453 -64.05472) (xy 143.867886 -64.139221) (xy 143.843233 -64.221726) (xy 143.810723 -64.301464)
			(xy 143.770662 -64.377688) (xy 143.723424 -64.449684) (xy 143.669451 -64.51678) (xy 143.609247 -64.578347)
			(xy 143.543378 -64.63381) (xy 143.472457 -64.682649) (xy 143.39715 -64.724408) (xy 143.318161 -64.758695)
			(xy 143.236229 -64.78519) (xy 143.194278 -64.794892) (xy 143.176752 -64.798702) (xy 143.1544 -64.826388)
			(xy 143.1544 -66.756026) (xy 143.154893 -66.76603) (xy 143.162557 -66.784513) (xy 143.176709 -66.798658)
			(xy 143.195196 -66.806312) (xy 143.2052 -66.806826) (xy 145.801842 -66.806826)
		)
		(stroke
			(width 0)
			(type solid)
		)
		(fill yes)
		(layer "In3.Cu")
		(net "P52V_2")
	)
	(gr_poly
		(pts
			(xy 474.000068 -199.098154) (xy 474.055876 -199.097646) (xy 474.167179 -199.089307) (xy 474.277548 -199.072673)
			(xy 474.386365 -199.047838) (xy 474.493022 -199.01494) (xy 474.596923 -198.974164) (xy 474.697485 -198.925736)
			(xy 474.794147 -198.869929) (xy 474.886368 -198.807054) (xy 474.973633 -198.737463) (xy 475.055452 -198.661545)
			(xy 475.13137 -198.579725) (xy 475.20096 -198.49246) (xy 475.263834 -198.400239) (xy 475.319641 -198.303576)
			(xy 475.368068 -198.203014) (xy 475.408844 -198.099113) (xy 475.441741 -197.992456) (xy 475.466575 -197.883638)
			(xy 475.483208 -197.773269) (xy 475.491546 -197.661966) (xy 475.492064 -197.606158) (xy 475.492064 -135.770112)
			(xy 475.491555 -135.714305) (xy 475.483215 -135.603002) (xy 475.46658 -135.492634) (xy 475.441744 -135.383817)
			(xy 475.408845 -135.277161) (xy 475.368068 -135.173262) (xy 475.31964 -135.072701) (xy 475.263833 -134.97604)
			(xy 475.200958 -134.88382) (xy 475.131367 -134.796556) (xy 475.055449 -134.714737) (xy 474.973629 -134.63882)
			(xy 474.886364 -134.569231) (xy 474.794143 -134.506357) (xy 474.697481 -134.450551) (xy 474.596919 -134.402124)
			(xy 474.49302 -134.361348) (xy 474.386363 -134.328451) (xy 474.277546 -134.303616) (xy 474.167178 -134.286983)
			(xy 474.055875 -134.278644) (xy 474.000068 -134.278116) (xy 444.999872 -134.278116) (xy 444.929968 -134.278612)
			(xy 444.790381 -134.286463) (xy 444.651454 -134.302127) (xy 444.513624 -134.325555) (xy 444.377323 -134.356674)
			(xy 444.242982 -134.395385) (xy 444.111022 -134.441566) (xy 443.981859 -134.495074) (xy 443.855899 -134.555738)
			(xy 443.733538 -134.623368) (xy 443.615161 -134.697752) (xy 443.50114 -134.778656) (xy 443.391834 -134.865825)
			(xy 443.287587 -134.958985) (xy 443.188727 -135.057842) (xy 443.095565 -135.162087) (xy 443.008393 -135.27139)
			(xy 442.927487 -135.385409) (xy 442.8531 -135.503784) (xy 442.785466 -135.626144) (xy 442.724799 -135.752102)
			(xy 442.671289 -135.881264) (xy 442.625104 -136.013223) (xy 442.586389 -136.147563) (xy 442.555267 -136.283863)
			(xy 442.531836 -136.421693) (xy 442.516168 -136.56062) (xy 442.508314 -136.700206) (xy 442.507878 -136.77011)
			(xy 442.507878 -153.299922) (xy 442.507375 -153.422774) (xy 442.499335 -153.668345) (xy 442.483265 -153.913522)
			(xy 442.459181 -154.158042) (xy 442.42711 -154.401643) (xy 442.387085 -154.644065) (xy 442.33915 -154.885047)
			(xy 442.283356 -155.124331) (xy 442.219763 -155.361662) (xy 442.148438 -155.596785) (xy 442.069459 -155.829449)
			(xy 441.982909 -156.059404) (xy 441.888882 -156.286404) (xy 441.787478 -156.510205) (xy 441.678806 -156.73057)
			(xy 441.562982 -156.94726) (xy 441.44013 -157.160045) (xy 441.310381 -157.368697) (xy 441.173875 -157.572991)
			(xy 441.030758 -157.77271) (xy 440.881183 -157.967639) (xy 440.72531 -158.15757) (xy 440.563307 -158.342299)
			(xy 440.395346 -158.521628) (xy 440.221607 -158.695366) (xy 440.042277 -158.863327) (xy 439.857547 -159.02533)
			(xy 439.667615 -159.181202) (xy 439.472686 -159.330776) (xy 439.272966 -159.473893) (xy 439.068671 -159.610398)
			(xy 438.860019 -159.740145) (xy 438.647234 -159.862996) (xy 438.430543 -159.97882) (xy 438.210178 -160.087491)
			(xy 437.986376 -160.188894) (xy 437.759376 -160.28292) (xy 437.52942 -160.369469) (xy 437.296757 -160.448447)
			(xy 437.061633 -160.519771) (xy 436.824302 -160.583363) (xy 436.585017 -160.639156) (xy 436.344035 -160.68709)
			(xy 436.101614 -160.727114) (xy 435.858012 -160.759184) (xy 435.613492 -160.783267) (xy 435.368315 -160.799337)
			(xy 435.122744 -160.807376) (xy 434.999892 -160.807908) (xy 416.576256 -160.807908) (xy 416.506352 -160.808399)
			(xy 416.366764 -160.816241) (xy 416.227835 -160.831897) (xy 416.090003 -160.855317) (xy 415.9537 -160.88643)
			(xy 415.819357 -160.925136) (xy 415.687395 -160.971313) (xy 415.55823 -161.024817) (xy 415.432268 -161.085479)
			(xy 415.309905 -161.153108) (xy 415.191527 -161.227492) (xy 415.077506 -161.308396) (xy 414.968201 -161.395567)
			(xy 414.863955 -161.488728) (xy 414.765097 -161.587588) (xy 414.671937 -161.691836) (xy 414.584769 -161.801143)
			(xy 414.503867 -161.915166) (xy 414.429485 -162.033545) (xy 414.361858 -162.155909) (xy 414.301198 -162.281872)
			(xy 414.247697 -162.411038) (xy 414.201522 -162.543001) (xy 414.162818 -162.677345) (xy 414.131708 -162.813648)
			(xy 414.10829 -162.951481) (xy 414.092637 -163.09041) (xy 414.084798 -163.229998) (xy 414.084262 -163.299902)
			(xy 414.084262 -187.606178) (xy 414.083778 -187.676532) (xy 414.07589 -187.817019) (xy 414.060137 -187.956842)
			(xy 414.036568 -188.095562) (xy 414.005258 -188.232743) (xy 413.966306 -188.367952) (xy 413.919834 -188.500764)
			(xy 413.865987 -188.630762) (xy 413.804937 -188.757535) (xy 413.736874 -188.880686) (xy 413.662013 -188.999827)
			(xy 413.580589 -189.114583) (xy 413.492859 -189.224593) (xy 413.399098 -189.329511) (xy 413.299602 -189.429006)
			(xy 413.194684 -189.522766) (xy 413.084674 -189.610496) (xy 412.969917 -189.691919) (xy 412.850776 -189.76678)
			(xy 412.727625 -189.834842) (xy 412.600851 -189.895892) (xy 412.470853 -189.949738) (xy 412.33804 -189.99621)
			(xy 412.202831 -190.035161) (xy 412.065651 -190.06647) (xy 411.92693 -190.090038) (xy 411.787107 -190.105791)
			(xy 411.64662 -190.113679) (xy 411.576266 -190.114174) (xy 351.499932 -190.114174) (xy 351.429578 -190.113691)
			(xy 351.28909 -190.105803) (xy 351.149266 -190.09005) (xy 351.010545 -190.066482) (xy 350.873364 -190.035172)
			(xy 350.738154 -189.996221) (xy 350.605341 -189.949748) (xy 350.475343 -189.895903) (xy 350.348569 -189.834852)
			(xy 350.225417 -189.766789) (xy 350.106275 -189.691929) (xy 349.991518 -189.610505) (xy 349.881507 -189.522775)
			(xy 349.776589 -189.429014) (xy 349.677092 -189.329519) (xy 349.583332 -189.2246) (xy 349.495601 -189.11459)
			(xy 349.414177 -188.999833) (xy 349.339316 -188.880692) (xy 349.271252 -188.75754) (xy 349.210202 -188.630766)
			(xy 349.156355 -188.500768) (xy 349.109883 -188.367955) (xy 349.07093 -188.232746) (xy 349.03962 -188.095565)
			(xy 349.016052 -187.956844) (xy 349.000298 -187.81702) (xy 348.99241 -187.676532) (xy 348.991936 -187.606178)
			(xy 348.991936 -110.499906) (xy 348.991437 -110.399374) (xy 348.983341 -110.198474) (xy 348.967162 -109.998063)
			(xy 348.942927 -109.798466) (xy 348.910674 -109.600006) (xy 348.870457 -109.403006) (xy 348.822339 -109.207786)
			(xy 348.7664 -109.014661) (xy 348.702729 -108.823945) (xy 348.631431 -108.635948) (xy 348.552621 -108.450974)
			(xy 348.466427 -108.269323) (xy 348.372988 -108.09129) (xy 348.272456 -107.917165) (xy 348.164995 -107.747228)
			(xy 348.050777 -107.581757) (xy 347.92999 -107.421018) (xy 347.802828 -107.265274) (xy 347.669498 -107.114776)
			(xy 347.530217 -106.969769) (xy 347.385209 -106.830488) (xy 347.234711 -106.697159) (xy 347.078966 -106.569998)
			(xy 346.918227 -106.449211) (xy 346.752755 -106.334994) (xy 346.582818 -106.227533) (xy 346.408692 -106.127002)
			(xy 346.230659 -106.033564) (xy 346.049008 -105.947371) (xy 345.864034 -105.868561) (xy 345.676036 -105.797264)
			(xy 345.48532 -105.733594) (xy 345.292195 -105.677656) (xy 345.096974 -105.629539) (xy 344.899974 -105.589322)
			(xy 344.701514 -105.55707) (xy 344.501917 -105.532836) (xy 344.301506 -105.516658) (xy 344.100606 -105.508563)
			(xy 344.000074 -105.508044) (xy 293.310056 -105.508044) (xy 293.254251 -105.508567) (xy 293.142952 -105.516911)
			(xy 293.032588 -105.533549) (xy 292.923776 -105.558388) (xy 292.817125 -105.591289) (xy 292.713231 -105.632068)
			(xy 292.612674 -105.680497) (xy 292.516018 -105.736305) (xy 292.423802 -105.799181) (xy 292.336543 -105.868771)
			(xy 292.254729 -105.944688) (xy 292.178817 -106.026507) (xy 292.109231 -106.11377) (xy 292.046361 -106.205989)
			(xy 291.990558 -106.302648) (xy 291.942135 -106.403208) (xy 291.901361 -106.507104) (xy 291.868466 -106.613758)
			(xy 291.843634 -106.722571) (xy 291.827002 -106.832936) (xy 291.818664 -106.944235) (xy 291.81806 -107.00004)
			(xy 291.81806 -121.780046) (xy 291.817562 -121.863539) (xy 291.809615 -122.030336) (xy 291.793739 -122.196566)
			(xy 291.769973 -122.361852) (xy 291.738368 -122.52582) (xy 291.698998 -122.688098) (xy 291.65195 -122.848319)
			(xy 291.597333 -123.006121) (xy 291.535268 -123.161144) (xy 291.465898 -123.313039) (xy 291.389379 -123.461461)
			(xy 291.305884 -123.606075) (xy 291.215603 -123.746551) (xy 291.11874 -123.882573) (xy 291.015514 -124.013832)
			(xy 290.90616 -124.14003) (xy 290.790925 -124.260882) (xy 290.670071 -124.376114) (xy 290.54387 -124.485465)
			(xy 290.412609 -124.588688) (xy 290.276585 -124.685548) (xy 290.136106 -124.775826) (xy 289.991491 -124.859317)
			(xy 289.843067 -124.935833) (xy 289.691171 -125.0052) (xy 289.536146 -125.067261) (xy 289.378343 -125.121875)
			(xy 289.218121 -125.168919) (xy 289.055841 -125.208285) (xy 288.891873 -125.239886) (xy 288.726586 -125.263649)
			(xy 288.560356 -125.27952) (xy 288.393559 -125.287464) (xy 288.310066 -125.28804) (xy 139.910058 -125.28804)
			(xy 139.826564 -125.287542) (xy 139.659766 -125.279595) (xy 139.493535 -125.26372) (xy 139.328247 -125.239954)
			(xy 139.164277 -125.20835) (xy 139.001997 -125.168979) (xy 138.841774 -125.121932) (xy 138.683971 -125.067315)
			(xy 138.528946 -125.005251) (xy 138.377049 -124.935881) (xy 138.228625 -124.859362) (xy 138.08401 -124.775868)
			(xy 137.943531 -124.685588) (xy 137.807507 -124.588725) (xy 137.676246 -124.4855) (xy 137.550046 -124.376146)
			(xy 137.429191 -124.260912) (xy 137.313956 -124.140057) (xy 137.204603 -124.013857) (xy 137.101377 -123.882596)
			(xy 137.004515 -123.746572) (xy 136.914234 -123.606094) (xy 136.830739 -123.461479) (xy 136.75422 -123.313055)
			(xy 136.68485 -123.161158) (xy 136.622786 -123.006132) (xy 136.568169 -122.848329) (xy 136.521122 -122.688106)
			(xy 136.481751 -122.525826) (xy 136.450147 -122.361857) (xy 136.42638 -122.196569) (xy 136.410505 -122.030338)
			(xy 136.402558 -121.86354) (xy 136.402064 -121.780046) (xy 136.402064 -107.00004) (xy 136.401556 -106.944232)
			(xy 136.393218 -106.832928) (xy 136.376585 -106.722558) (xy 136.35175 -106.61374) (xy 136.318853 -106.507082)
			(xy 136.278076 -106.403181) (xy 136.229649 -106.302618) (xy 136.173842 -106.205955) (xy 136.110967 -106.113733)
			(xy 136.041377 -106.026468) (xy 135.965459 -105.944647) (xy 135.883638 -105.868729) (xy 135.796373 -105.799137)
			(xy 135.704152 -105.736262) (xy 135.607489 -105.680455) (xy 135.506926 -105.632027) (xy 135.403025 -105.59125)
			(xy 135.296368 -105.558352) (xy 135.18755 -105.533517) (xy 135.07718 -105.516883) (xy 134.965876 -105.508544)
			(xy 134.910068 -105.508044) (xy 95.999808 -105.508044) (xy 95.899276 -105.508543) (xy 95.698376 -105.516639)
			(xy 95.497964 -105.532817) (xy 95.298366 -105.557053) (xy 95.099907 -105.589305) (xy 94.902906 -105.629523)
			(xy 94.707685 -105.67764) (xy 94.51456 -105.73358) (xy 94.323844 -105.79725) (xy 94.135846 -105.868548)
			(xy 93.950872 -105.947358) (xy 93.769221 -106.033552) (xy 93.591188 -106.126991) (xy 93.417061 -106.227522)
			(xy 93.247124 -106.334984) (xy 93.081652 -106.449201) (xy 92.920913 -106.569988) (xy 92.765169 -106.69715)
			(xy 92.61467 -106.83048) (xy 92.469663 -106.969761) (xy 92.330381 -107.114769) (xy 92.197051 -107.265267)
			(xy 92.06989 -107.421012) (xy 91.949102 -107.581751) (xy 91.834885 -107.747223) (xy 91.727424 -107.91716)
			(xy 91.626892 -108.091286) (xy 91.533453 -108.269319) (xy 91.447259 -108.45097) (xy 91.368448 -108.635944)
			(xy 91.29715 -108.823942) (xy 91.23348 -109.014658) (xy 91.177541 -109.207783) (xy 91.129423 -109.403004)
			(xy 91.089206 -109.600005) (xy 91.056953 -109.798465) (xy 91.032718 -109.998062) (xy 91.016539 -110.198474)
			(xy 91.008443 -110.399374) (xy 91.007946 -110.499906) (xy 91.007946 -187.606178) (xy 91.007462 -187.676532)
			(xy 90.999574 -187.817018) (xy 90.983821 -187.956841) (xy 90.960252 -188.095561) (xy 90.928942 -188.232741)
			(xy 90.88999 -188.36795) (xy 90.843517 -188.500762) (xy 90.789671 -188.630759) (xy 90.72862 -188.757532)
			(xy 90.660557 -188.880683) (xy 90.585696 -188.999823) (xy 90.504272 -189.114579) (xy 90.416542 -189.224588)
			(xy 90.322781 -189.329506) (xy 90.223285 -189.429) (xy 90.118367 -189.52276) (xy 90.008357 -189.610489)
			(xy 89.8936 -189.691911) (xy 89.774459 -189.766771) (xy 89.651307 -189.834833) (xy 89.524533 -189.895882)
			(xy 89.394536 -189.949727) (xy 89.261723 -189.996198) (xy 89.126514 -190.035149) (xy 88.989334 -190.066457)
			(xy 88.850614 -190.090024) (xy 88.71079 -190.105776) (xy 88.570304 -190.113663) (xy 88.49995 -190.114174)
			(xy 28.42387 -190.114174) (xy 28.353517 -190.11368) (xy 28.213033 -190.105789) (xy 28.073211 -190.090033)
			(xy 27.934494 -190.066462) (xy 27.797316 -190.035151) (xy 27.66211 -189.996197) (xy 27.5293 -189.949723)
			(xy 27.399305 -189.895876) (xy 27.272534 -189.834824) (xy 27.149386 -189.766761) (xy 27.030248 -189.691899)
			(xy 26.915494 -189.610476) (xy 26.805487 -189.522746) (xy 26.700572 -189.428986) (xy 26.601078 -189.329491)
			(xy 26.507321 -189.224573) (xy 26.419593 -189.114564) (xy 26.338172 -188.999809) (xy 26.263313 -188.880669)
			(xy 26.195252 -188.757519) (xy 26.134203 -188.630747) (xy 26.080358 -188.500751) (xy 26.033887 -188.367941)
			(xy 25.994936 -188.232734) (xy 25.963628 -188.095555) (xy 25.94006 -187.956837) (xy 25.924307 -187.817016)
			(xy 25.916419 -187.676531) (xy 25.915874 -187.606178) (xy 25.915874 -163.299902) (xy 25.915393 -163.229997)
			(xy 25.907553 -163.090407) (xy 25.8919 -162.951476) (xy 25.868481 -162.813642) (xy 25.83737 -162.677337)
			(xy 25.798666 -162.542992) (xy 25.752489 -162.411028) (xy 25.698986 -162.28186) (xy 25.638325 -162.155896)
			(xy 25.570696 -162.033531) (xy 25.496312 -161.915151) (xy 25.415408 -161.801128) (xy 25.328237 -161.69182)
			(xy 25.235075 -161.587572) (xy 25.136214 -161.488712) (xy 25.031966 -161.395551) (xy 24.922658 -161.308381)
			(xy 24.808634 -161.227478) (xy 24.690253 -161.153095) (xy 24.567888 -161.085467) (xy 24.441923 -161.024807)
			(xy 24.312756 -160.971304) (xy 24.180791 -160.925129) (xy 24.046445 -160.886426) (xy 23.91014 -160.855316)
			(xy 23.772306 -160.831898) (xy 23.633375 -160.816245) (xy 23.493785 -160.808407) (xy 23.42388 -160.807908)
			(xy 1.999996 -160.807908) (xy 1.944189 -160.80843) (xy 1.832887 -160.816771) (xy 1.72252 -160.833407)
			(xy 1.613705 -160.858243) (xy 1.50705 -160.891142) (xy 1.403152 -160.93192) (xy 1.302591 -160.980347)
			(xy 1.205931 -161.036154) (xy 1.113712 -161.099029) (xy 1.026449 -161.168619) (xy 0.94463 -161.244536)
			(xy 0.868714 -161.326355) (xy 0.799124 -161.413618) (xy 0.73625 -161.505838) (xy 0.680444 -161.602499)
			(xy 0.632016 -161.703059) (xy 0.59124 -161.806958) (xy 0.558341 -161.913613) (xy 0.533505 -162.022428)
			(xy 0.51687 -162.132795) (xy 0.50853 -162.244097) (xy 0.508 -162.299904) (xy 0.508 -194.670734) (xy 2.904225 -194.670734)
			(xy 2.904225 -194.541594) (xy 2.912175 -194.412699) (xy 2.928045 -194.284539) (xy 2.951774 -194.157598)
			(xy 2.983273 -194.032359) (xy 3.022422 -193.909296) (xy 3.069073 -193.788877) (xy 3.123048 -193.671558)
			(xy 3.184143 -193.557784) (xy 3.252126 -193.447987) (xy 3.32674 -193.342584) (xy 3.407701 -193.241974)
			(xy 3.494701 -193.146539) (xy 3.587412 -193.05664) (xy 3.685482 -192.972619) (xy 3.788537 -192.894795)
			(xy 3.896188 -192.823463) (xy 4.008027 -192.758893) (xy 4.123628 -192.701331) (xy 4.242553 -192.650994)
			(xy 4.364352 -192.608074) (xy 4.488562 -192.572733) (xy 4.614711 -192.545106) (xy 4.742323 -192.525297)
			(xy 4.870912 -192.513381) (xy 4.99999 -192.509405) (xy 5.129068 -192.513381) (xy 5.257657 -192.525297)
			(xy 5.385269 -192.545106) (xy 5.511418 -192.572733) (xy 5.635628 -192.608074) (xy 5.757427 -192.650994)
			(xy 5.876352 -192.701331) (xy 5.991953 -192.758893) (xy 6.103792 -192.823463) (xy 6.211443 -192.894795)
			(xy 6.314498 -192.972619) (xy 6.412568 -193.05664) (xy 6.505279 -193.146539) (xy 6.592279 -193.241974)
			(xy 6.67324 -193.342584) (xy 6.747854 -193.447987) (xy 6.815837 -193.557784) (xy 6.876932 -193.671558)
			(xy 6.930907 -193.788877) (xy 6.977558 -193.909296) (xy 7.016707 -194.032359) (xy 7.048206 -194.157598)
			(xy 7.071935 -194.284539) (xy 7.087805 -194.412699) (xy 7.095755 -194.541594) (xy 7.096252 -194.606164)
			(xy 7.095755 -194.670734) (xy 468.904309 -194.670734) (xy 468.904309 -194.541594) (xy 468.912259 -194.412699)
			(xy 468.928129 -194.284539) (xy 468.951858 -194.157598) (xy 468.983357 -194.032359) (xy 469.022506 -193.909296)
			(xy 469.069157 -193.788877) (xy 469.123132 -193.671558) (xy 469.184227 -193.557784) (xy 469.25221 -193.447987)
			(xy 469.326824 -193.342584) (xy 469.407785 -193.241974) (xy 469.494785 -193.146539) (xy 469.587496 -193.05664)
			(xy 469.685566 -192.972619) (xy 469.788621 -192.894795) (xy 469.896272 -192.823463) (xy 470.008111 -192.758893)
			(xy 470.123712 -192.701331) (xy 470.242637 -192.650994) (xy 470.364436 -192.608074) (xy 470.488646 -192.572733)
			(xy 470.614795 -192.545106) (xy 470.742407 -192.525297) (xy 470.870996 -192.513381) (xy 471.000074 -192.509405)
			(xy 471.129152 -192.513381) (xy 471.257741 -192.525297) (xy 471.385353 -192.545106) (xy 471.511502 -192.572733)
			(xy 471.635712 -192.608074) (xy 471.757511 -192.650994) (xy 471.876436 -192.701331) (xy 471.992037 -192.758893)
			(xy 472.103876 -192.823463) (xy 472.211527 -192.894795) (xy 472.314582 -192.972619) (xy 472.412652 -193.05664)
			(xy 472.505363 -193.146539) (xy 472.592363 -193.241974) (xy 472.673324 -193.342584) (xy 472.747938 -193.447987)
			(xy 472.815921 -193.557784) (xy 472.877016 -193.671558) (xy 472.930991 -193.788877) (xy 472.977642 -193.909296)
			(xy 473.016791 -194.032359) (xy 473.04829 -194.157598) (xy 473.072019 -194.284539) (xy 473.087889 -194.412699)
			(xy 473.095839 -194.541594) (xy 473.096336 -194.606164) (xy 473.095839 -194.670734) (xy 473.087889 -194.799629)
			(xy 473.072019 -194.927789) (xy 473.04829 -195.05473) (xy 473.016791 -195.179969) (xy 472.977642 -195.303032)
			(xy 472.930991 -195.423451) (xy 472.877016 -195.54077) (xy 472.815921 -195.654544) (xy 472.747938 -195.764341)
			(xy 472.673324 -195.869744) (xy 472.592363 -195.970354) (xy 472.505363 -196.065789) (xy 472.412652 -196.155688)
			(xy 472.314582 -196.239709) (xy 472.211527 -196.317533) (xy 472.103876 -196.388865) (xy 471.992037 -196.453435)
			(xy 471.876436 -196.510997) (xy 471.757511 -196.561334) (xy 471.635712 -196.604254) (xy 471.511502 -196.639595)
			(xy 471.385353 -196.667222) (xy 471.257741 -196.687031) (xy 471.129152 -196.698947) (xy 471.000074 -196.702924)
			(xy 470.870996 -196.698947) (xy 470.742407 -196.687031) (xy 470.614795 -196.667222) (xy 470.488646 -196.639595)
			(xy 470.364436 -196.604254) (xy 470.242637 -196.561334) (xy 470.123712 -196.510997) (xy 470.008111 -196.453435)
			(xy 469.896272 -196.388865) (xy 469.788621 -196.317533) (xy 469.685566 -196.239709) (xy 469.587496 -196.155688)
			(xy 469.494785 -196.065789) (xy 469.407785 -195.970354) (xy 469.326824 -195.869744) (xy 469.25221 -195.764341)
			(xy 469.184227 -195.654544) (xy 469.123132 -195.54077) (xy 469.069157 -195.423451) (xy 469.022506 -195.303032)
			(xy 468.983357 -195.179969) (xy 468.951858 -195.05473) (xy 468.928129 -194.927789) (xy 468.912259 -194.799629)
			(xy 468.904309 -194.670734) (xy 7.095755 -194.670734) (xy 7.087805 -194.799629) (xy 7.071935 -194.927789)
			(xy 7.048206 -195.05473) (xy 7.016707 -195.179969) (xy 6.977558 -195.303032) (xy 6.930907 -195.423451)
			(xy 6.876932 -195.54077) (xy 6.815837 -195.654544) (xy 6.747854 -195.764341) (xy 6.67324 -195.869744)
			(xy 6.592279 -195.970354) (xy 6.505279 -196.065789) (xy 6.412568 -196.155688) (xy 6.314498 -196.239709)
			(xy 6.211443 -196.317533) (xy 6.103792 -196.388865) (xy 5.991953 -196.453435) (xy 5.876352 -196.510997)
			(xy 5.757427 -196.561334) (xy 5.635628 -196.604254) (xy 5.511418 -196.639595) (xy 5.385269 -196.667222)
			(xy 5.257657 -196.687031) (xy 5.129068 -196.698947) (xy 4.99999 -196.702924) (xy 4.870912 -196.698947)
			(xy 4.742323 -196.687031) (xy 4.614711 -196.667222) (xy 4.488562 -196.639595) (xy 4.364352 -196.604254)
			(xy 4.242553 -196.561334) (xy 4.123628 -196.510997) (xy 4.008027 -196.453435) (xy 3.896188 -196.388865)
			(xy 3.788537 -196.317533) (xy 3.685482 -196.239709) (xy 3.587412 -196.155688) (xy 3.494701 -196.065789)
			(xy 3.407701 -195.970354) (xy 3.32674 -195.869744) (xy 3.252126 -195.764341) (xy 3.184143 -195.654544)
			(xy 3.123048 -195.54077) (xy 3.069073 -195.423451) (xy 3.022422 -195.303032) (xy 2.983273 -195.179969)
			(xy 2.951774 -195.05473) (xy 2.928045 -194.927789) (xy 2.912175 -194.799629) (xy 2.904225 -194.670734)
			(xy 0.508 -194.670734) (xy 0.508 -197.606158) (xy 0.508522 -197.661965) (xy 0.516863 -197.773267)
			(xy 0.533498 -197.883634) (xy 0.558335 -197.99245) (xy 0.591234 -198.099105) (xy 0.632011 -198.203004)
			(xy 0.680438 -198.303564) (xy 0.736246 -198.400225) (xy 0.79912 -198.492445) (xy 0.86871 -198.579708)
			(xy 0.944627 -198.661527) (xy 1.026446 -198.737444) (xy 1.113709 -198.807034) (xy 1.205929 -198.869908)
			(xy 1.30259 -198.925716) (xy 1.40315 -198.974143) (xy 1.507049 -199.01492) (xy 1.613704 -199.047819)
			(xy 1.72252 -199.072656) (xy 1.832887 -199.089291) (xy 1.944189 -199.097632) (xy 1.999996 -199.098154)
		)
		(stroke
			(width 0)
			(type solid)
		)
		(fill yes)
		(layer "In3.Cu")
		(net "GND3")
	)
	(gr_poly
		(pts
			(xy 75.000104 -171.140882) (xy 75.095437 -171.140376) (xy 75.285932 -171.132284) (xy 75.475912 -171.116114)
			(xy 75.665035 -171.091896) (xy 75.852959 -171.059673) (xy 76.039346 -171.019503) (xy 76.223861 -170.971459)
			(xy 76.40617 -170.915628) (xy 76.585945 -170.852109) (xy 76.762863 -170.781017) (xy 76.936604 -170.702482)
			(xy 77.106855 -170.616643) (xy 77.27331 -170.523655) (xy 77.435668 -170.423687) (xy 77.593638 -170.316919)
			(xy 77.746933 -170.203542) (xy 77.895279 -170.083761) (xy 78.038407 -169.957793) (xy 78.17606 -169.825863)
			(xy 78.30799 -169.68821) (xy 78.433959 -169.545082) (xy 78.55374 -169.396736) (xy 78.667117 -169.243441)
			(xy 78.773885 -169.085472) (xy 78.873853 -168.923113) (xy 78.966841 -168.756659) (xy 79.05268 -168.586408)
			(xy 79.131216 -168.412667) (xy 79.202307 -168.235749) (xy 79.265826 -168.055974) (xy 79.321658 -167.873665)
			(xy 79.369702 -167.68915) (xy 79.409872 -167.502763) (xy 79.442095 -167.314839) (xy 79.466314 -167.125716)
			(xy 79.482484 -166.935736) (xy 79.490576 -166.745241) (xy 79.491078 -166.649908) (xy 79.491078 -161.28111)
			(xy 79.497763 -161.194561) (xy 79.518105 -161.022146) (xy 79.546364 -160.850851) (xy 79.582482 -160.681039)
			(xy 79.626381 -160.51307) (xy 79.677968 -160.347301) (xy 79.737135 -160.184083) (xy 79.803755 -160.023764)
			(xy 79.877687 -159.866682) (xy 79.958774 -159.713171) (xy 80.046845 -159.563557) (xy 80.141711 -159.418158)
			(xy 80.243173 -159.277281) (xy 80.351014 -159.141227) (xy 80.465007 -159.010282) (xy 80.584908 -158.884726)
			(xy 80.710464 -158.764825) (xy 80.841408 -158.650833) (xy 80.977463 -158.542992) (xy 81.11834 -158.44153)
			(xy 81.263739 -158.346663) (xy 81.413353 -158.258593) (xy 81.566864 -158.177506) (xy 81.723946 -158.103574)
			(xy 81.884265 -158.036954) (xy 82.047483 -157.977788) (xy 82.213252 -157.9262) (xy 82.381221 -157.882301)
			(xy 82.551033 -157.846184) (xy 82.722328 -157.817924) (xy 82.894743 -157.797583) (xy 82.981292 -157.790896)
			(xy 83.49996 -157.790896) (xy 83.595294 -157.790398) (xy 83.785791 -157.782307) (xy 83.975773 -157.766139)
			(xy 84.164897 -157.741923) (xy 84.352823 -157.709701) (xy 84.539213 -157.669533) (xy 84.723729 -157.62149)
			(xy 84.90604 -157.565659) (xy 85.085818 -157.502142) (xy 85.262738 -157.431051) (xy 85.436481 -157.352516)
			(xy 85.606734 -157.266677) (xy 85.773191 -157.173691) (xy 85.935552 -157.073723) (xy 86.093523 -156.966955)
			(xy 86.246821 -156.853578) (xy 86.395169 -156.733797) (xy 86.538299 -156.607828) (xy 86.675955 -156.475898)
			(xy 86.807886 -156.338245) (xy 86.933857 -156.195116) (xy 87.05364 -156.04677) (xy 87.167019 -155.893474)
			(xy 87.273789 -155.735504) (xy 87.373759 -155.573145) (xy 87.466748 -155.406689) (xy 87.552589 -155.236437)
			(xy 87.631127 -155.062695) (xy 87.70222 -154.885776) (xy 87.76574 -154.705999) (xy 87.821573 -154.523689)
			(xy 87.869618 -154.339173) (xy 87.909789 -154.152784) (xy 87.942013 -153.964858) (xy 87.966233 -153.775734)
			(xy 87.982404 -153.585753) (xy 87.990497 -153.395256) (xy 87.990934 -153.299922) (xy 87.990934 -110.499906)
			(xy 87.991432 -110.374101) (xy 87.999343 -110.122617) (xy 88.015149 -109.871504) (xy 88.038834 -109.621013)
			(xy 88.070376 -109.371388) (xy 88.109743 -109.122878) (xy 88.156896 -108.875727) (xy 88.211788 -108.630178)
			(xy 88.274366 -108.386475) (xy 88.344568 -108.144858) (xy 88.422324 -107.905565) (xy 88.507557 -107.668832)
			(xy 88.600185 -107.434893) (xy 88.700114 -107.203979) (xy 88.807248 -106.976318) (xy 88.921479 -106.752134)
			(xy 89.042695 -106.531649) (xy 89.170776 -106.315079) (xy 89.305597 -106.10264) (xy 89.447024 -105.89454)
			(xy 89.594918 -105.690985) (xy 89.749132 -105.492175) (xy 89.909514 -105.298308) (xy 90.075907 -105.109574)
			(xy 90.248145 -104.926159) (xy 90.42606 -104.748244) (xy 90.609475 -104.576006) (xy 90.798209 -104.409613)
			(xy 90.992077 -104.249231) (xy 91.190887 -104.095017) (xy 91.394442 -103.947123) (xy 91.602542 -103.805696)
			(xy 91.814981 -103.670875) (xy 92.03155 -103.542794) (xy 92.252036 -103.421578) (xy 92.47622 -103.307347)
			(xy 92.703881 -103.200214) (xy 92.934795 -103.100284) (xy 93.168734 -103.007657) (xy 93.405467 -102.922423)
			(xy 93.64476 -102.844667) (xy 93.886377 -102.774465) (xy 94.13008 -102.711888) (xy 94.375628 -102.656995)
			(xy 94.62278 -102.609842) (xy 94.87129 -102.570476) (xy 95.120915 -102.538934) (xy 95.371406 -102.515249)
			(xy 95.622519 -102.499443) (xy 95.874003 -102.491532) (xy 95.999808 -102.491032) (xy 318.10579 -102.491032)
			(xy 318.106806 -102.492048) (xy 319.051686 -102.492048) (xy 319.052702 -102.491032) (xy 344.000074 -102.491032)
			(xy 344.12588 -102.491521) (xy 344.377368 -102.499423) (xy 344.628483 -102.515221) (xy 344.878979 -102.538899)
			(xy 345.128607 -102.570434) (xy 345.377121 -102.609794) (xy 345.624276 -102.656941) (xy 345.869829 -102.711827)
			(xy 346.113536 -102.7744) (xy 346.355158 -102.844597) (xy 346.594455 -102.922349) (xy 346.831192 -103.007579)
			(xy 347.065135 -103.100203) (xy 347.296054 -103.20013) (xy 347.523719 -103.30726) (xy 347.747907 -103.421489)
			(xy 347.968397 -103.542704) (xy 348.18497 -103.670784) (xy 348.397413 -103.805604) (xy 348.605517 -103.947031)
			(xy 348.809076 -104.094924) (xy 349.007888 -104.249139) (xy 349.201759 -104.409522) (xy 349.36105 -104.549956)
			(xy 422.484046 -104.549956) (xy 422.488076 -104.407621) (xy 422.500151 -104.265741) (xy 422.520234 -104.124773)
			(xy 422.548261 -103.985166) (xy 422.584141 -103.847368) (xy 422.627759 -103.711821) (xy 422.678976 -103.578959)
			(xy 422.737627 -103.449207) (xy 422.803525 -103.322981) (xy 422.876459 -103.200685) (xy 422.956196 -103.082712)
			(xy 423.042478 -102.969439) (xy 423.135031 -102.861228) (xy 423.233558 -102.758427) (xy 423.337743 -102.661365)
			(xy 423.447252 -102.570353) (xy 423.561735 -102.485681) (xy 423.680825 -102.407623) (xy 423.80414 -102.336427)
			(xy 423.931286 -102.272321) (xy 424.061855 -102.215512) (xy 424.195429 -102.16618) (xy 424.33158 -102.124484)
			(xy 424.469871 -102.090558) (xy 424.609861 -102.06451) (xy 424.7511 -102.046424) (xy 424.893136 -102.036357)
			(xy 425.035514 -102.034342) (xy 425.177778 -102.040385) (xy 425.319472 -102.054467) (xy 425.460142 -102.076543)
			(xy 425.599339 -102.106543) (xy 425.736615 -102.144369) (xy 425.871531 -102.189901) (xy 426.003655 -102.242992)
			(xy 426.132564 -102.303474) (xy 426.257845 -102.371152) (xy 426.379096 -102.445809) (xy 426.495929 -102.527207)
			(xy 426.60797 -102.615084) (xy 426.71486 -102.709159) (xy 426.816257 -102.809131) (xy 426.911835 -102.914679)
			(xy 427.001289 -103.025465) (xy 427.084331 -103.141134) (xy 427.160697 -103.261317) (xy 427.230141 -103.385627)
			(xy 427.292441 -103.513668) (xy 427.347397 -103.645027) (xy 427.394834 -103.779286) (xy 427.434598 -103.916013)
			(xy 427.466564 -104.054771) (xy 427.490629 -104.195115) (xy 427.506715 -104.336596) (xy 427.51477 -104.47876)
			(xy 427.515274 -104.549956) (xy 427.51477 -104.621152) (xy 427.506715 -104.763316) (xy 427.490629 -104.904797)
			(xy 427.466564 -105.045141) (xy 427.434598 -105.183899) (xy 427.394834 -105.320626) (xy 427.347397 -105.454885)
			(xy 427.292441 -105.586244) (xy 427.230141 -105.714285) (xy 427.160697 -105.838595) (xy 427.084331 -105.958778)
			(xy 427.001289 -106.074447) (xy 426.911835 -106.185233) (xy 426.816257 -106.290781) (xy 426.71486 -106.390753)
			(xy 426.60797 -106.484828) (xy 426.495929 -106.572705) (xy 426.379096 -106.654103) (xy 426.257845 -106.72876)
			(xy 426.132564 -106.796438) (xy 426.003655 -106.85692) (xy 425.871531 -106.910011) (xy 425.736615 -106.955543)
			(xy 425.599339 -106.993369) (xy 425.460142 -107.023369) (xy 425.319472 -107.045445) (xy 425.177778 -107.059527)
			(xy 425.035514 -107.06557) (xy 424.893136 -107.063555) (xy 424.7511 -107.053488) (xy 424.609861 -107.035402)
			(xy 424.469871 -107.009354) (xy 424.33158 -106.975428) (xy 424.195429 -106.933732) (xy 424.061855 -106.8844)
			(xy 423.931286 -106.827591) (xy 423.80414 -106.763485) (xy 423.680825 -106.692289) (xy 423.561735 -106.614231)
			(xy 423.447252 -106.529559) (xy 423.337743 -106.438547) (xy 423.233558 -106.341485) (xy 423.135031 -106.238684)
			(xy 423.042478 -106.130473) (xy 422.956196 -106.0172) (xy 422.876459 -105.899227) (xy 422.803525 -105.776931)
			(xy 422.737627 -105.650705) (xy 422.678976 -105.520953) (xy 422.627759 -105.388091) (xy 422.584141 -105.252544)
			(xy 422.548261 -105.114746) (xy 422.520234 -104.975139) (xy 422.500151 -104.834171) (xy 422.488076 -104.692291)
			(xy 422.484046 -104.549956) (xy 349.36105 -104.549956) (xy 349.390496 -104.575916) (xy 349.573914 -104.748156)
			(xy 349.75183 -104.926072) (xy 349.924071 -105.109489) (xy 350.090465 -105.298226) (xy 350.250849 -105.492096)
			(xy 350.405064 -105.690908) (xy 350.552958 -105.894467) (xy 350.694385 -106.10257) (xy 350.829205 -106.315013)
			(xy 350.957286 -106.531586) (xy 351.078501 -106.752075) (xy 351.192731 -106.976263) (xy 351.299862 -107.203928)
			(xy 351.399789 -107.434846) (xy 351.492414 -107.668789) (xy 351.577645 -107.905526) (xy 351.655397 -108.144823)
			(xy 351.725595 -108.386444) (xy 351.788168 -108.630152) (xy 351.843055 -108.875704) (xy 351.890203 -109.122859)
			(xy 351.929563 -109.371373) (xy 351.961098 -109.621001) (xy 351.984777 -109.871497) (xy 352.000576 -110.122612)
			(xy 352.008479 -110.3741) (xy 352.008948 -110.499906) (xy 352.008948 -111.879888) (xy 377.061232 -111.879888)
			(xy 377.065214 -111.789938) (xy 377.077131 -111.700691) (xy 377.096889 -111.612847) (xy 377.124333 -111.527093)
			(xy 377.159249 -111.4441) (xy 377.201363 -111.364518) (xy 377.250346 -111.288969) (xy 377.305814 -111.218045)
			(xy 377.367334 -111.1523) (xy 377.434423 -111.09225) (xy 377.506557 -111.038365) (xy 377.583171 -110.991065)
			(xy 377.663665 -110.950722) (xy 377.74741 -110.91765) (xy 377.833751 -110.89211) (xy 377.92201 -110.8743)
			(xy 378.011499 -110.86436) (xy 378.101515 -110.862369) (xy 378.191356 -110.86834) (xy 378.280317 -110.882229)
			(xy 378.367702 -110.903925) (xy 378.452828 -110.93326) (xy 378.535028 -110.970003) (xy 378.613659 -111.013867)
			(xy 378.688106 -111.064509) (xy 378.757786 -111.121533) (xy 378.822153 -111.184492) (xy 378.880704 -111.252893)
			(xy 378.932981 -111.326201) (xy 378.978574 -111.403843) (xy 379.017127 -111.48521) (xy 379.048338 -111.569666)
			(xy 379.071962 -111.65655) (xy 379.087815 -111.745182) (xy 379.095772 -111.834869) (xy 379.09627 -111.879888)
			(xy 396.619232 -111.879888) (xy 396.623214 -111.789938) (xy 396.635131 -111.700691) (xy 396.654889 -111.612847)
			(xy 396.682333 -111.527093) (xy 396.717249 -111.4441) (xy 396.759363 -111.364518) (xy 396.808346 -111.288969)
			(xy 396.863814 -111.218045) (xy 396.925334 -111.1523) (xy 396.992423 -111.09225) (xy 397.064557 -111.038365)
			(xy 397.141171 -110.991065) (xy 397.221665 -110.950722) (xy 397.30541 -110.91765) (xy 397.391751 -110.89211)
			(xy 397.48001 -110.8743) (xy 397.569499 -110.86436) (xy 397.659515 -110.862369) (xy 397.749356 -110.86834)
			(xy 397.838317 -110.882229) (xy 397.925702 -110.903925) (xy 398.010828 -110.93326) (xy 398.093028 -110.970003)
			(xy 398.171659 -111.013867) (xy 398.246106 -111.064509) (xy 398.315786 -111.121533) (xy 398.380153 -111.184492)
			(xy 398.438704 -111.252893) (xy 398.490981 -111.326201) (xy 398.536574 -111.403843) (xy 398.575127 -111.48521)
			(xy 398.606338 -111.569666) (xy 398.629962 -111.65655) (xy 398.645815 -111.745182) (xy 398.653772 -111.834869)
			(xy 398.65427 -111.879888) (xy 398.653772 -111.924907) (xy 398.645815 -112.014594) (xy 398.629962 -112.103226)
			(xy 398.606338 -112.19011) (xy 398.575127 -112.274566) (xy 398.536574 -112.355933) (xy 398.490981 -112.433575)
			(xy 398.438704 -112.506883) (xy 398.380153 -112.575284) (xy 398.315786 -112.638243) (xy 398.246106 -112.695267)
			(xy 398.171659 -112.745909) (xy 398.093028 -112.789773) (xy 398.010828 -112.826516) (xy 397.925702 -112.855851)
			(xy 397.838317 -112.877547) (xy 397.749356 -112.891436) (xy 397.659515 -112.897407) (xy 397.569499 -112.895416)
			(xy 397.48001 -112.885476) (xy 397.391751 -112.867666) (xy 397.30541 -112.842126) (xy 397.221665 -112.809054)
			(xy 397.141171 -112.768711) (xy 397.064557 -112.721411) (xy 396.992423 -112.667526) (xy 396.925334 -112.607476)
			(xy 396.863814 -112.541731) (xy 396.808346 -112.470807) (xy 396.759363 -112.395258) (xy 396.717249 -112.315676)
			(xy 396.682333 -112.232683) (xy 396.654889 -112.146929) (xy 396.635131 -112.059085) (xy 396.623214 -111.969838)
			(xy 396.619232 -111.879888) (xy 379.09627 -111.879888) (xy 379.095772 -111.924907) (xy 379.087815 -112.014594)
			(xy 379.071962 -112.103226) (xy 379.048338 -112.19011) (xy 379.017127 -112.274566) (xy 378.978574 -112.355933)
			(xy 378.932981 -112.433575) (xy 378.880704 -112.506883) (xy 378.822153 -112.575284) (xy 378.757786 -112.638243)
			(xy 378.688106 -112.695267) (xy 378.613659 -112.745909) (xy 378.535028 -112.789773) (xy 378.452828 -112.826516)
			(xy 378.367702 -112.855851) (xy 378.280317 -112.877547) (xy 378.191356 -112.891436) (xy 378.101515 -112.897407)
			(xy 378.011499 -112.895416) (xy 377.92201 -112.885476) (xy 377.833751 -112.867666) (xy 377.74741 -112.842126)
			(xy 377.663665 -112.809054) (xy 377.583171 -112.768711) (xy 377.506557 -112.721411) (xy 377.434423 -112.667526)
			(xy 377.367334 -112.607476) (xy 377.305814 -112.541731) (xy 377.250346 -112.470807) (xy 377.201363 -112.395258)
			(xy 377.159249 -112.315676) (xy 377.124333 -112.232683) (xy 377.096889 -112.146929) (xy 377.077131 -112.059085)
			(xy 377.065214 -111.969838) (xy 377.061232 -111.879888) (xy 352.008948 -111.879888) (xy 352.008948 -119.38)
			(xy 376.553741 -119.38) (xy 376.557716 -119.269941) (xy 376.569624 -119.160455) (xy 376.5894 -119.052114)
			(xy 376.616943 -118.945483) (xy 376.652108 -118.841117) (xy 376.694712 -118.73956) (xy 376.744533 -118.641343)
			(xy 376.801312 -118.546976) (xy 376.864751 -118.456952) (xy 376.934522 -118.371741) (xy 377.010259 -118.291786)
			(xy 377.091568 -118.217505) (xy 377.178025 -118.149285) (xy 377.269179 -118.08748) (xy 377.364556 -118.032415)
			(xy 377.463657 -117.984375) (xy 377.565966 -117.943611) (xy 377.67095 -117.910336) (xy 377.778061 -117.884723)
			(xy 377.886741 -117.866906) (xy 377.996424 -117.856977) (xy 378.106537 -117.854989) (xy 378.216507 -117.860951)
			(xy 378.32576 -117.874833) (xy 378.433726 -117.896563) (xy 378.539843 -117.926026) (xy 378.643557 -117.963069)
			(xy 378.744328 -118.0075) (xy 378.84163 -118.059087) (xy 378.934956 -118.117559) (xy 379.023819 -118.182614)
			(xy 379.107757 -118.253912) (xy 379.186332 -118.33108) (xy 379.259133 -118.413717) (xy 379.325781 -118.501391)
			(xy 379.38593 -118.593647) (xy 379.439264 -118.690002) (xy 379.485507 -118.789954) (xy 379.524417 -118.892982)
			(xy 379.555791 -118.99855) (xy 379.579466 -119.106106) (xy 379.595318 -119.21509) (xy 379.603265 -119.324934)
			(xy 379.603762 -119.38) (xy 396.111741 -119.38) (xy 396.115716 -119.269941) (xy 396.127624 -119.160455)
			(xy 396.1474 -119.052114) (xy 396.174943 -118.945483) (xy 396.210108 -118.841117) (xy 396.252712 -118.73956)
			(xy 396.302533 -118.641343) (xy 396.359312 -118.546976) (xy 396.422751 -118.456952) (xy 396.492522 -118.371741)
			(xy 396.568259 -118.291786) (xy 396.649568 -118.217505) (xy 396.736025 -118.149285) (xy 396.827179 -118.08748)
			(xy 396.922556 -118.032415) (xy 397.021657 -117.984375) (xy 397.123966 -117.943611) (xy 397.22895 -117.910336)
			(xy 397.336061 -117.884723) (xy 397.444741 -117.866906) (xy 397.554424 -117.856977) (xy 397.664537 -117.854989)
			(xy 397.774507 -117.860951) (xy 397.88376 -117.874833) (xy 397.991726 -117.896563) (xy 398.097843 -117.926026)
			(xy 398.201557 -117.963069) (xy 398.302328 -118.0075) (xy 398.39963 -118.059087) (xy 398.492956 -118.117559)
			(xy 398.581819 -118.182614) (xy 398.665757 -118.253912) (xy 398.744332 -118.33108) (xy 398.817133 -118.413717)
			(xy 398.883781 -118.501391) (xy 398.94393 -118.593647) (xy 398.997264 -118.690002) (xy 399.043507 -118.789954)
			(xy 399.082417 -118.892982) (xy 399.113791 -118.99855) (xy 399.137466 -119.106106) (xy 399.153318 -119.21509)
			(xy 399.161265 -119.324934) (xy 399.161762 -119.38) (xy 399.161265 -119.435066) (xy 399.153318 -119.54491)
			(xy 399.137466 -119.653894) (xy 399.113791 -119.76145) (xy 399.082417 -119.867018) (xy 399.043507 -119.970046)
			(xy 398.997264 -120.069998) (xy 398.94393 -120.166353) (xy 398.883781 -120.258609) (xy 398.817133 -120.346283)
			(xy 398.744332 -120.42892) (xy 398.665757 -120.506088) (xy 398.581819 -120.577386) (xy 398.492956 -120.642441)
			(xy 398.39963 -120.700913) (xy 398.302328 -120.7525) (xy 398.201557 -120.796931) (xy 398.097843 -120.833974)
			(xy 397.991726 -120.863437) (xy 397.88376 -120.885167) (xy 397.774507 -120.899049) (xy 397.664537 -120.905011)
			(xy 397.554424 -120.903023) (xy 397.444741 -120.893094) (xy 397.336061 -120.875277) (xy 397.22895 -120.849664)
			(xy 397.123966 -120.816389) (xy 397.021657 -120.775625) (xy 396.922556 -120.727585) (xy 396.827179 -120.67252)
			(xy 396.736025 -120.610715) (xy 396.649568 -120.542495) (xy 396.568259 -120.468214) (xy 396.492522 -120.388259)
			(xy 396.422751 -120.303048) (xy 396.359312 -120.213024) (xy 396.302533 -120.118657) (xy 396.252712 -120.02044)
			(xy 396.210108 -119.918883) (xy 396.174943 -119.814517) (xy 396.1474 -119.707886) (xy 396.127624 -119.599545)
			(xy 396.115716 -119.490059) (xy 396.111741 -119.38) (xy 379.603762 -119.38) (xy 379.603265 -119.435066)
			(xy 379.595318 -119.54491) (xy 379.579466 -119.653894) (xy 379.555791 -119.76145) (xy 379.524417 -119.867018)
			(xy 379.485507 -119.970046) (xy 379.439264 -120.069998) (xy 379.38593 -120.166353) (xy 379.325781 -120.258609)
			(xy 379.259133 -120.346283) (xy 379.186332 -120.42892) (xy 379.107757 -120.506088) (xy 379.023819 -120.577386)
			(xy 378.934956 -120.642441) (xy 378.84163 -120.700913) (xy 378.744328 -120.7525) (xy 378.643557 -120.796931)
			(xy 378.539843 -120.833974) (xy 378.433726 -120.863437) (xy 378.32576 -120.885167) (xy 378.216507 -120.899049)
			(xy 378.106537 -120.905011) (xy 377.996424 -120.903023) (xy 377.886741 -120.893094) (xy 377.778061 -120.875277)
			(xy 377.67095 -120.849664) (xy 377.565966 -120.816389) (xy 377.463657 -120.775625) (xy 377.364556 -120.727585)
			(xy 377.269179 -120.67252) (xy 377.178025 -120.610715) (xy 377.091568 -120.542495) (xy 377.010259 -120.468214)
			(xy 376.934522 -120.388259) (xy 376.864751 -120.303048) (xy 376.801312 -120.213024) (xy 376.744533 -120.118657)
			(xy 376.694712 -120.02044) (xy 376.652108 -119.918883) (xy 376.616943 -119.814517) (xy 376.5894 -119.707886)
			(xy 376.569624 -119.599545) (xy 376.557716 -119.490059) (xy 376.553741 -119.38) (xy 352.008948 -119.38)
			(xy 352.008948 -132.199888) (xy 377.061232 -132.199888) (xy 377.065214 -132.109938) (xy 377.077131 -132.020691)
			(xy 377.096889 -131.932847) (xy 377.124333 -131.847093) (xy 377.159249 -131.7641) (xy 377.201363 -131.684518)
			(xy 377.250346 -131.608969) (xy 377.305814 -131.538045) (xy 377.367334 -131.4723) (xy 377.434423 -131.41225)
			(xy 377.506557 -131.358365) (xy 377.583171 -131.311065) (xy 377.663665 -131.270722) (xy 377.74741 -131.23765)
			(xy 377.833751 -131.21211) (xy 377.92201 -131.1943) (xy 378.011499 -131.18436) (xy 378.101515 -131.182369)
			(xy 378.191356 -131.18834) (xy 378.280317 -131.202229) (xy 378.367702 -131.223925) (xy 378.452828 -131.25326)
			(xy 378.535028 -131.290003) (xy 378.613659 -131.333867) (xy 378.688106 -131.384509) (xy 378.757786 -131.441533)
			(xy 378.822153 -131.504492) (xy 378.880704 -131.572893) (xy 378.932981 -131.646201) (xy 378.978574 -131.723843)
			(xy 379.017127 -131.80521) (xy 379.048338 -131.889666) (xy 379.071962 -131.97655) (xy 379.087815 -132.065182)
			(xy 379.095772 -132.154869) (xy 379.09627 -132.199888) (xy 396.619232 -132.199888) (xy 396.623214 -132.109938)
			(xy 396.635131 -132.020691) (xy 396.654889 -131.932847) (xy 396.682333 -131.847093) (xy 396.717249 -131.7641)
			(xy 396.759363 -131.684518) (xy 396.808346 -131.608969) (xy 396.863814 -131.538045) (xy 396.925334 -131.4723)
			(xy 396.992423 -131.41225) (xy 397.064557 -131.358365) (xy 397.141171 -131.311065) (xy 397.221665 -131.270722)
			(xy 397.30541 -131.23765) (xy 397.391751 -131.21211) (xy 397.48001 -131.1943) (xy 397.569499 -131.18436)
			(xy 397.659515 -131.182369) (xy 397.749356 -131.18834) (xy 397.838317 -131.202229) (xy 397.925702 -131.223925)
			(xy 398.010828 -131.25326) (xy 398.093028 -131.290003) (xy 398.171659 -131.333867) (xy 398.246106 -131.384509)
			(xy 398.315786 -131.441533) (xy 398.380153 -131.504492) (xy 398.438704 -131.572893) (xy 398.490981 -131.646201)
			(xy 398.536574 -131.723843) (xy 398.575127 -131.80521) (xy 398.606338 -131.889666) (xy 398.629962 -131.97655)
			(xy 398.645815 -132.065182) (xy 398.653772 -132.154869) (xy 398.65427 -132.199888) (xy 398.653772 -132.244907)
			(xy 398.645815 -132.334594) (xy 398.629962 -132.423226) (xy 398.606338 -132.51011) (xy 398.575127 -132.594566)
			(xy 398.536574 -132.675933) (xy 398.490981 -132.753575) (xy 398.438704 -132.826883) (xy 398.380153 -132.895284)
			(xy 398.315786 -132.958243) (xy 398.246106 -133.015267) (xy 398.171659 -133.065909) (xy 398.093028 -133.109773)
			(xy 398.010828 -133.146516) (xy 397.925702 -133.175851) (xy 397.838317 -133.197547) (xy 397.749356 -133.211436)
			(xy 397.659515 -133.217407) (xy 397.569499 -133.215416) (xy 397.48001 -133.205476) (xy 397.391751 -133.187666)
			(xy 397.30541 -133.162126) (xy 397.221665 -133.129054) (xy 397.141171 -133.088711) (xy 397.064557 -133.041411)
			(xy 396.992423 -132.987526) (xy 396.925334 -132.927476) (xy 396.863814 -132.861731) (xy 396.808346 -132.790807)
			(xy 396.759363 -132.715258) (xy 396.717249 -132.635676) (xy 396.682333 -132.552683) (xy 396.654889 -132.466929)
			(xy 396.635131 -132.379085) (xy 396.623214 -132.289838) (xy 396.619232 -132.199888) (xy 379.09627 -132.199888)
			(xy 379.095772 -132.244907) (xy 379.087815 -132.334594) (xy 379.071962 -132.423226) (xy 379.048338 -132.51011)
			(xy 379.017127 -132.594566) (xy 378.978574 -132.675933) (xy 378.932981 -132.753575) (xy 378.880704 -132.826883)
			(xy 378.822153 -132.895284) (xy 378.757786 -132.958243) (xy 378.688106 -133.015267) (xy 378.613659 -133.065909)
			(xy 378.535028 -133.109773) (xy 378.452828 -133.146516) (xy 378.367702 -133.175851) (xy 378.280317 -133.197547)
			(xy 378.191356 -133.211436) (xy 378.101515 -133.217407) (xy 378.011499 -133.215416) (xy 377.92201 -133.205476)
			(xy 377.833751 -133.187666) (xy 377.74741 -133.162126) (xy 377.663665 -133.129054) (xy 377.583171 -133.088711)
			(xy 377.506557 -133.041411) (xy 377.434423 -132.987526) (xy 377.367334 -132.927476) (xy 377.305814 -132.861731)
			(xy 377.250346 -132.790807) (xy 377.201363 -132.715258) (xy 377.159249 -132.635676) (xy 377.124333 -132.552683)
			(xy 377.096889 -132.466929) (xy 377.077131 -132.379085) (xy 377.065214 -132.289838) (xy 377.061232 -132.199888)
			(xy 352.008948 -132.199888) (xy 352.008948 -139.7) (xy 376.553741 -139.7) (xy 376.557716 -139.589941)
			(xy 376.569624 -139.480455) (xy 376.5894 -139.372114) (xy 376.616943 -139.265483) (xy 376.652108 -139.161117)
			(xy 376.694712 -139.05956) (xy 376.744533 -138.961343) (xy 376.801312 -138.866976) (xy 376.864751 -138.776952)
			(xy 376.934522 -138.691741) (xy 377.010259 -138.611786) (xy 377.091568 -138.537505) (xy 377.178025 -138.469285)
			(xy 377.269179 -138.40748) (xy 377.364556 -138.352415) (xy 377.463657 -138.304375) (xy 377.565966 -138.263611)
			(xy 377.67095 -138.230336) (xy 377.778061 -138.204723) (xy 377.886741 -138.186906) (xy 377.996424 -138.176977)
			(xy 378.106537 -138.174989) (xy 378.216507 -138.180951) (xy 378.32576 -138.194833) (xy 378.433726 -138.216563)
			(xy 378.539843 -138.246026) (xy 378.643557 -138.283069) (xy 378.744328 -138.3275) (xy 378.84163 -138.379087)
			(xy 378.934956 -138.437559) (xy 379.023819 -138.502614) (xy 379.107757 -138.573912) (xy 379.186332 -138.65108)
			(xy 379.259133 -138.733717) (xy 379.325781 -138.821391) (xy 379.38593 -138.913647) (xy 379.439264 -139.010002)
			(xy 379.485507 -139.109954) (xy 379.524417 -139.212982) (xy 379.555791 -139.31855) (xy 379.579466 -139.426106)
			(xy 379.595318 -139.53509) (xy 379.603265 -139.644934) (xy 379.603762 -139.7) (xy 396.111741 -139.7)
			(xy 396.115716 -139.589941) (xy 396.127624 -139.480455) (xy 396.1474 -139.372114) (xy 396.174943 -139.265483)
			(xy 396.210108 -139.161117) (xy 396.252712 -139.05956) (xy 396.302533 -138.961343) (xy 396.359312 -138.866976)
			(xy 396.422751 -138.776952) (xy 396.492522 -138.691741) (xy 396.568259 -138.611786) (xy 396.649568 -138.537505)
			(xy 396.736025 -138.469285) (xy 396.827179 -138.40748) (xy 396.922556 -138.352415) (xy 397.021657 -138.304375)
			(xy 397.123966 -138.263611) (xy 397.22895 -138.230336) (xy 397.336061 -138.204723) (xy 397.444741 -138.186906)
			(xy 397.554424 -138.176977) (xy 397.664537 -138.174989) (xy 397.774507 -138.180951) (xy 397.88376 -138.194833)
			(xy 397.991726 -138.216563) (xy 398.097843 -138.246026) (xy 398.201557 -138.283069) (xy 398.302328 -138.3275)
			(xy 398.39963 -138.379087) (xy 398.492956 -138.437559) (xy 398.581819 -138.502614) (xy 398.665757 -138.573912)
			(xy 398.744332 -138.65108) (xy 398.817133 -138.733717) (xy 398.883781 -138.821391) (xy 398.94393 -138.913647)
			(xy 398.997264 -139.010002) (xy 399.043507 -139.109954) (xy 399.082417 -139.212982) (xy 399.113791 -139.31855)
			(xy 399.137466 -139.426106) (xy 399.153318 -139.53509) (xy 399.161265 -139.644934) (xy 399.161762 -139.7)
			(xy 399.161265 -139.755066) (xy 399.153318 -139.86491) (xy 399.137466 -139.973894) (xy 399.113791 -140.08145)
			(xy 399.082417 -140.187018) (xy 399.043507 -140.290046) (xy 398.997264 -140.389998) (xy 398.94393 -140.486353)
			(xy 398.883781 -140.578609) (xy 398.817133 -140.666283) (xy 398.744332 -140.74892) (xy 398.665757 -140.826088)
			(xy 398.581819 -140.897386) (xy 398.492956 -140.962441) (xy 398.39963 -141.020913) (xy 398.302328 -141.0725)
			(xy 398.201557 -141.116931) (xy 398.097843 -141.153974) (xy 397.991726 -141.183437) (xy 397.88376 -141.205167)
			(xy 397.774507 -141.219049) (xy 397.664537 -141.225011) (xy 397.554424 -141.223023) (xy 397.444741 -141.213094)
			(xy 397.336061 -141.195277) (xy 397.22895 -141.169664) (xy 397.123966 -141.136389) (xy 397.021657 -141.095625)
			(xy 396.922556 -141.047585) (xy 396.827179 -140.99252) (xy 396.736025 -140.930715) (xy 396.649568 -140.862495)
			(xy 396.568259 -140.788214) (xy 396.492522 -140.708259) (xy 396.422751 -140.623048) (xy 396.359312 -140.533024)
			(xy 396.302533 -140.438657) (xy 396.252712 -140.34044) (xy 396.210108 -140.238883) (xy 396.174943 -140.134517)
			(xy 396.1474 -140.027886) (xy 396.127624 -139.919545) (xy 396.115716 -139.810059) (xy 396.111741 -139.7)
			(xy 379.603762 -139.7) (xy 379.603265 -139.755066) (xy 379.595318 -139.86491) (xy 379.579466 -139.973894)
			(xy 379.555791 -140.08145) (xy 379.524417 -140.187018) (xy 379.485507 -140.290046) (xy 379.439264 -140.389998)
			(xy 379.38593 -140.486353) (xy 379.325781 -140.578609) (xy 379.259133 -140.666283) (xy 379.186332 -140.74892)
			(xy 379.107757 -140.826088) (xy 379.023819 -140.897386) (xy 378.934956 -140.962441) (xy 378.84163 -141.020913)
			(xy 378.744328 -141.0725) (xy 378.643557 -141.116931) (xy 378.539843 -141.153974) (xy 378.433726 -141.183437)
			(xy 378.32576 -141.205167) (xy 378.216507 -141.219049) (xy 378.106537 -141.225011) (xy 377.996424 -141.223023)
			(xy 377.886741 -141.213094) (xy 377.778061 -141.195277) (xy 377.67095 -141.169664) (xy 377.565966 -141.136389)
			(xy 377.463657 -141.095625) (xy 377.364556 -141.047585) (xy 377.269179 -140.99252) (xy 377.178025 -140.930715)
			(xy 377.091568 -140.862495) (xy 377.010259 -140.788214) (xy 376.934522 -140.708259) (xy 376.864751 -140.623048)
			(xy 376.801312 -140.533024) (xy 376.744533 -140.438657) (xy 376.694712 -140.34044) (xy 376.652108 -140.238883)
			(xy 376.616943 -140.134517) (xy 376.5894 -140.027886) (xy 376.569624 -139.919545) (xy 376.557716 -139.810059)
			(xy 376.553741 -139.7) (xy 352.008948 -139.7) (xy 352.008948 -153.299922) (xy 352.009454 -153.395255)
			(xy 352.017547 -153.585749) (xy 352.033718 -153.775728) (xy 352.057937 -153.964849) (xy 352.09016 -154.152772)
			(xy 352.130331 -154.339159) (xy 352.178375 -154.523672) (xy 352.234207 -154.70598) (xy 352.297727 -154.885754)
			(xy 352.368818 -155.062671) (xy 352.447355 -155.23641) (xy 352.533194 -155.40666) (xy 352.626182 -155.573114)
			(xy 352.72615 -155.735471) (xy 352.832919 -155.893439) (xy 352.946296 -156.046733) (xy 353.066077 -156.195077)
			(xy 353.192045 -156.338204) (xy 353.323975 -156.475856) (xy 353.461628 -156.607784) (xy 353.604756 -156.733752)
			(xy 353.753102 -156.853531) (xy 353.906397 -156.966907) (xy 354.064366 -157.073674) (xy 354.226724 -157.173641)
			(xy 354.393179 -157.266627) (xy 354.563429 -157.352464) (xy 354.73717 -157.430999) (xy 354.914087 -157.502089)
			(xy 355.093862 -157.565606) (xy 355.27617 -157.621437) (xy 355.460684 -157.66948) (xy 355.647071 -157.709648)
			(xy 355.834994 -157.74187) (xy 356.024116 -157.766087) (xy 356.214095 -157.782255) (xy 356.404589 -157.790347)
			(xy 356.499922 -157.790896) (xy 357.000048 -157.790896) (xy 357.083565 -157.791394) (xy 357.250411 -157.799344)
			(xy 357.416689 -157.815224) (xy 357.582024 -157.838998) (xy 357.746039 -157.870611) (xy 357.908365 -157.909993)
			(xy 358.068633 -157.957054) (xy 358.226481 -158.011687) (xy 358.38155 -158.07377) (xy 358.53349 -158.14316)
			(xy 358.681955 -158.219701) (xy 358.826611 -158.30322) (xy 358.967129 -158.393527) (xy 359.10319 -158.490418)
			(xy 359.234488 -158.593673) (xy 359.360723 -158.703059) (xy 359.481611 -158.818327) (xy 359.492747 -158.830006)
			(xy 361.785893 -158.830006) (xy 361.789998 -158.730238) (xy 361.802285 -158.631143) (xy 361.822671 -158.533393)
			(xy 361.85102 -158.437649) (xy 361.887138 -158.344557) (xy 361.930782 -158.254747) (xy 361.981657 -158.168826)
			(xy 362.039419 -158.087375) (xy 362.103677 -158.010945) (xy 362.173997 -157.940052) (xy 362.21162 -157.907228)
			(xy 362.219631 -157.899646) (xy 362.228855 -157.879636) (xy 362.2294 -157.86862) (xy 362.2294 -157.791404)
			(xy 362.22886 -157.780385) (xy 362.219642 -157.760369) (xy 362.21162 -157.752796) (xy 362.175695 -157.72148)
			(xy 362.108323 -157.65406) (xy 362.046446 -157.581563) (xy 361.990445 -157.504438) (xy 361.940665 -157.423158)
			(xy 361.897412 -157.338225) (xy 361.860953 -157.250162) (xy 361.831512 -157.15951) (xy 361.809271 -157.066829)
			(xy 361.794367 -156.972689) (xy 361.786891 -156.87767) (xy 361.786424 -156.830014) (xy 361.786965 -156.779837)
			(xy 361.79525 -156.679825) (xy 361.811765 -156.580838) (xy 361.836396 -156.483554) (xy 361.868976 -156.388635)
			(xy 361.909282 -156.29673) (xy 361.957039 -156.208467) (xy 362.01192 -156.124449) (xy 362.073551 -156.045249)
			(xy 362.141512 -155.971408) (xy 362.215337 -155.903431) (xy 362.294523 -155.841782) (xy 362.378528 -155.786881)
			(xy 362.46678 -155.739104) (xy 362.558676 -155.698777) (xy 362.653587 -155.666176) (xy 362.750866 -155.641522)
			(xy 362.849849 -155.624985) (xy 362.949859 -155.616677) (xy 363.000036 -155.616148) (xy 363.047698 -155.616657)
			(xy 363.142727 -155.624138) (xy 363.236876 -155.639052) (xy 363.329565 -155.661306) (xy 363.420222 -155.690763)
			(xy 363.508289 -155.727242) (xy 363.593222 -155.770518) (xy 363.674499 -155.820323) (xy 363.751617 -155.876352)
			(xy 363.824103 -155.938258) (xy 363.891508 -156.005661) (xy 363.922818 -156.041598) (xy 363.930385 -156.049627)
			(xy 363.950406 -156.058842) (xy 363.961426 -156.059378) (xy 364.038642 -156.059378) (xy 364.049665 -156.05887)
			(xy 364.069681 -156.04963) (xy 364.07725 -156.041598) (xy 364.108538 -156.005641) (xy 364.175953 -155.938249)
			(xy 364.248446 -155.876351) (xy 364.32557 -155.820329) (xy 364.406849 -155.770527) (xy 364.491784 -155.727252)
			(xy 364.579851 -155.690771) (xy 364.670507 -155.661309) (xy 364.763194 -155.639047) (xy 364.857342 -155.624122)
			(xy 364.95237 -155.616626) (xy 365.000032 -155.616148) (xy 365.050199 -155.616675) (xy 365.150189 -155.624962)
			(xy 365.249154 -155.641476) (xy 365.346418 -155.666105) (xy 365.441316 -155.69868) (xy 365.5332 -155.738979)
			(xy 365.621444 -155.786728) (xy 365.705443 -155.841599) (xy 365.784626 -155.903218) (xy 365.85845 -155.971164)
			(xy 365.926413 -156.044974) (xy 365.988049 -156.124143) (xy 366.042938 -156.208131) (xy 366.090705 -156.296364)
			(xy 366.131025 -156.38824) (xy 366.16362 -156.483131) (xy 366.18827 -156.580389) (xy 366.204806 -156.679351)
			(xy 366.213114 -156.779339) (xy 366.213644 -156.829506) (xy 366.213644 -156.830014) (xy 366.21318 -156.877671)
			(xy 366.205711 -156.972691) (xy 366.190811 -157.066833) (xy 366.168573 -157.159516) (xy 366.139134 -157.250169)
			(xy 366.102675 -157.338233) (xy 366.059421 -157.423167) (xy 366.009638 -157.504446) (xy 365.953632 -157.58157)
			(xy 365.891751 -157.654063) (xy 365.824373 -157.721479) (xy 365.788448 -157.752796) (xy 365.780421 -157.760364)
			(xy 365.771207 -157.780384) (xy 365.770668 -157.791404) (xy 365.770668 -157.86862) (xy 365.771205 -157.879639)
			(xy 365.780426 -157.899654) (xy 365.788448 -157.907228) (xy 365.826082 -157.94004) (xy 365.896405 -158.010933)
			(xy 365.960665 -158.087364) (xy 366.018429 -158.168815) (xy 366.069306 -158.254737) (xy 366.112952 -158.344548)
			(xy 366.149072 -158.437642) (xy 366.177421 -158.533388) (xy 366.197809 -158.63114) (xy 366.210097 -158.730236)
			(xy 366.214202 -158.830006) (xy 367.785885 -158.830006) (xy 367.78999 -158.730238) (xy 367.802277 -158.631144)
			(xy 367.822663 -158.533394) (xy 367.851011 -158.43765) (xy 367.887129 -158.344558) (xy 367.930773 -158.254748)
			(xy 367.981647 -158.168827) (xy 368.039408 -158.087376) (xy 368.103666 -158.010945) (xy 368.173985 -157.940052)
			(xy 368.211608 -157.907228) (xy 368.219618 -157.899644) (xy 368.228843 -157.879636) (xy 368.229388 -157.86862)
			(xy 368.229388 -157.791404) (xy 368.228852 -157.780385) (xy 368.219631 -157.760368) (xy 368.211608 -157.752796)
			(xy 368.17568 -157.721483) (xy 368.108309 -157.654062) (xy 368.046432 -157.581565) (xy 367.990432 -157.504439)
			(xy 367.940652 -157.423159) (xy 367.897399 -157.338226) (xy 367.86094 -157.250162) (xy 367.8315 -157.15951)
			(xy 367.809259 -157.066829) (xy 367.794355 -156.972689) (xy 367.786879 -156.87767) (xy 367.786412 -156.830014)
			(xy 367.786965 -156.779837) (xy 367.79525 -156.679826) (xy 367.811765 -156.58084) (xy 367.836396 -156.483556)
			(xy 367.868975 -156.388637) (xy 367.909281 -156.296733) (xy 367.957037 -156.208471) (xy 368.011917 -156.124453)
			(xy 368.073548 -156.045253) (xy 368.141507 -155.971413) (xy 368.215332 -155.903435) (xy 368.294517 -155.841786)
			(xy 368.378521 -155.786885) (xy 368.466772 -155.739108) (xy 368.558667 -155.698781) (xy 368.653578 -155.666178)
			(xy 368.750856 -155.641524) (xy 368.849838 -155.624986) (xy 368.949847 -155.616677) (xy 369.000024 -155.616148)
			(xy 369.047687 -155.616593) (xy 369.142718 -155.624081) (xy 369.236868 -155.639002) (xy 369.329558 -155.661263)
			(xy 369.420216 -155.690726) (xy 369.508283 -155.727212) (xy 369.593216 -155.770493) (xy 369.674492 -155.820305)
			(xy 369.751609 -155.876339) (xy 369.824093 -155.938251) (xy 369.891497 -156.005658) (xy 369.922806 -156.041598)
			(xy 369.930378 -156.049622) (xy 369.950395 -156.05884) (xy 369.961414 -156.059378) (xy 370.03863 -156.059378)
			(xy 370.049652 -156.058864) (xy 370.069669 -156.049628) (xy 370.077238 -156.041598) (xy 370.108532 -156.005647)
			(xy 370.175947 -155.938254) (xy 370.248439 -155.876356) (xy 370.325562 -155.820334) (xy 370.406841 -155.770531)
			(xy 370.491775 -155.727256) (xy 370.579841 -155.690775) (xy 370.670497 -155.661312) (xy 370.763183 -155.639049)
			(xy 370.857331 -155.624123) (xy 370.952359 -155.616626) (xy 371.00002 -155.616148) (xy 371.050186 -155.616687)
			(xy 371.150177 -155.624972) (xy 371.249142 -155.641486) (xy 371.346405 -155.666113) (xy 371.441303 -155.698688)
			(xy 371.533187 -155.738987) (xy 371.621431 -155.786734) (xy 371.70543 -155.841604) (xy 371.784613 -155.903223)
			(xy 371.858438 -155.971169) (xy 371.9264 -156.044978) (xy 371.988036 -156.124147) (xy 372.042926 -156.208134)
			(xy 372.090693 -156.296366) (xy 372.131012 -156.388242) (xy 372.163608 -156.483132) (xy 372.188258 -156.58039)
			(xy 372.204794 -156.679351) (xy 372.213102 -156.77934) (xy 372.213632 -156.829506) (xy 372.213632 -156.830014)
			(xy 372.213173 -156.877671) (xy 372.205703 -156.972691) (xy 372.190803 -157.066833) (xy 372.168565 -157.159516)
			(xy 372.139126 -157.250169) (xy 372.102666 -157.338234) (xy 372.059411 -157.423168) (xy 372.009628 -157.504447)
			(xy 371.953622 -157.58157) (xy 371.89174 -157.654063) (xy 371.824361 -157.721479) (xy 371.788436 -157.752796)
			(xy 371.780407 -157.760362) (xy 371.771194 -157.780384) (xy 371.770656 -157.791404) (xy 371.770656 -157.86862)
			(xy 371.771165 -157.879643) (xy 371.780403 -157.89966) (xy 371.788436 -157.907228) (xy 371.82687 -157.940727)
			(xy 371.898577 -158.013215) (xy 371.963952 -158.091462) (xy 372.022533 -158.174916) (xy 372.073908 -158.26299)
			(xy 372.096284 -158.308802) (xy 372.100856 -158.318454) (xy 372.116858 -158.332424) (xy 372.199154 -158.357316)
			(xy 372.209416 -158.359985) (xy 372.230452 -158.357503) (xy 372.239794 -158.35249) (xy 372.285756 -158.325685)
			(xy 372.380859 -158.27795) (xy 372.479133 -158.237137) (xy 372.580073 -158.203457) (xy 372.683163 -158.17708)
			(xy 372.787875 -158.158142) (xy 372.893673 -158.146741) (xy 373.000016 -158.142934) (xy 373.106359 -158.146741)
			(xy 373.212157 -158.158142) (xy 373.316869 -158.17708) (xy 373.419959 -158.203457) (xy 373.520899 -158.237137)
			(xy 373.619173 -158.27795) (xy 373.714276 -158.325685) (xy 373.760238 -158.35249) (xy 373.769622 -158.357377)
			(xy 373.79061 -158.359868) (xy 373.800878 -158.357316) (xy 373.883174 -158.332424) (xy 373.899176 -158.318454)
			(xy 373.903748 -158.308802) (xy 373.926127 -158.262992) (xy 373.977496 -158.174915) (xy 374.036076 -158.091459)
			(xy 374.101453 -158.013214) (xy 374.173165 -157.940731) (xy 374.211596 -157.907228) (xy 374.219604 -157.899642)
			(xy 374.228831 -157.879636) (xy 374.229376 -157.86862) (xy 374.229376 -157.791404) (xy 374.228843 -157.780384)
			(xy 374.219621 -157.760367) (xy 374.211596 -157.752796) (xy 374.175666 -157.721486) (xy 374.108295 -157.654064)
			(xy 374.046419 -157.581567) (xy 373.990418 -157.504441) (xy 373.940639 -157.423161) (xy 373.897386 -157.338227)
			(xy 373.860928 -157.250163) (xy 373.831488 -157.159511) (xy 373.809247 -157.066829) (xy 373.794343 -156.972689)
			(xy 373.786867 -156.87767) (xy 373.7864 -156.830014) (xy 373.786965 -156.779837) (xy 373.79525 -156.679827)
			(xy 373.811764 -156.580841) (xy 373.836395 -156.483558) (xy 373.868974 -156.38864) (xy 373.909279 -156.296736)
			(xy 373.957035 -156.208474) (xy 374.011915 -156.124457) (xy 374.073545 -156.045257) (xy 374.141503 -155.971417)
			(xy 374.215327 -155.90344) (xy 374.294511 -155.84179) (xy 374.378515 -155.786889) (xy 374.466765 -155.739112)
			(xy 374.558659 -155.698784) (xy 374.653568 -155.666181) (xy 374.750846 -155.641526) (xy 374.849827 -155.624988)
			(xy 374.949835 -155.616678) (xy 375.000012 -155.616148) (xy 375.047675 -155.616602) (xy 375.142705 -155.624089)
			(xy 375.236856 -155.639009) (xy 375.329545 -155.661268) (xy 375.420203 -155.690731) (xy 375.50827 -155.727216)
			(xy 375.593203 -155.770497) (xy 375.674479 -155.820308) (xy 375.751597 -155.876341) (xy 375.824081 -155.938252)
			(xy 375.891484 -156.005658) (xy 375.922794 -156.041598) (xy 375.930371 -156.049616) (xy 375.950384 -156.058837)
			(xy 375.961402 -156.059378) (xy 376.038618 -156.059378) (xy 376.049639 -156.058857) (xy 376.069656 -156.049626)
			(xy 376.077226 -156.041598) (xy 376.108527 -156.005653) (xy 376.175941 -155.93826) (xy 376.248432 -155.876362)
			(xy 376.325555 -155.820339) (xy 376.406833 -155.770536) (xy 376.491766 -155.72726) (xy 376.579831 -155.690779)
			(xy 376.670486 -155.661315) (xy 376.763173 -155.639051) (xy 376.857319 -155.624124) (xy 376.952347 -155.616626)
			(xy 377.000008 -155.616148) (xy 377.050174 -155.616698) (xy 377.150164 -155.624983) (xy 377.249129 -155.641495)
			(xy 377.346392 -155.666122) (xy 377.44129 -155.698696) (xy 377.533174 -155.738994) (xy 377.621418 -155.78674)
			(xy 377.705417 -155.84161) (xy 377.7846 -155.903228) (xy 377.858425 -155.971173) (xy 377.926387 -156.044982)
			(xy 377.988024 -156.12415) (xy 378.042913 -156.208137) (xy 378.090681 -156.296369) (xy 378.131 -156.388243)
			(xy 378.163596 -156.483134) (xy 378.188246 -156.580391) (xy 378.204782 -156.679352) (xy 378.21309 -156.77934)
			(xy 378.21362 -156.829506) (xy 378.21362 -156.830014) (xy 378.213165 -156.877671) (xy 378.205695 -156.972692)
			(xy 378.190795 -157.066834) (xy 378.168557 -157.159517) (xy 378.139117 -157.25017) (xy 378.102657 -157.338235)
			(xy 378.059402 -157.423168) (xy 378.009618 -157.504447) (xy 377.953612 -157.581571) (xy 377.891728 -157.654064)
			(xy 377.82435 -157.721479) (xy 377.788424 -157.752796) (xy 377.780393 -157.76036) (xy 377.771182 -157.780384)
			(xy 377.770644 -157.791404) (xy 377.770644 -157.86862) (xy 377.771157 -157.879642) (xy 377.780393 -157.899659)
			(xy 377.788424 -157.907228) (xy 377.826059 -157.94004) (xy 377.896383 -158.010932) (xy 377.960645 -158.087362)
			(xy 378.01841 -158.168813) (xy 378.069288 -158.254735) (xy 378.112934 -158.344547) (xy 378.149055 -158.43764)
			(xy 378.177405 -158.533387) (xy 378.197793 -158.631139) (xy 378.210081 -158.730235) (xy 378.214186 -158.830006)
			(xy 378.21008 -158.929778) (xy 378.197791 -159.028874) (xy 378.177402 -159.126626) (xy 378.149051 -159.222372)
			(xy 378.112929 -159.315465) (xy 378.069281 -159.405276) (xy 378.018403 -159.491197) (xy 377.960637 -159.572648)
			(xy 377.896374 -159.649078) (xy 377.82605 -159.719969) (xy 377.788424 -159.752792) (xy 377.780395 -159.760358)
			(xy 377.771183 -159.78038) (xy 377.770644 -159.7914) (xy 377.770644 -159.868616) (xy 377.771159 -159.879638)
			(xy 377.780393 -159.899655) (xy 377.788424 -159.907224) (xy 377.824368 -159.938518) (xy 377.891738 -160.005942)
			(xy 377.953613 -160.078441) (xy 378.009613 -160.155569) (xy 378.059391 -160.236851) (xy 378.102642 -160.321787)
			(xy 378.139099 -160.409852) (xy 378.168538 -160.500505) (xy 378.190777 -160.593188) (xy 378.205679 -160.687329)
			(xy 378.213153 -160.782349) (xy 378.21362 -160.830006) (xy 381.986028 -160.830006) (xy 381.986502 -160.782344)
			(xy 381.993988 -160.687314) (xy 382.008905 -160.593164) (xy 382.031164 -160.500475) (xy 382.060625 -160.409817)
			(xy 382.097107 -160.321751) (xy 382.140386 -160.236817) (xy 382.190195 -160.155541) (xy 382.246226 -160.078423)
			(xy 382.308135 -160.005939) (xy 382.375539 -159.938534) (xy 382.411478 -159.907224) (xy 382.4195 -159.899652)
			(xy 382.428716 -159.879634) (xy 382.429258 -159.868616) (xy 382.429258 -159.7914) (xy 382.428734 -159.780379)
			(xy 382.419506 -159.760362) (xy 382.411478 -159.752792) (xy 382.375537 -159.721486) (xy 382.308145 -159.654072)
			(xy 382.246247 -159.581581) (xy 382.190224 -159.504459) (xy 382.140421 -159.423182) (xy 382.097145 -159.338249)
			(xy 382.060663 -159.250184) (xy 382.031199 -159.15953) (xy 382.008934 -159.066844) (xy 381.994006 -158.972698)
			(xy 381.986507 -158.877671) (xy 381.986028 -158.83001) (xy 381.986505 -158.782348) (xy 381.99399 -158.687318)
			(xy 382.008908 -158.593168) (xy 382.031165 -158.500479) (xy 382.060626 -158.409822) (xy 382.097108 -158.321755)
			(xy 382.140387 -158.236822) (xy 382.190196 -158.155546) (xy 382.246227 -158.078427) (xy 382.308135 -158.005943)
			(xy 382.37554 -157.938538) (xy 382.411478 -157.907228) (xy 382.419499 -157.899655) (xy 382.428715 -157.879638)
			(xy 382.429258 -157.86862) (xy 382.429258 -157.791404) (xy 382.428731 -157.780383) (xy 382.419505 -157.760366)
			(xy 382.411478 -157.752796) (xy 382.375539 -157.721488) (xy 382.308147 -157.654074) (xy 382.246249 -157.581583)
			(xy 382.190226 -157.504462) (xy 382.140423 -157.423184) (xy 382.097147 -157.338252) (xy 382.060664 -157.250187)
			(xy 382.0312 -157.159533) (xy 382.008935 -157.066848) (xy 381.994007 -156.972702) (xy 381.986507 -156.877675)
			(xy 381.986028 -156.830014) (xy 381.986552 -156.779829) (xy 381.994839 -156.679803) (xy 382.011358 -156.580802)
			(xy 382.035996 -156.483504) (xy 382.068585 -156.388573) (xy 382.108902 -156.296657) (xy 382.156672 -156.208384)
			(xy 382.211568 -156.124358) (xy 382.273215 -156.045152) (xy 382.341193 -155.971307) (xy 382.415037 -155.903328)
			(xy 382.494242 -155.84168) (xy 382.578267 -155.786782) (xy 382.666539 -155.739011) (xy 382.758454 -155.698693)
			(xy 382.853385 -155.666102) (xy 382.950683 -155.641462) (xy 383.049683 -155.624942) (xy 383.149709 -155.616653)
			(xy 383.199894 -155.616148) (xy 383.247556 -155.616615) (xy 383.342587 -155.624101) (xy 383.436737 -155.639019)
			(xy 383.529426 -155.661277) (xy 383.620084 -155.690739) (xy 383.708151 -155.727222) (xy 383.793084 -155.770502)
			(xy 383.87436 -155.820311) (xy 383.951478 -155.876344) (xy 384.023962 -155.938253) (xy 384.091366 -156.005659)
			(xy 384.122676 -156.041598) (xy 384.13026 -156.049608) (xy 384.150268 -156.058834) (xy 384.161284 -156.059378)
			(xy 384.2385 -156.059378) (xy 384.24952 -156.058847) (xy 384.269537 -156.049623) (xy 384.277108 -156.041598)
			(xy 384.308419 -156.005661) (xy 384.375832 -155.938269) (xy 384.448322 -155.87637) (xy 384.525443 -155.820346)
			(xy 384.60672 -155.770543) (xy 384.691652 -155.727267) (xy 384.779717 -155.690784) (xy 384.870371 -155.661319)
			(xy 384.963056 -155.639054) (xy 385.057202 -155.624126) (xy 385.152229 -155.616627) (xy 385.19989 -155.616148)
			(xy 385.250075 -155.616648) (xy 385.350103 -155.624936) (xy 385.449105 -155.641456) (xy 385.546404 -155.666095)
			(xy 385.641336 -155.698684) (xy 385.733253 -155.739003) (xy 385.821526 -155.786773) (xy 385.905553 -155.841671)
			(xy 385.984759 -155.90332) (xy 386.058604 -155.971299) (xy 386.126583 -156.045144) (xy 386.188232 -156.12435)
			(xy 386.243129 -156.208377) (xy 386.290899 -156.296651) (xy 386.331217 -156.388568) (xy 386.363807 -156.4835)
			(xy 386.388445 -156.580799) (xy 386.404965 -156.679801) (xy 386.413252 -156.779829) (xy 386.413756 -156.830014)
			(xy 386.413302 -156.877677) (xy 386.405815 -156.972707) (xy 386.390895 -157.066858) (xy 386.368635 -157.159547)
			(xy 386.339172 -157.250205) (xy 386.302688 -157.338272) (xy 386.259407 -157.423205) (xy 386.209596 -157.504481)
			(xy 386.153563 -157.581599) (xy 386.091652 -157.654083) (xy 386.024245 -157.721486) (xy 385.988306 -157.752796)
			(xy 385.980288 -157.760372) (xy 385.971066 -157.780386) (xy 385.970526 -157.791404) (xy 385.970526 -157.86862)
			(xy 385.971045 -157.879641) (xy 385.980277 -157.899658) (xy 385.988306 -157.907228) (xy 386.024253 -157.938527)
			(xy 386.091646 -158.005941) (xy 386.153544 -158.078433) (xy 386.209567 -158.155555) (xy 386.259369 -158.236834)
			(xy 386.302644 -158.321767) (xy 386.339126 -158.409833) (xy 386.36859 -158.500488) (xy 386.390853 -158.593174)
			(xy 386.40578 -158.687321) (xy 386.413278 -158.782349) (xy 386.413756 -158.83001) (xy 386.413299 -158.877672)
			(xy 386.405812 -158.972703) (xy 386.390893 -159.066853) (xy 386.368633 -159.159543) (xy 386.339171 -159.250201)
			(xy 386.302686 -159.338268) (xy 386.259406 -159.423201) (xy 386.209595 -159.504477) (xy 386.153562 -159.581594)
			(xy 386.091652 -159.654079) (xy 386.024245 -159.721482) (xy 385.988306 -159.752792) (xy 385.980289 -159.76037)
			(xy 385.971067 -159.780382) (xy 385.970526 -159.7914) (xy 385.970526 -159.868616) (xy 385.971047 -159.879637)
			(xy 385.980278 -159.899654) (xy 385.988306 -159.907224) (xy 386.024251 -159.938525) (xy 386.091644 -160.005939)
			(xy 386.153542 -160.078431) (xy 386.209565 -160.155553) (xy 386.259368 -160.236831) (xy 386.302643 -160.321764)
			(xy 386.339125 -160.409829) (xy 386.368589 -160.500484) (xy 386.390852 -160.593171) (xy 386.405779 -160.687317)
			(xy 386.413277 -160.782345) (xy 386.413756 -160.830006) (xy 386.41359 -160.852381) (xy 386.411813 -160.897097)
			(xy 386.4102 -160.919414) (xy 386.4102 -160.919668) (xy 386.409958 -160.928551) (xy 386.414832 -160.945627)
			(xy 386.425194 -160.960048) (xy 386.432298 -160.965388) (xy 386.50545 -161.014664) (xy 386.512994 -161.019448)
			(xy 386.530299 -161.023851) (xy 386.548064 -161.022055) (xy 386.55625 -161.018474) (xy 386.556504 -161.01822)
			(xy 386.606586 -160.994237) (xy 386.709718 -160.953049) (xy 386.815678 -160.919811) (xy 386.923857 -160.894713)
			(xy 387.033629 -160.877899) (xy 387.14436 -160.869468) (xy 387.255412 -160.869468) (xy 387.366143 -160.877899)
			(xy 387.475915 -160.894713) (xy 387.584094 -160.919811) (xy 387.690054 -160.953049) (xy 387.793186 -160.994237)
			(xy 387.843268 -161.01822) (xy 387.843522 -161.018474) (xy 387.851694 -161.022085) (xy 387.869464 -161.023863)
			(xy 387.886764 -161.019431) (xy 387.894322 -161.014664) (xy 387.967474 -160.965388) (xy 387.974676 -160.960145)
			(xy 387.985104 -160.945713) (xy 387.989919 -160.928571) (xy 387.989572 -160.919668) (xy 387.989572 -160.91916)
			(xy 387.987965 -160.896906) (xy 387.986188 -160.852317) (xy 387.986016 -160.830006) (xy 387.986494 -160.782344)
			(xy 387.99398 -160.687314) (xy 388.008897 -160.593165) (xy 388.031155 -160.500476) (xy 388.060616 -160.409818)
			(xy 388.097098 -160.321752) (xy 388.140377 -160.236818) (xy 388.190185 -160.155542) (xy 388.246216 -160.078424)
			(xy 388.308124 -160.005939) (xy 388.375528 -159.938534) (xy 388.411466 -159.907224) (xy 388.419487 -159.89965)
			(xy 388.428704 -159.879634) (xy 388.429246 -159.868616) (xy 388.429246 -159.7914) (xy 388.428725 -159.780379)
			(xy 388.419496 -159.760361) (xy 388.411466 -159.752792) (xy 388.375523 -159.721489) (xy 388.308131 -159.654075)
			(xy 388.246233 -159.581583) (xy 388.19021 -159.504461) (xy 388.140408 -159.423183) (xy 388.097133 -159.33825)
			(xy 388.06065 -159.250185) (xy 388.031186 -159.15953) (xy 388.008922 -159.066845) (xy 387.993994 -158.972698)
			(xy 387.986495 -158.877671) (xy 387.986016 -158.83001) (xy 387.986497 -158.782348) (xy 387.993982 -158.687318)
			(xy 388.0089 -158.593169) (xy 388.031157 -158.50048) (xy 388.060618 -158.409823) (xy 388.097099 -158.321756)
			(xy 388.140378 -158.236823) (xy 388.190186 -158.155546) (xy 388.246216 -158.078428) (xy 388.308124 -158.005943)
			(xy 388.375528 -157.938538) (xy 388.411466 -157.907228) (xy 388.419485 -157.899653) (xy 388.428703 -157.879638)
			(xy 388.429246 -157.86862) (xy 388.429246 -157.791404) (xy 388.428723 -157.780383) (xy 388.419495 -157.760366)
			(xy 388.411466 -157.752796) (xy 388.375525 -157.721491) (xy 388.308133 -157.654077) (xy 388.246235 -157.581585)
			(xy 388.190212 -157.504463) (xy 388.14041 -157.423186) (xy 388.097134 -157.338253) (xy 388.060652 -157.250188)
			(xy 388.031187 -157.159534) (xy 388.008923 -157.066848) (xy 387.993995 -156.972702) (xy 387.986495 -156.877675)
			(xy 387.986016 -156.830014) (xy 387.986566 -156.77983) (xy 387.994853 -156.679805) (xy 388.011372 -156.580807)
			(xy 388.036009 -156.48351) (xy 388.068597 -156.38858) (xy 388.108913 -156.296666) (xy 388.156682 -156.208395)
			(xy 388.211577 -156.12437) (xy 388.273223 -156.045165) (xy 388.341199 -155.971321) (xy 388.415041 -155.903343)
			(xy 388.494244 -155.841695) (xy 388.578267 -155.786798) (xy 388.666537 -155.739027) (xy 388.758451 -155.698709)
			(xy 388.853379 -155.666118) (xy 388.950675 -155.641478) (xy 389.049674 -155.624957) (xy 389.149698 -155.616667)
			(xy 389.199882 -155.616148) (xy 389.247544 -155.616624) (xy 389.342574 -155.624108) (xy 389.436724 -155.639026)
			(xy 389.529414 -155.661283) (xy 389.620071 -155.690744) (xy 389.708138 -155.727226) (xy 389.793071 -155.770505)
			(xy 389.874347 -155.820314) (xy 389.951465 -155.876345) (xy 390.02395 -155.938254) (xy 390.091354 -156.005659)
			(xy 390.122664 -156.041598) (xy 390.130253 -156.049603) (xy 390.150257 -156.058831) (xy 390.161272 -156.059378)
			(xy 390.238488 -156.059378) (xy 390.249507 -156.05884) (xy 390.269524 -156.049622) (xy 390.277096 -156.041598)
			(xy 390.308413 -156.005667) (xy 390.375826 -155.938274) (xy 390.448315 -155.876375) (xy 390.525436 -155.820351)
			(xy 390.606712 -155.770548) (xy 390.691643 -155.727271) (xy 390.779707 -155.690787) (xy 390.870361 -155.661322)
			(xy 390.963045 -155.639057) (xy 391.057191 -155.624128) (xy 391.152217 -155.616628) (xy 391.199878 -155.616148)
			(xy 391.250063 -155.61666) (xy 391.35009 -155.624946) (xy 391.449092 -155.641465) (xy 391.546391 -155.666103)
			(xy 391.641323 -155.698692) (xy 391.73324 -155.73901) (xy 391.821513 -155.78678) (xy 391.90554 -155.841676)
			(xy 391.984746 -155.903324) (xy 392.058591 -155.971303) (xy 392.12657 -156.045147) (xy 392.188219 -156.124354)
			(xy 392.243116 -156.20838) (xy 392.290887 -156.296653) (xy 392.331205 -156.388569) (xy 392.363794 -156.483501)
			(xy 392.388433 -156.5808) (xy 392.404953 -156.679802) (xy 392.41324 -156.779829) (xy 392.413744 -156.830014)
			(xy 392.413294 -156.877677) (xy 392.405807 -156.972708) (xy 392.390887 -157.066858) (xy 392.368627 -157.159548)
			(xy 392.339164 -157.250206) (xy 392.302679 -157.338273) (xy 392.259397 -157.423206) (xy 392.209586 -157.504482)
			(xy 392.153552 -157.581599) (xy 392.091641 -157.654083) (xy 392.024234 -157.721487) (xy 391.988294 -157.752796)
			(xy 391.980274 -157.760371) (xy 391.971054 -157.780386) (xy 391.970514 -157.791404) (xy 391.970514 -157.86862)
			(xy 391.971036 -157.879641) (xy 391.980266 -157.899658) (xy 391.988294 -157.907228) (xy 392.024239 -157.93853)
			(xy 392.091631 -158.005944) (xy 392.15353 -158.078435) (xy 392.209553 -158.155557) (xy 392.259356 -158.236835)
			(xy 392.302632 -158.321768) (xy 392.339114 -158.409833) (xy 392.368577 -158.500488) (xy 392.390841 -158.593175)
			(xy 392.405768 -158.687321) (xy 392.413266 -158.782349) (xy 392.413744 -158.83001) (xy 392.413291 -158.877673)
			(xy 392.405804 -158.972703) (xy 392.390885 -159.066854) (xy 392.368625 -159.159544) (xy 392.339162 -159.250202)
			(xy 392.302678 -159.338268) (xy 392.259396 -159.423202) (xy 392.209585 -159.504478) (xy 392.153552 -159.581595)
			(xy 392.091641 -159.654079) (xy 392.024234 -159.721482) (xy 391.988294 -159.752792) (xy 391.980276 -159.760368)
			(xy 391.971055 -159.780382) (xy 391.970514 -159.7914) (xy 391.970514 -159.868616) (xy 391.971038 -159.879637)
			(xy 391.980267 -159.899653) (xy 391.988294 -159.907224) (xy 392.024237 -159.938528) (xy 392.09163 -160.005941)
			(xy 392.153528 -160.078433) (xy 392.209552 -160.155554) (xy 392.259354 -160.236832) (xy 392.30263 -160.321765)
			(xy 392.339112 -160.40983) (xy 392.368576 -160.500485) (xy 392.39084 -160.593171) (xy 392.405767 -160.687318)
			(xy 392.413265 -160.782345) (xy 392.413744 -160.830006) (xy 392.413267 -160.880192) (xy 392.404978 -160.98022)
			(xy 392.388457 -161.079222) (xy 392.363817 -161.176522) (xy 392.331225 -161.271455) (xy 392.290906 -161.363372)
			(xy 392.243134 -161.451646) (xy 392.188235 -161.535673) (xy 392.126585 -161.614879) (xy 392.058604 -161.688724)
			(xy 391.984758 -161.756703) (xy 391.90555 -161.818351) (xy 391.821522 -161.873248) (xy 391.733247 -161.921018)
			(xy 391.641329 -161.961335) (xy 391.546395 -161.993925) (xy 391.449095 -162.018563) (xy 391.350092 -162.035082)
			(xy 391.250064 -162.043368) (xy 391.199878 -162.043872) (xy 391.152216 -162.043418) (xy 391.057185 -162.03593)
			(xy 390.963035 -162.02101) (xy 390.870345 -161.99875) (xy 390.779688 -161.969287) (xy 390.691621 -161.932803)
			(xy 390.606688 -161.889522) (xy 390.525412 -161.839711) (xy 390.448294 -161.783678) (xy 390.37581 -161.721767)
			(xy 390.308406 -161.654361) (xy 390.277096 -161.618422) (xy 390.269535 -161.610387) (xy 390.249509 -161.601178)
			(xy 390.238488 -161.600642) (xy 390.161272 -161.600642) (xy 390.150249 -161.601151) (xy 390.130232 -161.61039)
			(xy 390.122664 -161.618422) (xy 390.091374 -161.654377) (xy 390.023958 -161.721768) (xy 389.951465 -161.783666)
			(xy 389.874341 -161.839688) (xy 389.793062 -161.88949) (xy 389.708128 -161.932764) (xy 389.620062 -161.969245)
			(xy 389.529406 -161.998708) (xy 389.436719 -162.020971) (xy 389.342571 -162.035897) (xy 389.247544 -162.043394)
			(xy 389.199882 -162.043872) (xy 389.145602 -162.043262) (xy 389.037477 -162.03354) (xy 388.930654 -162.014192)
			(xy 388.825987 -161.985374) (xy 388.77494 -161.96691) (xy 388.761986 -161.962084) (xy 388.73557 -161.966656)
			(xy 388.646416 -162.040316) (xy 388.637018 -162.06597) (xy 388.639304 -162.079432) (xy 388.648117 -162.132911)
			(xy 388.65875 -162.240785) (xy 388.66136 -162.34915) (xy 388.655931 -162.457411) (xy 388.642494 -162.564971)
			(xy 388.621122 -162.67124) (xy 388.591933 -162.775633) (xy 388.555087 -162.877575) (xy 388.510788 -162.976507)
			(xy 388.459279 -163.071883) (xy 388.400842 -163.163179) (xy 388.335801 -163.249894) (xy 388.264511 -163.331549)
			(xy 388.187366 -163.407697) (xy 388.10479 -163.477918) (xy 388.017236 -163.541825) (xy 387.925187 -163.599069)
			(xy 387.829149 -163.649333) (xy 387.729649 -163.692341) (xy 387.627236 -163.727856) (xy 387.522472 -163.755684)
			(xy 387.415934 -163.775672) (xy 387.308208 -163.787708) (xy 387.199886 -163.791727) (xy 387.091564 -163.787708)
			(xy 386.983838 -163.775672) (xy 386.8773 -163.755684) (xy 386.772536 -163.727856) (xy 386.670123 -163.692341)
			(xy 386.570623 -163.649333) (xy 386.474585 -163.599069) (xy 386.382536 -163.541825) (xy 386.294982 -163.477918)
			(xy 386.212406 -163.407697) (xy 386.135261 -163.331549) (xy 386.063971 -163.249894) (xy 385.99893 -163.163179)
			(xy 385.940493 -163.071883) (xy 385.888984 -162.976507) (xy 385.844685 -162.877575) (xy 385.807839 -162.775633)
			(xy 385.77865 -162.67124) (xy 385.757278 -162.564971) (xy 385.743841 -162.457411) (xy 385.738412 -162.34915)
			(xy 385.741022 -162.240785) (xy 385.751655 -162.132911) (xy 385.760468 -162.079432) (xy 385.762754 -162.06597)
			(xy 385.753356 -162.040316) (xy 385.664202 -161.966656) (xy 385.637786 -161.962084) (xy 385.624832 -161.96691)
			(xy 385.573782 -161.985364) (xy 385.469113 -162.014163) (xy 385.362291 -162.033508) (xy 385.254169 -162.043246)
			(xy 385.19989 -162.043872) (xy 385.152228 -162.04341) (xy 385.057197 -162.035923) (xy 384.963047 -162.021004)
			(xy 384.870358 -161.998744) (xy 384.7797 -161.969282) (xy 384.691634 -161.932798) (xy 384.6067 -161.889518)
			(xy 384.525424 -161.839709) (xy 384.448307 -161.783676) (xy 384.375822 -161.721766) (xy 384.308418 -161.654361)
			(xy 384.277108 -161.618422) (xy 384.269543 -161.610392) (xy 384.24952 -161.601181) (xy 384.2385 -161.600642)
			(xy 384.161284 -161.600642) (xy 384.150262 -161.601158) (xy 384.130245 -161.610391) (xy 384.122676 -161.618422)
			(xy 384.091379 -161.654371) (xy 384.023964 -161.721763) (xy 383.951472 -161.78366) (xy 383.874349 -161.839683)
			(xy 383.793071 -161.889485) (xy 383.708137 -161.93276) (xy 383.620071 -161.969242) (xy 383.529416 -161.998705)
			(xy 383.43673 -162.020969) (xy 383.342583 -162.035895) (xy 383.247555 -162.043394) (xy 383.199894 -162.043872)
			(xy 383.14971 -162.043353) (xy 383.049684 -162.035065) (xy 382.950684 -162.018544) (xy 382.853387 -161.993905)
			(xy 382.758456 -161.961315) (xy 382.666541 -161.920997) (xy 382.57827 -161.873226) (xy 382.494245 -161.81833)
			(xy 382.41504 -161.756682) (xy 382.341196 -161.688704) (xy 382.273218 -161.61486) (xy 382.21157 -161.535655)
			(xy 382.156674 -161.45163) (xy 382.108903 -161.363359) (xy 382.068585 -161.271444) (xy 382.035995 -161.176513)
			(xy 382.011356 -161.079216) (xy 381.994835 -160.980216) (xy 381.986547 -160.88019) (xy 381.986028 -160.830006)
			(xy 378.21362 -160.830006) (xy 378.213154 -160.880185) (xy 378.204867 -160.9802) (xy 378.188349 -161.07919)
			(xy 378.163715 -161.176478) (xy 378.131132 -161.271399) (xy 378.090823 -161.363306) (xy 378.043062 -161.451571)
			(xy 377.988176 -161.535591) (xy 377.92654 -161.614791) (xy 377.858576 -161.688633) (xy 377.784746 -161.75661)
			(xy 377.705555 -161.818259) (xy 377.621544 -161.873158) (xy 377.533288 -161.920934) (xy 377.441387 -161.961259)
			(xy 377.346471 -161.993858) (xy 377.249188 -162.018508) (xy 377.150201 -162.035042) (xy 377.050187 -162.043345)
			(xy 377.000008 -162.043872) (xy 376.952346 -162.043397) (xy 376.857316 -162.035911) (xy 376.763166 -162.020993)
			(xy 376.670477 -161.998736) (xy 376.57982 -161.969275) (xy 376.491753 -161.932792) (xy 376.40682 -161.889513)
			(xy 376.325543 -161.839705) (xy 376.248425 -161.783673) (xy 376.175941 -161.721765) (xy 376.108536 -161.65436)
			(xy 376.077226 -161.618422) (xy 376.069653 -161.6104) (xy 376.049636 -161.601184) (xy 376.038618 -161.600642)
			(xy 375.961402 -161.600642) (xy 375.950381 -161.601168) (xy 375.930364 -161.610394) (xy 375.922794 -161.618422)
			(xy 375.891487 -161.654362) (xy 375.824073 -161.721754) (xy 375.751582 -161.783652) (xy 375.67446 -161.839675)
			(xy 375.593183 -161.889478) (xy 375.50825 -161.932754) (xy 375.420186 -161.969236) (xy 375.329532 -161.998701)
			(xy 375.236846 -162.020965) (xy 375.1427 -162.035893) (xy 375.047673 -162.043393) (xy 375.000012 -162.043872)
			(xy 374.950031 -162.043367) (xy 374.850408 -162.035131) (xy 374.7518 -162.01873) (xy 374.654875 -161.994275)
			(xy 374.56029 -161.961933) (xy 374.468684 -161.921921) (xy 374.380679 -161.874511) (xy 374.296872 -161.820025)
			(xy 374.217828 -161.758831) (xy 374.144086 -161.691345) (xy 374.076142 -161.618022) (xy 374.014459 -161.53936)
			(xy 373.959454 -161.455892) (xy 373.911499 -161.368183) (xy 373.87092 -161.276828) (xy 373.83799 -161.182445)
			(xy 373.812935 -161.085673) (xy 373.803926 -161.036508) (xy 373.801331 -161.024879) (xy 373.787304 -161.005662)
			(xy 373.777002 -160.999678) (xy 373.693436 -160.957514) (xy 373.669814 -160.95726) (xy 373.658892 -160.962594)
			(xy 373.611617 -160.985464) (xy 373.514417 -161.025256) (xy 373.414651 -161.058087) (xy 373.312816 -161.083794)
			(xy 373.20942 -161.102248) (xy 373.10498 -161.113358) (xy 373.000016 -161.117067) (xy 372.895052 -161.113358)
			(xy 372.790612 -161.102248) (xy 372.687216 -161.083794) (xy 372.585381 -161.058087) (xy 372.485615 -161.025256)
			(xy 372.388415 -160.985464) (xy 372.34114 -160.962594) (xy 372.330237 -160.95791) (xy 372.306532 -160.958058)
			(xy 372.295674 -160.962848) (xy 372.22303 -160.999678) (xy 372.212755 -161.0057) (xy 372.198706 -161.024888)
			(xy 372.196106 -161.036508) (xy 372.187109 -161.085678) (xy 372.16207 -161.182458) (xy 372.129154 -161.276851)
			(xy 372.088584 -161.368216) (xy 372.040637 -161.455934) (xy 371.985635 -161.539411) (xy 371.923954 -161.61808)
			(xy 371.856009 -161.691408) (xy 371.782263 -161.758898) (xy 371.703215 -161.820093) (xy 371.619401 -161.874578)
			(xy 371.531389 -161.921984) (xy 371.439775 -161.961989) (xy 371.345181 -161.994321) (xy 371.248248 -162.018763)
			(xy 371.149633 -162.035148) (xy 371.050004 -162.043365) (xy 371.00002 -162.043872) (xy 370.952358 -162.043388)
			(xy 370.857328 -162.035903) (xy 370.763179 -162.020987) (xy 370.67049 -161.99873) (xy 370.579832 -161.96927)
			(xy 370.491766 -161.932788) (xy 370.406832 -161.88951) (xy 370.325556 -161.839702) (xy 370.248438 -161.783672)
			(xy 370.175953 -161.721764) (xy 370.108548 -161.65436) (xy 370.077238 -161.618422) (xy 370.06966 -161.610406)
			(xy 370.049647 -161.601186) (xy 370.03863 -161.600642) (xy 369.961414 -161.600642) (xy 369.950394 -161.601175)
			(xy 369.930377 -161.610396) (xy 369.922806 -161.618422) (xy 369.891493 -161.654356) (xy 369.824079 -161.721748)
			(xy 369.751589 -161.783647) (xy 369.674468 -161.83967) (xy 369.593191 -161.889473) (xy 369.508259 -161.93275)
			(xy 369.420196 -161.969233) (xy 369.329542 -161.998698) (xy 369.236857 -162.020963) (xy 369.142711 -162.035892)
			(xy 369.047685 -162.043392) (xy 369.000024 -162.043872) (xy 368.949856 -162.043371) (xy 368.849863 -162.035088)
			(xy 368.750895 -162.018577) (xy 368.653628 -161.99395) (xy 368.558727 -161.961376) (xy 368.466839 -161.921078)
			(xy 368.378593 -161.873329) (xy 368.294591 -161.818457) (xy 368.215407 -161.756836) (xy 368.141581 -161.688887)
			(xy 368.073618 -161.615075) (xy 368.011981 -161.535903) (xy 367.957093 -161.451911) (xy 367.909327 -161.363675)
			(xy 367.86901 -161.271795) (xy 367.836418 -161.1769) (xy 367.811772 -161.079638) (xy 367.795241 -160.980674)
			(xy 367.786939 -160.880682) (xy 367.786412 -160.830514) (xy 367.786412 -160.830006) (xy 367.786905 -160.78235)
			(xy 367.794373 -160.687331) (xy 367.80927 -160.59319) (xy 367.831506 -160.500508) (xy 367.860943 -160.409856)
			(xy 367.897399 -160.321791) (xy 367.94065 -160.236858) (xy 367.99043 -160.155578) (xy 368.046432 -160.078454)
			(xy 368.108311 -160.00596) (xy 368.175685 -159.938542) (xy 368.211608 -159.907224) (xy 368.219619 -159.899642)
			(xy 368.228844 -159.879632) (xy 368.229388 -159.868616) (xy 368.229388 -159.7914) (xy 368.228854 -159.780381)
			(xy 368.219632 -159.760364) (xy 368.211608 -159.752792) (xy 368.173995 -159.719957) (xy 368.103675 -159.649064)
			(xy 368.039416 -159.572635) (xy 367.981654 -159.491184) (xy 367.930779 -159.405264) (xy 367.887134 -159.315454)
			(xy 367.851015 -159.222363) (xy 367.822666 -159.126619) (xy 367.802279 -159.028869) (xy 367.789991 -158.929775)
			(xy 367.785885 -158.830006) (xy 366.214202 -158.830006) (xy 366.210096 -158.929777) (xy 366.197807 -159.028873)
			(xy 366.177418 -159.126625) (xy 366.149068 -159.22237) (xy 366.112947 -159.315464) (xy 366.0693 -159.405274)
			(xy 366.018422 -159.491196) (xy 365.960657 -159.572647) (xy 365.896396 -159.649077) (xy 365.826073 -159.719969)
			(xy 365.788448 -159.752792) (xy 365.780422 -159.760361) (xy 365.771208 -159.780381) (xy 365.770668 -159.7914)
			(xy 365.770668 -159.868616) (xy 365.771207 -159.879634) (xy 365.780427 -159.89965) (xy 365.788448 -159.907224)
			(xy 365.824398 -159.938513) (xy 365.891767 -160.005937) (xy 365.953641 -160.078437) (xy 366.00964 -160.155566)
			(xy 366.059417 -160.236849) (xy 366.102668 -160.321785) (xy 366.139124 -160.409851) (xy 366.168563 -160.500505)
			(xy 366.190801 -160.593187) (xy 366.205703 -160.687329) (xy 366.213177 -160.782349) (xy 366.213644 -160.830006)
			(xy 366.213154 -160.880184) (xy 366.204867 -160.980199) (xy 366.18835 -161.079187) (xy 366.163717 -161.176473)
			(xy 366.131134 -161.271394) (xy 366.090826 -161.3633) (xy 366.043066 -161.451564) (xy 365.988182 -161.535583)
			(xy 365.926547 -161.614783) (xy 365.858584 -161.688624) (xy 365.784756 -161.756601) (xy 365.705567 -161.81825)
			(xy 365.621558 -161.87315) (xy 365.533303 -161.920926) (xy 365.441404 -161.961252) (xy 365.34649 -161.993852)
			(xy 365.249208 -162.018504) (xy 365.150223 -162.035039) (xy 365.05021 -162.043344) (xy 365.000032 -162.043872)
			(xy 364.95237 -162.043379) (xy 364.857341 -162.035896) (xy 364.763192 -162.02098) (xy 364.670502 -161.998724)
			(xy 364.579845 -161.969265) (xy 364.491778 -161.932784) (xy 364.406845 -161.889507) (xy 364.325569 -161.8397)
			(xy 364.24845 -161.78367) (xy 364.175965 -161.721763) (xy 364.10856 -161.65436) (xy 364.07725 -161.618422)
			(xy 364.069668 -161.610411) (xy 364.049658 -161.601189) (xy 364.038642 -161.600642) (xy 363.961426 -161.600642)
			(xy 363.950407 -161.601181) (xy 363.93039 -161.610398) (xy 363.922818 -161.618422) (xy 363.891498 -161.65435)
			(xy 363.824086 -161.721743) (xy 363.751596 -161.783641) (xy 363.674476 -161.839665) (xy 363.5932 -161.889469)
			(xy 363.508268 -161.932746) (xy 363.420205 -161.969229) (xy 363.329552 -161.998695) (xy 363.236868 -162.020961)
			(xy 363.142723 -162.035891) (xy 363.047697 -162.043392) (xy 363.000036 -162.043872) (xy 362.949868 -162.04336)
			(xy 362.849875 -162.035078) (xy 362.750907 -162.018567) (xy 362.653641 -161.993942) (xy 362.55874 -161.961369)
			(xy 362.466852 -161.92107) (xy 362.378606 -161.873323) (xy 362.294604 -161.818451) (xy 362.21542 -161.756831)
			(xy 362.141594 -161.688883) (xy 362.07363 -161.615071) (xy 362.011994 -161.535899) (xy 361.957105 -161.451909)
			(xy 361.909339 -161.363672) (xy 361.869022 -161.271793) (xy 361.83643 -161.176899) (xy 361.811784 -161.079638)
			(xy 361.795253 -160.980673) (xy 361.786951 -160.880682) (xy 361.786424 -160.830514) (xy 361.786424 -160.830006)
			(xy 361.786913 -160.78235) (xy 361.794381 -160.687331) (xy 361.809279 -160.59319) (xy 361.831514 -160.500508)
			(xy 361.860951 -160.409855) (xy 361.897408 -160.321791) (xy 361.94066 -160.236857) (xy 361.99044 -160.155578)
			(xy 362.046442 -160.078453) (xy 362.108322 -160.005959) (xy 362.175696 -159.938542) (xy 362.21162 -159.907224)
			(xy 362.219633 -159.899643) (xy 362.228856 -159.879633) (xy 362.2294 -159.868616) (xy 362.2294 -159.7914)
			(xy 362.228862 -159.780381) (xy 362.219642 -159.760365) (xy 362.21162 -159.752792) (xy 362.174006 -159.719957)
			(xy 362.103686 -159.649065) (xy 362.039427 -159.572635) (xy 361.981664 -159.491185) (xy 361.930788 -159.405265)
			(xy 361.887143 -159.315455) (xy 361.851024 -159.222363) (xy 361.822675 -159.126619) (xy 361.802287 -159.028869)
			(xy 361.789999 -158.929775) (xy 361.785893 -158.830006) (xy 359.492747 -158.830006) (xy 359.596877 -158.939217)
			(xy 359.706261 -159.065454) (xy 359.809514 -159.196753) (xy 359.906403 -159.332816) (xy 359.996708 -159.473335)
			(xy 360.080225 -159.617992) (xy 360.156764 -159.766459) (xy 360.226152 -159.9184) (xy 360.288231 -160.07347)
			(xy 360.342862 -160.231318) (xy 360.389921 -160.391587) (xy 360.4293 -160.553913) (xy 360.460911 -160.71793)
			(xy 360.484682 -160.883264) (xy 360.50056 -161.049543) (xy 360.508507 -161.216389) (xy 360.509058 -161.299906)
			(xy 360.509058 -166.649908) (xy 360.509557 -166.745241) (xy 360.51765 -166.935736) (xy 360.53382 -167.125715)
			(xy 360.558038 -167.314837) (xy 360.590261 -167.502761) (xy 360.629411 -167.684417) (xy 365.513608 -167.684417)
			(xy 365.513608 -167.575771) (xy 365.521539 -167.467414) (xy 365.537358 -167.359925) (xy 365.560981 -167.253878)
			(xy 365.592282 -167.149838) (xy 365.631094 -167.04836) (xy 365.677209 -166.949986) (xy 365.730383 -166.855241)
			(xy 365.790331 -166.76463) (xy 365.856733 -166.678636) (xy 365.929235 -166.597719) (xy 366.00745 -166.522311)
			(xy 366.090961 -166.452812) (xy 366.179322 -166.389595) (xy 366.272062 -166.332997) (xy 366.368686 -166.283319)
			(xy 366.468678 -166.240827) (xy 366.571506 -166.205747) (xy 366.67662 -166.178267) (xy 366.783459 -166.158532)
			(xy 366.891454 -166.146649) (xy 367.000028 -166.142682) (xy 367.108602 -166.146649) (xy 367.216597 -166.158532)
			(xy 367.323436 -166.178267) (xy 367.42855 -166.205747) (xy 367.531378 -166.240827) (xy 367.63137 -166.283319)
			(xy 367.727994 -166.332997) (xy 367.820734 -166.389595) (xy 367.909095 -166.452812) (xy 367.992606 -166.522311)
			(xy 368.070821 -166.597719) (xy 368.143323 -166.678636) (xy 368.209725 -166.76463) (xy 368.252971 -166.829996)
			(xy 397.160973 -166.829996) (xy 397.165078 -166.730227) (xy 397.177366 -166.631132) (xy 397.197754 -166.533381)
			(xy 397.226103 -166.437636) (xy 397.262222 -166.344543) (xy 397.305867 -166.254733) (xy 397.356743 -166.168811)
			(xy 397.414505 -166.08736) (xy 397.478764 -166.010929) (xy 397.549084 -165.940036) (xy 397.586708 -165.907212)
			(xy 397.594725 -165.899634) (xy 397.603946 -165.879622) (xy 397.604488 -165.868604) (xy 397.604488 -165.791388)
			(xy 397.60396 -165.780368) (xy 397.594734 -165.760351) (xy 397.586708 -165.75278) (xy 397.549083 -165.719958)
			(xy 397.478763 -165.649065) (xy 397.414504 -165.572634) (xy 397.356742 -165.491183) (xy 397.305867 -165.405261)
			(xy 397.262223 -165.315451) (xy 397.226104 -165.222358) (xy 397.197756 -165.126613) (xy 397.177369 -165.028863)
			(xy 397.165081 -164.929768) (xy 397.160976 -164.829999) (xy 397.165081 -164.730229) (xy 397.177369 -164.631135)
			(xy 397.197756 -164.533384) (xy 397.226105 -164.437639) (xy 397.262224 -164.344547) (xy 397.305869 -164.254736)
			(xy 397.356744 -164.168815) (xy 397.414506 -164.087364) (xy 397.478764 -164.010933) (xy 397.549085 -163.94004)
			(xy 397.586708 -163.907216) (xy 397.594723 -163.899637) (xy 397.603946 -163.879625) (xy 397.604488 -163.868608)
			(xy 397.604488 -163.791392) (xy 397.603958 -163.780372) (xy 397.594733 -163.760355) (xy 397.586708 -163.752784)
			(xy 397.549087 -163.719958) (xy 397.478767 -163.649065) (xy 397.414508 -163.572634) (xy 397.356746 -163.491183)
			(xy 397.305871 -163.405262) (xy 397.262227 -163.315452) (xy 397.226108 -163.22236) (xy 397.197759 -163.126615)
			(xy 397.177372 -163.028865) (xy 397.165084 -162.92977) (xy 397.160979 -162.830001) (xy 397.165084 -162.730232)
			(xy 397.177372 -162.631138) (xy 397.197759 -162.533388) (xy 397.226107 -162.437643) (xy 397.262226 -162.34455)
			(xy 397.30587 -162.25474) (xy 397.356745 -162.168819) (xy 397.414507 -162.087368) (xy 397.478765 -162.010937)
			(xy 397.549085 -161.940044) (xy 397.586708 -161.90722) (xy 397.594721 -161.899639) (xy 397.603945 -161.879629)
			(xy 397.604488 -161.868612) (xy 397.604488 -161.791396) (xy 397.603956 -161.780376) (xy 397.594733 -161.76036)
			(xy 397.586708 -161.752788) (xy 397.549091 -161.719957) (xy 397.478771 -161.649065) (xy 397.414512 -161.572634)
			(xy 397.35675 -161.491184) (xy 397.305875 -161.405263) (xy 397.262231 -161.315453) (xy 397.226112 -161.222361)
			(xy 397.197763 -161.126617) (xy 397.177375 -161.028867) (xy 397.165088 -160.929773) (xy 397.160982 -160.830004)
			(xy 397.165087 -160.730235) (xy 397.177374 -160.631141) (xy 397.197761 -160.533391) (xy 397.226109 -160.437646)
			(xy 397.262227 -160.344554) (xy 397.305871 -160.254744) (xy 397.356746 -160.168823) (xy 397.414508 -160.087372)
			(xy 397.478765 -160.010941) (xy 397.549085 -159.940048) (xy 397.586708 -159.907224) (xy 397.594719 -159.899642)
			(xy 397.603944 -159.879632) (xy 397.604488 -159.868616) (xy 397.604488 -159.7914) (xy 397.603954 -159.780381)
			(xy 397.594732 -159.760364) (xy 397.586708 -159.752792) (xy 397.549095 -159.719957) (xy 397.478775 -159.649064)
			(xy 397.414516 -159.572635) (xy 397.356754 -159.491184) (xy 397.305879 -159.405264) (xy 397.262234 -159.315454)
			(xy 397.226115 -159.222363) (xy 397.197766 -159.126619) (xy 397.177379 -159.028869) (xy 397.165091 -158.929775)
			(xy 397.160985 -158.830006) (xy 397.16509 -158.730238) (xy 397.177377 -158.631144) (xy 397.197763 -158.533394)
			(xy 397.226111 -158.43765) (xy 397.262229 -158.344558) (xy 397.305873 -158.254748) (xy 397.356747 -158.168827)
			(xy 397.414508 -158.087376) (xy 397.478766 -158.010945) (xy 397.549085 -157.940052) (xy 397.586708 -157.907228)
			(xy 397.594718 -157.899644) (xy 397.603943 -157.879636) (xy 397.604488 -157.86862) (xy 397.604488 -157.791404)
			(xy 397.603952 -157.780385) (xy 397.594731 -157.760368) (xy 397.586708 -157.752796) (xy 397.549099 -157.719956)
			(xy 397.478779 -157.649064) (xy 397.41452 -157.572635) (xy 397.356758 -157.491185) (xy 397.305883 -157.405265)
			(xy 397.262238 -157.315455) (xy 397.226119 -157.222364) (xy 397.19777 -157.12662) (xy 397.177382 -157.028871)
			(xy 397.165094 -156.929777) (xy 397.160988 -156.830009) (xy 397.165093 -156.730241) (xy 397.177379 -156.631147)
			(xy 397.197766 -156.533397) (xy 397.226113 -156.437653) (xy 397.262231 -156.344561) (xy 397.305874 -156.254751)
			(xy 397.356748 -156.16883) (xy 397.414509 -156.08738) (xy 397.478766 -156.010949) (xy 397.549085 -155.940056)
			(xy 397.586708 -155.907232) (xy 397.594716 -155.899646) (xy 397.603942 -155.87964) (xy 397.604488 -155.868624)
			(xy 397.604488 -155.791408) (xy 397.603949 -155.780389) (xy 397.594731 -155.760372) (xy 397.586708 -155.7528)
			(xy 397.549103 -155.719956) (xy 397.478783 -155.649064) (xy 397.414524 -155.572635) (xy 397.356762 -155.491185)
			(xy 397.305887 -155.405266) (xy 397.262242 -155.315457) (xy 397.226123 -155.222366) (xy 397.197774 -155.126622)
			(xy 397.177386 -155.028873) (xy 397.165097 -154.92978) (xy 397.160991 -154.830012) (xy 397.165095 -154.730244)
			(xy 397.177382 -154.63115) (xy 397.197768 -154.533401) (xy 397.226115 -154.437656) (xy 397.262233 -154.344565)
			(xy 397.305876 -154.254755) (xy 397.35675 -154.168834) (xy 397.41451 -154.087383) (xy 397.478767 -154.010953)
			(xy 397.549085 -153.94006) (xy 397.586708 -153.907236) (xy 397.594714 -153.899649) (xy 397.603942 -153.879643)
			(xy 397.604488 -153.868628) (xy 397.604488 -153.791412) (xy 397.603947 -153.780393) (xy 397.59473 -153.760377)
			(xy 397.586708 -153.752804) (xy 397.550784 -153.721486) (xy 397.483413 -153.654066) (xy 397.421536 -153.58157)
			(xy 397.365535 -153.504444) (xy 397.315755 -153.423165) (xy 397.272502 -153.338232) (xy 397.236043 -153.250169)
			(xy 397.206602 -153.159517) (xy 397.184361 -153.066836) (xy 397.169456 -152.972697) (xy 397.16198 -152.877678)
			(xy 397.161512 -152.830022) (xy 397.162073 -152.779845) (xy 397.170357 -152.679834) (xy 397.186871 -152.580848)
			(xy 397.211501 -152.483564) (xy 397.24408 -152.388646) (xy 397.284385 -152.296742) (xy 397.332141 -152.208479)
			(xy 397.387021 -152.124461) (xy 397.448651 -152.045262) (xy 397.51661 -151.971421) (xy 397.590434 -151.903444)
			(xy 397.669619 -151.841794) (xy 397.753623 -151.786893) (xy 397.841874 -151.739116) (xy 397.933768 -151.698789)
			(xy 398.028678 -151.666187) (xy 398.125957 -151.641532) (xy 398.224938 -151.624994) (xy 398.324947 -151.616685)
			(xy 398.375124 -151.616156) (xy 398.422787 -151.616598) (xy 398.517818 -151.624087) (xy 398.611969 -151.639007)
			(xy 398.704659 -151.661268) (xy 398.795316 -151.690732) (xy 398.883383 -151.727218) (xy 398.968317 -151.7705)
			(xy 399.049592 -151.820312) (xy 399.12671 -151.876346) (xy 399.199193 -151.938258) (xy 399.266597 -152.005666)
			(xy 399.297906 -152.041606) (xy 399.305477 -152.049631) (xy 399.325495 -152.058848) (xy 399.336514 -152.059386)
			(xy 399.41373 -152.059386) (xy 399.424752 -152.058869) (xy 399.444768 -152.049635) (xy 399.452338 -152.041606)
			(xy 399.483634 -152.005656) (xy 399.551049 -151.938264) (xy 399.623541 -151.876366) (xy 399.700663 -151.820343)
			(xy 399.781942 -151.77054) (xy 399.866876 -151.727265) (xy 399.954941 -151.690783) (xy 400.045597 -151.66132)
			(xy 400.138284 -151.639057) (xy 400.232431 -151.624131) (xy 400.327459 -151.616634) (xy 400.37512 -151.616156)
			(xy 400.425287 -151.616687) (xy 400.525277 -151.624972) (xy 400.624243 -151.641486) (xy 400.721506 -151.666114)
			(xy 400.816405 -151.698689) (xy 400.908289 -151.738988) (xy 400.996533 -151.786735) (xy 401.080533 -151.841606)
			(xy 401.159716 -151.903225) (xy 401.23354 -151.971171) (xy 401.301503 -152.044981) (xy 401.363139 -152.12415)
			(xy 401.418028 -152.208138) (xy 401.465796 -152.296372) (xy 401.506115 -152.388247) (xy 401.53871 -152.483139)
			(xy 401.56336 -152.580397) (xy 401.579895 -152.679359) (xy 401.588202 -152.779347) (xy 401.588732 -152.829514)
			(xy 401.588732 -152.830022) (xy 401.588278 -152.877679) (xy 401.580808 -152.9727) (xy 401.565908 -153.066842)
			(xy 401.543669 -153.159525) (xy 401.514229 -153.250178) (xy 401.477769 -153.338243) (xy 401.434513 -153.423176)
			(xy 401.384729 -153.504455) (xy 401.328723 -153.581579) (xy 401.26684 -153.654072) (xy 401.199462 -153.721487)
			(xy 401.163536 -153.752804) (xy 401.155503 -153.760367) (xy 401.146292 -153.780391) (xy 401.145756 -153.791412)
			(xy 401.145756 -153.868628) (xy 401.146261 -153.879651) (xy 401.155502 -153.899669) (xy 401.163536 -153.907236)
			(xy 401.201179 -153.940039) (xy 401.271502 -154.010932) (xy 401.335763 -154.087363) (xy 401.393527 -154.168815)
			(xy 401.444405 -154.254738) (xy 401.488051 -154.34455) (xy 401.524171 -154.437644) (xy 401.55252 -154.533391)
			(xy 401.572908 -154.631143) (xy 401.585195 -154.73024) (xy 401.5893 -154.830012) (xy 401.585193 -154.929783)
			(xy 401.572904 -155.02888) (xy 401.552515 -155.126632) (xy 401.524163 -155.222378) (xy 401.488042 -155.315472)
			(xy 401.444394 -155.405283) (xy 401.393515 -155.491204) (xy 401.335749 -155.572655) (xy 401.271486 -155.649085)
			(xy 401.201162 -155.719977) (xy 401.163536 -155.7528) (xy 401.155505 -155.760364) (xy 401.146293 -155.780388)
			(xy 401.145756 -155.791408) (xy 401.145756 -155.868624) (xy 401.146263 -155.879647) (xy 401.155502 -155.899664)
			(xy 401.163536 -155.907232) (xy 401.201175 -155.94004) (xy 401.271498 -156.010932) (xy 401.335759 -156.087363)
			(xy 401.393523 -156.168815) (xy 401.444401 -156.254737) (xy 401.488047 -156.344549) (xy 401.524167 -156.437643)
			(xy 401.552517 -156.533389) (xy 401.572904 -156.631141) (xy 401.585192 -156.730238) (xy 401.589297 -156.830009)
			(xy 401.585191 -156.92978) (xy 401.572901 -157.028877) (xy 401.552512 -157.126628) (xy 401.524161 -157.222375)
			(xy 401.48804 -157.315468) (xy 401.444392 -157.405279) (xy 401.393514 -157.4912) (xy 401.335748 -157.572651)
			(xy 401.271486 -157.649081) (xy 401.201161 -157.719973) (xy 401.163536 -157.752796) (xy 401.155507 -157.760362)
			(xy 401.146294 -157.780384) (xy 401.145756 -157.791404) (xy 401.145756 -157.86862) (xy 401.146265 -157.879643)
			(xy 401.155503 -157.89966) (xy 401.163536 -157.907228) (xy 401.201171 -157.94004) (xy 401.271494 -158.010933)
			(xy 401.335755 -158.087363) (xy 401.393519 -158.168814) (xy 401.444397 -158.254736) (xy 401.488043 -158.344548)
			(xy 401.524163 -158.437641) (xy 401.552513 -158.533387) (xy 401.572901 -158.631139) (xy 401.585189 -158.730236)
			(xy 401.589294 -158.830006) (xy 401.585188 -158.929777) (xy 401.572899 -159.028874) (xy 401.55251 -159.126625)
			(xy 401.524159 -159.222371) (xy 401.488038 -159.315464) (xy 401.444391 -159.405275) (xy 401.393512 -159.491197)
			(xy 401.335747 -159.572647) (xy 401.271485 -159.649077) (xy 401.201161 -159.719969) (xy 401.163536 -159.752792)
			(xy 401.155508 -159.760359) (xy 401.146295 -159.78038) (xy 401.145756 -159.7914) (xy 401.145756 -159.868616)
			(xy 401.146267 -159.879639) (xy 401.155504 -159.899656) (xy 401.163536 -159.907224) (xy 401.201167 -159.940041)
			(xy 401.27149 -160.010933) (xy 401.335751 -160.087363) (xy 401.393516 -160.168814) (xy 401.444393 -160.254735)
			(xy 401.488039 -160.344546) (xy 401.52416 -160.43764) (xy 401.55251 -160.533386) (xy 401.572898 -160.631137)
			(xy 401.585186 -160.730233) (xy 401.589291 -160.830004) (xy 401.585185 -160.929774) (xy 401.572896 -161.028871)
			(xy 401.552508 -161.126622) (xy 401.524157 -161.222368) (xy 401.488036 -161.315461) (xy 401.444389 -161.405272)
			(xy 401.393511 -161.491193) (xy 401.335746 -161.572643) (xy 401.271485 -161.649073) (xy 401.201161 -161.719965)
			(xy 401.163536 -161.752788) (xy 401.15551 -161.760357) (xy 401.146296 -161.780377) (xy 401.145756 -161.791396)
			(xy 401.145756 -161.868612) (xy 401.146269 -161.879634) (xy 401.155504 -161.899652) (xy 401.163536 -161.90722)
			(xy 401.201163 -161.940041) (xy 401.271486 -162.010933) (xy 401.335747 -162.087363) (xy 401.393512 -162.168813)
			(xy 401.444389 -162.254734) (xy 401.488036 -162.344545) (xy 401.524156 -162.437638) (xy 401.552506 -162.533384)
			(xy 401.572894 -162.631135) (xy 401.585182 -162.730231) (xy 401.589288 -162.830001) (xy 401.585182 -162.929772)
			(xy 401.572894 -163.028867) (xy 401.552505 -163.126619) (xy 401.524155 -163.222364) (xy 401.488035 -163.315457)
			(xy 401.444388 -163.405268) (xy 401.39351 -163.491189) (xy 401.335745 -163.57264) (xy 401.271484 -163.649069)
			(xy 401.201161 -163.719961) (xy 401.163536 -163.752784) (xy 401.155512 -163.760355) (xy 401.146296 -163.780373)
			(xy 401.145756 -163.791392) (xy 401.145756 -163.868608) (xy 401.146272 -163.87963) (xy 401.155505 -163.899648)
			(xy 401.163536 -163.907216) (xy 401.201159 -163.940041) (xy 401.271482 -164.010933) (xy 401.335743 -164.087362)
			(xy 401.393508 -164.168813) (xy 401.444385 -164.254734) (xy 401.488032 -164.344544) (xy 401.524152 -164.437637)
			(xy 401.552503 -164.533382) (xy 401.572891 -164.631133) (xy 401.585179 -164.730229) (xy 401.589285 -164.829999)
			(xy 401.585179 -164.929769) (xy 401.572891 -165.028864) (xy 401.552503 -165.126615) (xy 401.524153 -165.222361)
			(xy 401.488033 -165.315454) (xy 401.444386 -165.405264) (xy 401.393509 -165.491185) (xy 401.335745 -165.572636)
			(xy 401.271484 -165.649065) (xy 401.201161 -165.719957) (xy 401.163536 -165.75278) (xy 401.155514 -165.760352)
			(xy 401.146297 -165.78037) (xy 401.145756 -165.791388) (xy 401.145756 -165.868604) (xy 401.146274 -165.879626)
			(xy 401.155505 -165.899643) (xy 401.163536 -165.907212) (xy 401.201155 -165.940042) (xy 401.271478 -166.010933)
			(xy 401.335739 -166.087362) (xy 401.393504 -166.168812) (xy 401.444381 -166.254733) (xy 401.488028 -166.344543)
			(xy 401.524149 -166.437635) (xy 401.552499 -166.53338) (xy 401.572887 -166.631131) (xy 401.585176 -166.730226)
			(xy 401.589282 -166.829996) (xy 401.585177 -166.929766) (xy 401.572889 -167.028861) (xy 401.552501 -167.126612)
			(xy 401.524151 -167.222357) (xy 401.488031 -167.31545) (xy 401.444385 -167.40526) (xy 401.393508 -167.491181)
			(xy 401.335744 -167.572632) (xy 401.271483 -167.649061) (xy 401.201161 -167.719953) (xy 401.163536 -167.752776)
			(xy 401.155516 -167.76035) (xy 401.146298 -167.780366) (xy 401.145756 -167.791384) (xy 401.145756 -167.8686)
			(xy 401.146276 -167.879622) (xy 401.155506 -167.899639) (xy 401.163536 -167.907208) (xy 401.199475 -167.938508)
			(xy 401.266845 -168.005932) (xy 401.32872 -168.07843) (xy 401.384719 -168.155558) (xy 401.434498 -168.236839)
			(xy 401.477749 -168.321774) (xy 401.514207 -168.409839) (xy 401.543646 -168.500491) (xy 401.565886 -168.593173)
			(xy 401.58079 -168.687314) (xy 401.588265 -168.782333) (xy 401.588732 -168.82999) (xy 401.588238 -168.880168)
			(xy 401.579953 -168.980183) (xy 401.563437 -169.079172) (xy 401.538804 -169.176459) (xy 401.506223 -169.271379)
			(xy 401.465915 -169.363286) (xy 401.418156 -169.45155) (xy 401.363272 -169.53557) (xy 401.301637 -169.61477)
			(xy 401.233674 -169.688611) (xy 401.159846 -169.756589) (xy 401.080657 -169.818238) (xy 400.996648 -169.873138)
			(xy 400.908392 -169.920914) (xy 400.816494 -169.961239) (xy 400.721579 -169.993839) (xy 400.624297 -170.01849)
			(xy 400.525311 -170.035024) (xy 400.425298 -170.043329) (xy 400.37512 -170.043856) (xy 400.327458 -170.043378)
			(xy 400.232428 -170.035893) (xy 400.138278 -170.020976) (xy 400.045589 -169.998719) (xy 399.954931 -169.969258)
			(xy 399.866864 -169.932776) (xy 399.781931 -169.889498) (xy 399.700655 -169.839689) (xy 399.623537 -169.783658)
			(xy 399.551052 -169.721749) (xy 399.483648 -169.654345) (xy 399.452338 -169.618406) (xy 399.444748 -169.610403)
			(xy 399.424745 -169.601173) (xy 399.41373 -169.600626) (xy 399.336514 -169.600626) (xy 399.325495 -169.601163)
			(xy 399.305478 -169.610382) (xy 399.297906 -169.618406) (xy 399.266589 -169.654337) (xy 399.199176 -169.721729)
			(xy 399.126687 -169.783628) (xy 399.049566 -169.839652) (xy 398.96829 -169.889456) (xy 398.883358 -169.932733)
			(xy 398.795295 -169.969216) (xy 398.704641 -169.998681) (xy 398.611956 -170.020947) (xy 398.517811 -170.035876)
			(xy 398.422785 -170.043376) (xy 398.375124 -170.043856) (xy 398.324958 -170.043271) (xy 398.224969 -170.034989)
			(xy 398.126005 -170.018479) (xy 398.028743 -169.993855) (xy 397.933845 -169.961284) (xy 397.841961 -169.920988)
			(xy 397.753718 -169.873244) (xy 397.669718 -169.818376) (xy 397.590535 -169.756761) (xy 397.516711 -169.688817)
			(xy 397.448748 -169.61501) (xy 397.387111 -169.535844) (xy 397.332221 -169.451859) (xy 397.284453 -169.363628)
			(xy 397.244133 -169.271755) (xy 397.211537 -169.176866) (xy 397.186887 -169.07961) (xy 397.170351 -168.98065)
			(xy 397.162042 -168.880664) (xy 397.161512 -168.830498) (xy 397.161512 -168.82999) (xy 397.161994 -168.782334)
			(xy 397.169463 -168.687314) (xy 397.184361 -168.593173) (xy 397.206598 -168.500491) (xy 397.236036 -168.409839)
			(xy 397.272493 -168.321774) (xy 397.315746 -168.236841) (xy 397.365527 -168.155562) (xy 397.42153 -168.078437)
			(xy 397.483409 -168.005943) (xy 397.550784 -167.938526) (xy 397.586708 -167.907208) (xy 397.594727 -167.899632)
			(xy 397.603947 -167.879618) (xy 397.604488 -167.8686) (xy 397.604488 -167.791384) (xy 397.603963 -167.780363)
			(xy 397.594735 -167.760347) (xy 397.586708 -167.752776) (xy 397.549079 -167.719959) (xy 397.478759 -167.649065)
			(xy 397.4145 -167.572634) (xy 397.356739 -167.491182) (xy 397.305863 -167.40526) (xy 397.262219 -167.31545)
			(xy 397.226101 -167.222357) (xy 397.197752 -167.126611) (xy 397.177365 -167.028861) (xy 397.165078 -166.929766)
			(xy 397.160973 -166.829996) (xy 368.252971 -166.829996) (xy 368.269673 -166.855241) (xy 368.322847 -166.949986)
			(xy 368.368962 -167.04836) (xy 368.407774 -167.149838) (xy 368.439075 -167.253878) (xy 368.462698 -167.359925)
			(xy 368.478517 -167.467414) (xy 368.486448 -167.575771) (xy 368.486944 -167.630094) (xy 368.486448 -167.684417)
			(xy 368.478517 -167.792774) (xy 368.462698 -167.900263) (xy 368.439075 -168.00631) (xy 368.407774 -168.11035)
			(xy 368.368962 -168.211828) (xy 368.322847 -168.310202) (xy 368.269673 -168.404947) (xy 368.209725 -168.495558)
			(xy 368.143323 -168.581552) (xy 368.070821 -168.662469) (xy 367.992606 -168.737877) (xy 367.909095 -168.807376)
			(xy 367.820734 -168.870593) (xy 367.727994 -168.927191) (xy 367.63137 -168.976869) (xy 367.531378 -169.019361)
			(xy 367.42855 -169.054441) (xy 367.323436 -169.081921) (xy 367.216597 -169.101656) (xy 367.108602 -169.113539)
			(xy 367.000028 -169.117507) (xy 366.891454 -169.113539) (xy 366.783459 -169.101656) (xy 366.67662 -169.081921)
			(xy 366.571506 -169.054441) (xy 366.468678 -169.019361) (xy 366.368686 -168.976869) (xy 366.272062 -168.927191)
			(xy 366.179322 -168.870593) (xy 366.090961 -168.807376) (xy 366.00745 -168.737877) (xy 365.929235 -168.662469)
			(xy 365.856733 -168.581552) (xy 365.790331 -168.495558) (xy 365.730383 -168.404947) (xy 365.677209 -168.310202)
			(xy 365.631094 -168.211828) (xy 365.592282 -168.11035) (xy 365.560981 -168.00631) (xy 365.537358 -167.900263)
			(xy 365.521539 -167.792774) (xy 365.513608 -167.684417) (xy 360.629411 -167.684417) (xy 360.630431 -167.689148)
			(xy 360.678475 -167.873662) (xy 360.734307 -168.05597) (xy 360.797826 -168.235745) (xy 360.868918 -168.412662)
			(xy 360.947454 -168.586403) (xy 361.033294 -168.756653) (xy 361.126281 -168.923107) (xy 361.22625 -169.085465)
			(xy 361.333019 -169.243433) (xy 361.446396 -169.396728) (xy 361.566177 -169.545073) (xy 361.692146 -169.6882)
			(xy 361.824076 -169.825852) (xy 361.961729 -169.957781) (xy 362.104858 -170.083749) (xy 362.253204 -170.203529)
			(xy 362.406499 -170.316905) (xy 362.564469 -170.423672) (xy 362.726827 -170.523639) (xy 362.893282 -170.616625)
			(xy 363.063534 -170.702463) (xy 363.237275 -170.780998) (xy 363.414192 -170.852088) (xy 363.593968 -170.915605)
			(xy 363.776277 -170.971436) (xy 363.960791 -171.019478) (xy 364.147178 -171.059646) (xy 364.335102 -171.091868)
			(xy 364.524225 -171.116085) (xy 364.714204 -171.132253) (xy 364.904699 -171.140344) (xy 365.000032 -171.140882)
			(xy 403.999954 -171.140882) (xy 404.095288 -171.140384) (xy 404.285785 -171.132294) (xy 404.475767 -171.116126)
			(xy 404.664891 -171.091909) (xy 404.852817 -171.059688) (xy 405.039206 -171.01952) (xy 405.223723 -170.971477)
			(xy 405.406034 -170.915647) (xy 405.585812 -170.852129) (xy 405.762731 -170.781038) (xy 405.936475 -170.702503)
			(xy 406.106728 -170.616665) (xy 406.273185 -170.523678) (xy 406.435545 -170.423711) (xy 406.593517 -170.316942)
			(xy 406.746814 -170.203565) (xy 406.895162 -170.083785) (xy 407.038292 -169.957816) (xy 407.175947 -169.825886)
			(xy 407.307879 -169.688232) (xy 407.43385 -169.545103) (xy 407.553632 -169.396757) (xy 407.667011 -169.243461)
			(xy 407.773781 -169.085491) (xy 407.873751 -168.923132) (xy 407.96674 -168.756676) (xy 408.05258 -168.586423)
			(xy 408.131117 -168.412681) (xy 408.20221 -168.235762) (xy 408.26573 -168.055986) (xy 408.321562 -167.873675)
			(xy 408.369607 -167.689159) (xy 408.409778 -167.50277) (xy 408.442001 -167.314844) (xy 408.46622 -167.12572)
			(xy 408.48239 -166.935739) (xy 408.490483 -166.745242) (xy 408.490928 -166.649908) (xy 408.490928 -163.299902)
			(xy 408.491427 -163.194368) (xy 408.499512 -162.983455) (xy 408.515669 -162.773006) (xy 408.539875 -162.563331)
			(xy 408.572094 -162.354737) (xy 408.61228 -162.14753) (xy 408.660372 -161.942014) (xy 408.716302 -161.738491)
			(xy 408.779985 -161.53726) (xy 408.85133 -161.338616) (xy 408.930231 -161.14285) (xy 409.016573 -160.95025)
			(xy 409.110228 -160.761098) (xy 409.21106 -160.575672) (xy 409.31892 -160.394245) (xy 409.43365 -160.217082)
			(xy 409.555081 -160.044444) (xy 409.683036 -159.876583) (xy 409.817327 -159.713747) (xy 409.957756 -159.556174)
			(xy 410.104118 -159.404096) (xy 410.256198 -159.257735) (xy 410.413771 -159.117306) (xy 410.576608 -158.983016)
			(xy 410.74447 -158.855062) (xy 410.917109 -158.733632) (xy 411.094272 -158.618903) (xy 411.2757 -158.511044)
			(xy 411.461126 -158.410213) (xy 411.650279 -158.316559) (xy 411.842879 -158.230219) (xy 412.038645 -158.151319)
			(xy 412.23729 -158.079975) (xy 412.438522 -158.016293) (xy 412.642045 -157.960365) (xy 412.847561 -157.912273)
			(xy 413.054769 -157.872089) (xy 413.263363 -157.839871) (xy 413.473038 -157.815666) (xy 413.683487 -157.79951)
			(xy 413.8944 -157.791427) (xy 413.999934 -157.790896) (xy 434.999892 -157.790896) (xy 435.095226 -157.79039)
			(xy 435.285721 -157.782299) (xy 435.475702 -157.766129) (xy 435.664825 -157.741911) (xy 435.85275 -157.709689)
			(xy 436.039137 -157.66952) (xy 436.223653 -157.621476) (xy 436.405963 -157.565645) (xy 436.585739 -157.502126)
			(xy 436.762657 -157.431035) (xy 436.936399 -157.3525) (xy 437.106651 -157.266661) (xy 437.273106 -157.173674)
			(xy 437.435465 -157.073706) (xy 437.593435 -156.966938) (xy 437.746732 -156.853561) (xy 437.895078 -156.73378)
			(xy 438.038207 -156.607812) (xy 438.175861 -156.475882) (xy 438.307792 -156.338229) (xy 438.433761 -156.195101)
			(xy 438.553543 -156.046755) (xy 438.66692 -155.89346) (xy 438.77369 -155.73549) (xy 438.873659 -155.573132)
			(xy 438.966647 -155.406677) (xy 439.052487 -155.236426) (xy 439.131023 -155.062685) (xy 439.202116 -154.885767)
			(xy 439.265635 -154.705991) (xy 439.321468 -154.523682) (xy 439.369513 -154.339167) (xy 439.409683 -154.152779)
			(xy 439.441907 -153.964854) (xy 439.466126 -153.775732) (xy 439.482297 -153.585751) (xy 439.49039 -153.395256)
			(xy 439.490866 -153.299922) (xy 439.490866 -136.77011) (xy 439.491377 -136.664578) (xy 439.499472 -136.453669)
			(xy 439.515639 -136.243225) (xy 439.539854 -136.033554) (xy 439.572082 -135.824965) (xy 439.612275 -135.617763)
			(xy 439.660375 -135.412253) (xy 439.71631 -135.208736) (xy 439.78 -135.00751) (xy 439.851349 -134.808871)
			(xy 439.930254 -134.613111) (xy 440.016599 -134.420517) (xy 440.110257 -134.231371) (xy 440.211091 -134.045951)
			(xy 440.318953 -133.864528) (xy 440.433684 -133.687371) (xy 440.555116 -133.514737) (xy 440.68307 -133.346881)
			(xy 440.81736 -133.184049) (xy 440.957788 -133.026479) (xy 441.104148 -132.874404) (xy 441.256225 -132.728046)
			(xy 441.413796 -132.58762) (xy 441.576629 -132.453332) (xy 441.744487 -132.325379) (xy 441.917122 -132.203949)
			(xy 442.094281 -132.08922) (xy 442.275704 -131.981361) (xy 442.461126 -131.880529) (xy 442.650273 -131.786873)
			(xy 442.842868 -131.70053) (xy 443.038629 -131.621627) (xy 443.237269 -131.55028) (xy 443.438495 -131.486593)
			(xy 443.642013 -131.430659) (xy 443.847524 -131.382562) (xy 444.054726 -131.342371) (xy 444.263316 -131.310146)
			(xy 444.472987 -131.285933) (xy 444.683431 -131.269768) (xy 444.89434 -131.261676) (xy 444.999872 -131.261104)
			(xy 471.000074 -131.261104) (xy 471.095408 -131.260599) (xy 471.285904 -131.252508) (xy 471.475885 -131.236339)
			(xy 471.665009 -131.212122) (xy 471.852935 -131.1799) (xy 472.039323 -131.139731) (xy 472.223839 -131.091688)
			(xy 472.40615 -131.035857) (xy 472.585927 -130.972339) (xy 472.762846 -130.901249) (xy 472.936588 -130.822713)
			(xy 473.106841 -130.736875) (xy 473.273298 -130.643888) (xy 473.435658 -130.543921) (xy 473.593628 -130.437152)
			(xy 473.746926 -130.323776) (xy 473.895273 -130.203995) (xy 474.038403 -130.078027) (xy 474.176057 -129.946097)
			(xy 474.307989 -129.808444) (xy 474.433959 -129.665316) (xy 474.553742 -129.51697) (xy 474.66712 -129.363674)
			(xy 474.77389 -129.205705) (xy 474.87386 -129.043346) (xy 474.966849 -128.876891) (xy 475.052689 -128.706639)
			(xy 475.131227 -128.532897) (xy 475.20232 -128.355979) (xy 475.26584 -128.176203) (xy 475.321673 -127.993893)
			(xy 475.369718 -127.809378) (xy 475.409889 -127.62299) (xy 475.442114 -127.435064) (xy 475.466333 -127.245941)
			(xy 475.482504 -127.05596) (xy 475.490597 -126.865464) (xy 475.491048 -126.77013) (xy 475.491048 -21.770086)
			(xy 475.490549 -21.674753) (xy 475.482456 -21.484258) (xy 475.466286 -21.294279) (xy 475.442067 -21.105157)
			(xy 475.409844 -20.917234) (xy 475.369674 -20.730847) (xy 475.321629 -20.546333) (xy 475.265797 -20.364024)
			(xy 475.202278 -20.18425) (xy 475.131186 -20.007333) (xy 475.05265 -19.833593) (xy 474.966811 -19.663342)
			(xy 474.873823 -19.496888) (xy 474.773855 -19.334531) (xy 474.667086 -19.176562) (xy 474.553708 -19.023267)
			(xy 474.433927 -18.874923) (xy 474.307958 -18.731795) (xy 474.176028 -18.594143) (xy 474.038375 -18.462215)
			(xy 473.895247 -18.336247) (xy 473.746901 -18.216467) (xy 473.593605 -18.103091) (xy 473.435636 -17.996324)
			(xy 473.273277 -17.896357) (xy 473.106823 -17.803371) (xy 472.936571 -17.717533) (xy 472.76283 -17.638998)
			(xy 472.585913 -17.567908) (xy 472.406138 -17.50439) (xy 472.223829 -17.44856) (xy 472.039314 -17.400517)
			(xy 471.852927 -17.360349) (xy 471.665003 -17.328127) (xy 471.475881 -17.30391) (xy 471.285902 -17.287741)
			(xy 471.095407 -17.27965) (xy 471.000074 -17.279112) (xy 444.999872 -17.279112) (xy 444.894339 -17.278602)
			(xy 444.683429 -17.27051) (xy 444.472984 -17.254345) (xy 444.263312 -17.230132) (xy 444.054721 -17.197906)
			(xy 443.847518 -17.157714) (xy 443.642006 -17.109616) (xy 443.438487 -17.053682) (xy 443.237259 -16.989994)
			(xy 443.038619 -16.918645) (xy 442.842857 -16.839741) (xy 442.650261 -16.753397) (xy 442.461113 -16.65974)
			(xy 442.275691 -16.558907) (xy 442.094267 -16.451046) (xy 441.917108 -16.336315) (xy 441.744473 -16.214883)
			(xy 441.576615 -16.086929) (xy 441.413781 -15.952639) (xy 441.25621 -15.812211) (xy 441.104134 -15.665851)
			(xy 440.957774 -15.513774) (xy 440.817347 -15.356202) (xy 440.683058 -15.193368) (xy 440.555104 -15.02551)
			(xy 440.433673 -14.852874) (xy 440.318943 -14.675714) (xy 440.211083 -14.49429) (xy 440.11025 -14.308867)
			(xy 440.016594 -14.119719) (xy 439.93025 -13.927123) (xy 439.851347 -13.73136) (xy 439.779999 -13.53272)
			(xy 439.716312 -13.331492) (xy 439.660379 -13.127973) (xy 439.612281 -12.922461) (xy 439.572091 -12.715257)
			(xy 439.539865 -12.506666) (xy 439.515653 -12.296994) (xy 439.499489 -12.086549) (xy 439.491397 -11.875639)
			(xy 439.490866 -11.770106) (xy 439.490866 -4.99999) (xy 439.49036 -4.904657) (xy 439.482267 -4.714162)
			(xy 439.466097 -4.524183) (xy 439.441879 -4.335061) (xy 439.409656 -4.147137) (xy 439.369486 -3.96075)
			(xy 439.321442 -3.776236) (xy 439.26561 -3.593927) (xy 439.202091 -3.414153) (xy 439.130999 -3.237235)
			(xy 439.052463 -3.063495) (xy 438.966624 -2.893244) (xy 438.873637 -2.72679) (xy 438.773669 -2.564432)
			(xy 438.6669 -2.406464) (xy 438.553523 -2.253169) (xy 438.433742 -2.104824) (xy 438.307774 -1.961696)
			(xy 438.175844 -1.824043) (xy 438.038191 -1.692114) (xy 437.895063 -1.566146) (xy 437.746717 -1.446366)
			(xy 437.593422 -1.33299) (xy 437.435453 -1.226222) (xy 437.273094 -1.126254) (xy 437.10664 -1.033267)
			(xy 436.936389 -0.947429) (xy 436.762648 -0.868894) (xy 436.585731 -0.797803) (xy 436.405955 -0.734284)
			(xy 436.223646 -0.678453) (xy 436.039132 -0.63041) (xy 435.852745 -0.590241) (xy 435.664821 -0.558018)
			(xy 435.475699 -0.533801) (xy 435.28572 -0.517631) (xy 435.095225 -0.50954) (xy 434.999892 -0.509016)
			(xy 4.99999 -0.509016) (xy 4.904657 -0.509522) (xy 4.714162 -0.517614) (xy 4.524182 -0.533784) (xy 4.335059 -0.558002)
			(xy 4.147135 -0.590225) (xy 3.960748 -0.630394) (xy 3.776233 -0.678438) (xy 3.593924 -0.73427) (xy 3.414149 -0.797788)
			(xy 3.237231 -0.86888) (xy 3.06349 -0.947415) (xy 2.893239 -1.033254) (xy 2.726784 -1.126242) (xy 2.564426 -1.22621)
			(xy 2.406456 -1.332978) (xy 2.253161 -1.446355) (xy 2.104815 -1.566136) (xy 1.961687 -1.692104) (xy 1.824034 -1.824034)
			(xy 1.692104 -1.961687) (xy 1.566136 -2.104815) (xy 1.446355 -2.253161) (xy 1.332978 -2.406456) (xy 1.22621 -2.564426)
			(xy 1.126242 -2.726784) (xy 1.033254 -2.893239) (xy 0.947415 -3.06349) (xy 0.86888 -3.237231) (xy 0.797788 -3.414149)
			(xy 0.73427 -3.593924) (xy 0.678438 -3.776233) (xy 0.646137 -3.900286) (xy 59.465106 -3.900286) (xy 59.471831 -3.783378)
			(xy 59.486516 -3.667201) (xy 59.509092 -3.552297) (xy 59.539454 -3.4392) (xy 59.577461 -3.328438)
			(xy 59.622935 -3.220527) (xy 59.675664 -3.115969) (xy 59.735404 -3.015253) (xy 59.801875 -2.918846)
			(xy 59.874768 -2.827198) (xy 59.953743 -2.740736) (xy 60.038433 -2.659864) (xy 60.128442 -2.584957)
			(xy 60.223352 -2.516365) (xy 60.32272 -2.454408) (xy 60.426083 -2.399373) (xy 60.532959 -2.351518)
			(xy 60.642851 -2.311065) (xy 60.755247 -2.278204) (xy 60.869623 -2.253086) (xy 60.985446 -2.23583)
			(xy 61.102176 -2.226514) (xy 61.219269 -2.225184) (xy 61.336181 -2.231845) (xy 61.452366 -2.246466)
			(xy 61.567283 -2.268978) (xy 61.680396 -2.299278) (xy 61.791179 -2.337224) (xy 61.899115 -2.382638)
			(xy 62.003702 -2.43531) (xy 62.104452 -2.494994) (xy 62.200895 -2.561413) (xy 62.292583 -2.634255)
			(xy 62.336172 -2.67335) (xy 62.343731 -2.679658) (xy 62.362196 -2.686443) (xy 62.381859 -2.68581)
			(xy 62.391036 -2.68224) (xy 62.476126 -2.644394) (xy 62.484905 -2.639997) (xy 62.498544 -2.625901)
			(xy 62.505902 -2.607719) (xy 62.506352 -2.597912) (xy 62.506352 -2.590038) (xy 62.506852 -2.540721)
			(xy 62.514857 -2.442413) (xy 62.530814 -2.345078) (xy 62.554617 -2.24936) (xy 62.58611 -2.155889)
			(xy 62.625084 -2.065282) (xy 62.671283 -1.978137) (xy 62.724402 -1.895029) (xy 62.784091 -1.816506)
			(xy 62.849955 -1.743086) (xy 62.92156 -1.675253) (xy 62.998434 -1.613455) (xy 63.08007 -1.5581) (xy 63.165929 -1.509552)
			(xy 63.255444 -1.468132) (xy 63.348026 -1.434114) (xy 63.443063 -1.407721) (xy 63.539928 -1.389129)
			(xy 63.637983 -1.378458) (xy 63.73658 -1.375781) (xy 63.83507 -1.381114) (xy 63.932801 -1.394422)
			(xy 64.029131 -1.415618) (xy 64.123422 -1.444561) (xy 64.215054 -1.481062) (xy 64.303421 -1.524878)
			(xy 64.38794 -1.575721) (xy 64.468055 -1.633256) (xy 64.543236 -1.697102) (xy 64.612988 -1.76684)
			(xy 64.67685 -1.842008) (xy 64.734401 -1.922111) (xy 64.785262 -2.00662) (xy 64.829096 -2.094978)
			(xy 64.865616 -2.186602) (xy 64.894579 -2.280887) (xy 64.915794 -2.377212) (xy 64.929123 -2.474941)
			(xy 64.934476 -2.57343) (xy 64.934028 -2.590038) (xy 65.045593 -2.590038) (xy 65.049633 -2.491055)
			(xy 65.061728 -2.392732) (xy 65.081798 -2.295721) (xy 65.109708 -2.200669) (xy 65.145272 -2.108208)
			(xy 65.188255 -2.018953) (xy 65.23837 -1.933499) (xy 65.295283 -1.852414) (xy 65.358616 -1.776238)
			(xy 65.427947 -1.705478) (xy 65.502816 -1.640604) (xy 65.582723 -1.582049) (xy 65.667137 -1.530201)
			(xy 65.755496 -1.485407) (xy 65.847212 -1.447964) (xy 65.941675 -1.418121) (xy 66.038256 -1.396077)
			(xy 66.136313 -1.381978) (xy 66.235193 -1.375919) (xy 66.334237 -1.37794) (xy 66.432787 -1.388027)
			(xy 66.530187 -1.406113) (xy 66.625789 -1.432078) (xy 66.718956 -1.46575) (xy 66.809069 -1.506903)
			(xy 66.895527 -1.555264) (xy 66.977756 -1.610511) (xy 67.055208 -1.672277) (xy 67.127368 -1.740151)
			(xy 67.193756 -1.81368) (xy 67.253929 -1.892376) (xy 67.307487 -1.975715) (xy 67.354075 -2.063142)
			(xy 67.393381 -2.154075) (xy 67.425145 -2.24791) (xy 67.449154 -2.344021) (xy 67.46525 -2.44177)
			(xy 67.473325 -2.540506) (xy 67.47383 -2.590038) (xy 67.473325 -2.63957) (xy 67.472584 -2.648633)
			(xy 74.704694 -2.648633) (xy 74.704694 -2.531443) (xy 74.712691 -2.414525) (xy 74.728649 -2.298426)
			(xy 74.752492 -2.183686) (xy 74.78411 -2.070841) (xy 74.823355 -1.960417) (xy 74.870043 -1.852928)
			(xy 74.923959 -1.748876) (xy 74.984849 -1.648746) (xy 75.052431 -1.553005) (xy 75.126389 -1.462099)
			(xy 75.206377 -1.376451) (xy 75.292025 -1.296463) (xy 75.382931 -1.222505) (xy 75.478672 -1.154923)
			(xy 75.578802 -1.094033) (xy 75.682854 -1.040117) (xy 75.790343 -0.993429) (xy 75.900767 -0.954184)
			(xy 76.013612 -0.922566) (xy 76.128352 -0.898723) (xy 76.244451 -0.882765) (xy 76.361369 -0.874768)
			(xy 76.478559 -0.874768) (xy 76.595477 -0.882765) (xy 76.711576 -0.898723) (xy 76.826316 -0.922566)
			(xy 76.939161 -0.954184) (xy 77.049585 -0.993429) (xy 77.157074 -1.040117) (xy 77.261126 -1.094033)
			(xy 77.361256 -1.154923) (xy 77.456997 -1.222505) (xy 77.547903 -1.296463) (xy 77.633551 -1.376451)
			(xy 77.713539 -1.462099) (xy 77.787497 -1.553005) (xy 77.855079 -1.648746) (xy 77.915969 -1.748876)
			(xy 77.969885 -1.852928) (xy 78.016573 -1.960417) (xy 78.055818 -2.070841) (xy 78.087436 -2.183686)
			(xy 78.111279 -2.298426) (xy 78.127237 -2.414525) (xy 78.135234 -2.531443) (xy 78.135734 -2.590038)
			(xy 78.135234 -2.648633) (xy 78.127237 -2.765551) (xy 78.111279 -2.88165) (xy 78.087436 -2.99639)
			(xy 78.055818 -3.109235) (xy 78.016573 -3.219659) (xy 77.969885 -3.327148) (xy 77.915969 -3.4312)
			(xy 77.855079 -3.53133) (xy 77.787497 -3.627071) (xy 77.713539 -3.717977) (xy 77.633551 -3.803625)
			(xy 77.547903 -3.883613) (xy 77.456997 -3.957571) (xy 77.361256 -4.025153) (xy 77.261126 -4.086043)
			(xy 77.157074 -4.139959) (xy 77.049585 -4.186647) (xy 76.939161 -4.225892) (xy 76.826316 -4.25751)
			(xy 76.711576 -4.281353) (xy 76.595477 -4.297311) (xy 76.478559 -4.305308) (xy 76.361369 -4.305308)
			(xy 76.244451 -4.297311) (xy 76.128352 -4.281353) (xy 76.013612 -4.25751) (xy 75.900767 -4.225892)
			(xy 75.790343 -4.186647) (xy 75.682854 -4.139959) (xy 75.578802 -4.086043) (xy 75.478672 -4.025153)
			(xy 75.382931 -3.957571) (xy 75.292025 -3.883613) (xy 75.206377 -3.803625) (xy 75.126389 -3.717977)
			(xy 75.052431 -3.627071) (xy 74.984849 -3.53133) (xy 74.923959 -3.4312) (xy 74.870043 -3.327148)
			(xy 74.823355 -3.219659) (xy 74.78411 -3.109235) (xy 74.752492 -2.99639) (xy 74.728649 -2.88165)
			(xy 74.712691 -2.765551) (xy 74.704694 -2.648633) (xy 67.472584 -2.648633) (xy 67.46525 -2.738306)
			(xy 67.449154 -2.836055) (xy 67.425145 -2.932166) (xy 67.393381 -3.026001) (xy 67.354075 -3.116934)
			(xy 67.307487 -3.204361) (xy 67.253929 -3.2877) (xy 67.193756 -3.366396) (xy 67.127368 -3.439925)
			(xy 67.055208 -3.507799) (xy 66.977756 -3.569565) (xy 66.895527 -3.624812) (xy 66.809069 -3.673173)
			(xy 66.718956 -3.714326) (xy 66.625789 -3.747998) (xy 66.530187 -3.773963) (xy 66.432787 -3.792049)
			(xy 66.334237 -3.802136) (xy 66.235193 -3.804157) (xy 66.136313 -3.798098) (xy 66.038256 -3.783999)
			(xy 65.941675 -3.761955) (xy 65.847212 -3.732112) (xy 65.755496 -3.694669) (xy 65.667137 -3.649875)
			(xy 65.582723 -3.598027) (xy 65.502816 -3.539472) (xy 65.427947 -3.474598) (xy 65.358616 -3.403838)
			(xy 65.295283 -3.327662) (xy 65.23837 -3.246577) (xy 65.188255 -3.161123) (xy 65.145272 -3.071868)
			(xy 65.109708 -2.979407) (xy 65.081798 -2.884355) (xy 65.061728 -2.787344) (xy 65.049633 -2.689021)
			(xy 65.045593 -2.590038) (xy 64.934028 -2.590038) (xy 64.931819 -2.672028) (xy 64.921169 -2.770085)
			(xy 64.902596 -2.866954) (xy 64.876223 -2.961996) (xy 64.842223 -3.054585) (xy 64.800822 -3.144109)
			(xy 64.752292 -3.229978) (xy 64.696954 -3.311625) (xy 64.635172 -3.388512) (xy 64.567354 -3.460131)
			(xy 64.493947 -3.52601) (xy 64.415436 -3.585715) (xy 64.332339 -3.638851) (xy 64.245203 -3.685068)
			(xy 64.154604 -3.724061) (xy 64.06114 -3.755573) (xy 63.965427 -3.779396) (xy 63.868095 -3.795372)
			(xy 63.769789 -3.803397) (xy 63.720472 -3.803904) (xy 63.719964 -3.803904) (xy 63.667939 -3.803349)
			(xy 63.564271 -3.794428) (xy 63.461748 -3.776665) (xy 63.361123 -3.750189) (xy 63.263133 -3.715195)
			(xy 63.1685 -3.67194) (xy 63.077917 -3.620741) (xy 63.034672 -3.591814) (xy 63.022226 -3.583178)
			(xy 62.992 -3.58267) (xy 62.887352 -3.647948) (xy 62.874652 -3.67538) (xy 62.876938 -3.690366) (xy 62.88499 -3.748362)
			(xy 62.894112 -3.865108) (xy 62.895249 -3.982203) (xy 62.888395 -4.099104) (xy 62.873582 -4.215265)
			(xy 62.85088 -4.330144) (xy 62.820393 -4.443207) (xy 62.782264 -4.553927) (xy 62.736672 -4.661788)
			(xy 62.683827 -4.766287) (xy 62.623976 -4.866938) (xy 62.557399 -4.963272) (xy 62.484405 -5.054839)
			(xy 62.405335 -5.141214) (xy 62.320556 -5.221993) (xy 62.230464 -5.296801) (xy 62.178873 -5.334)
			(xy 81.787492 -5.334) (xy 81.787492 -5.333492) (xy 81.788098 -5.28716) (xy 81.797769 -5.195002) (xy 81.816965 -5.104348)
			(xy 81.845477 -5.016179) (xy 81.863692 -4.973574) (xy 81.867498 -4.963632) (xy 81.867498 -4.942368)
			(xy 81.863692 -4.932426) (xy 81.845447 -4.889764) (xy 81.816903 -4.801471) (xy 81.79771 -4.710686)
			(xy 81.788077 -4.618396) (xy 81.787492 -4.572) (xy 81.788075 -4.525604) (xy 81.79772 -4.433316) (xy 81.816916 -4.342532)
			(xy 81.845454 -4.254239) (xy 81.863692 -4.211574) (xy 81.867498 -4.201632) (xy 81.867498 -4.180368)
			(xy 81.863692 -4.170426) (xy 81.84547 -4.127823) (xy 81.816952 -4.039656) (xy 81.79776 -3.949) (xy 81.7881 -3.85684)
			(xy 81.787492 -3.810508) (xy 81.787492 -3.81) (xy 81.787967 -3.768898) (xy 81.795552 -3.687043) (xy 81.810657 -3.606238)
			(xy 81.833153 -3.527171) (xy 81.862849 -3.450517) (xy 81.899491 -3.37693) (xy 81.942766 -3.307038)
			(xy 81.992306 -3.241437) (xy 82.047687 -3.180687) (xy 82.108437 -3.125306) (xy 82.174038 -3.075766)
			(xy 82.24393 -3.032491) (xy 82.317517 -2.995849) (xy 82.394171 -2.966153) (xy 82.473238 -2.943657)
			(xy 82.554043 -2.928552) (xy 82.635898 -2.920967) (xy 82.677 -2.920492) (xy 82.677508 -2.920492)
			(xy 82.72384 -2.921098) (xy 82.815998 -2.930769) (xy 82.906652 -2.949965) (xy 82.994821 -2.978477)
			(xy 83.037426 -2.996692) (xy 83.047368 -3.000498) (xy 83.068632 -3.000498) (xy 83.078574 -2.996692)
			(xy 83.121236 -2.978447) (xy 83.209529 -2.949903) (xy 83.300314 -2.93071) (xy 83.392604 -2.921077)
			(xy 83.439 -2.920492) (xy 83.485396 -2.921075) (xy 83.577684 -2.93072) (xy 83.668468 -2.949916) (xy 83.756761 -2.978454)
			(xy 83.799426 -2.996692) (xy 83.809368 -3.000498) (xy 83.830632 -3.000498) (xy 83.840574 -2.996692)
			(xy 83.883236 -2.978447) (xy 83.971529 -2.949903) (xy 84.062314 -2.93071) (xy 84.154604 -2.921077)
			(xy 84.201 -2.920492) (xy 84.247396 -2.921075) (xy 84.339684 -2.93072) (xy 84.430468 -2.949916) (xy 84.518761 -2.978454)
			(xy 84.561426 -2.996692) (xy 84.571368 -3.000498) (xy 84.592632 -3.000498) (xy 84.602574 -2.996692)
			(xy 84.645236 -2.978447) (xy 84.733529 -2.949903) (xy 84.824314 -2.93071) (xy 84.916604 -2.921077)
			(xy 84.963 -2.920492) (xy 85.009396 -2.921075) (xy 85.101684 -2.93072) (xy 85.192468 -2.949916) (xy 85.280761 -2.978454)
			(xy 85.323426 -2.996692) (xy 85.333368 -3.000498) (xy 85.354632 -3.000498) (xy 85.364574 -2.996692)
			(xy 85.407236 -2.978447) (xy 85.495529 -2.949903) (xy 85.586314 -2.93071) (xy 85.678604 -2.921077)
			(xy 85.725 -2.920492) (xy 85.771396 -2.921075) (xy 85.863684 -2.93072) (xy 85.954468 -2.949916) (xy 86.042761 -2.978454)
			(xy 86.085426 -2.996692) (xy 86.095368 -3.000498) (xy 86.116632 -3.000498) (xy 86.126574 -2.996692)
			(xy 86.169177 -2.97847) (xy 86.257344 -2.949952) (xy 86.348 -2.93076) (xy 86.44016 -2.9211) (xy 86.486492 -2.920492)
			(xy 86.487 -2.920492) (xy 86.528102 -2.920967) (xy 86.609957 -2.928552) (xy 86.690762 -2.943657)
			(xy 86.769829 -2.966153) (xy 86.846483 -2.995849) (xy 86.92007 -3.032491) (xy 86.989962 -3.075766)
			(xy 87.055563 -3.125306) (xy 87.116313 -3.180687) (xy 87.171694 -3.241437) (xy 87.221234 -3.307038)
			(xy 87.264509 -3.37693) (xy 87.301151 -3.450517) (xy 87.330847 -3.527171) (xy 87.353343 -3.606238)
			(xy 87.368448 -3.687043) (xy 87.376033 -3.768898) (xy 87.376508 -3.81) (xy 87.376508 -3.810508) (xy 87.375902 -3.85684)
			(xy 87.366231 -3.948998) (xy 87.347035 -4.039652) (xy 87.318523 -4.127821) (xy 87.300308 -4.170426)
			(xy 87.296502 -4.180368) (xy 87.296502 -4.201632) (xy 87.300308 -4.211574) (xy 87.318553 -4.254236)
			(xy 87.347097 -4.342529) (xy 87.36629 -4.433314) (xy 87.375923 -4.525604) (xy 87.376508 -4.572) (xy 87.375925 -4.618396)
			(xy 87.36628 -4.710684) (xy 87.347084 -4.801468) (xy 87.318546 -4.889761) (xy 87.300308 -4.932426)
			(xy 87.296502 -4.942368) (xy 87.296502 -4.963632) (xy 87.300308 -4.973574) (xy 87.31853 -5.016177)
			(xy 87.347048 -5.104344) (xy 87.36624 -5.195) (xy 87.3759 -5.28716) (xy 87.376508 -5.333492) (xy 87.376508 -5.334)
			(xy 87.376285 -5.353304) (xy 354.006912 -5.353304) (xy 354.006912 -5.352796) (xy 354.007518 -5.306464)
			(xy 354.017189 -5.214306) (xy 354.036385 -5.123652) (xy 354.064897 -5.035483) (xy 354.083112 -4.992878)
			(xy 354.086914 -4.982935) (xy 354.086915 -4.961672) (xy 354.083112 -4.95173) (xy 354.06487 -4.909067)
			(xy 354.036325 -4.820775) (xy 354.017131 -4.72999) (xy 354.007497 -4.6377) (xy 354.006912 -4.591304)
			(xy 354.007495 -4.544908) (xy 354.017139 -4.45262) (xy 354.036335 -4.361836) (xy 354.064874 -4.273543)
			(xy 354.083112 -4.230878) (xy 354.086914 -4.220935) (xy 354.086915 -4.199672) (xy 354.083112 -4.18973)
			(xy 354.064892 -4.147126) (xy 354.036374 -4.058959) (xy 354.01718 -3.968304) (xy 354.00752 -3.876144)
			(xy 354.006912 -3.829812) (xy 354.006912 -3.829304) (xy 354.007356 -3.7882) (xy 354.014941 -3.706344)
			(xy 354.030046 -3.625536) (xy 354.052543 -3.546467) (xy 354.08224 -3.469811) (xy 354.118884 -3.396222)
			(xy 354.162161 -3.326328) (xy 354.211702 -3.260725) (xy 354.267085 -3.199974) (xy 354.327838 -3.144592)
			(xy 354.393441 -3.095051) (xy 354.463336 -3.051776) (xy 354.536925 -3.015134) (xy 354.613582 -2.985438)
			(xy 354.692652 -2.962943) (xy 354.773459 -2.947839) (xy 354.855316 -2.940255) (xy 354.89642 -2.939796)
			(xy 354.896928 -2.939796) (xy 354.94326 -2.940395) (xy 355.035418 -2.950068) (xy 355.126072 -2.969266)
			(xy 355.214241 -2.99778) (xy 355.256846 -3.015996) (xy 355.266788 -3.019802) (xy 355.288052 -3.019802)
			(xy 355.297994 -3.015996) (xy 355.340654 -2.997745) (xy 355.428947 -2.969202) (xy 355.519733 -2.950011)
			(xy 355.612024 -2.94038) (xy 355.65842 -2.939796) (xy 355.704815 -2.940407) (xy 355.797102 -2.950044)
			(xy 355.887886 -2.969231) (xy 355.97618 -2.997762) (xy 356.018846 -3.015996) (xy 356.028788 -3.019802)
			(xy 356.050052 -3.019802) (xy 356.059994 -3.015996) (xy 356.102654 -2.997745) (xy 356.190947 -2.969202)
			(xy 356.281733 -2.950011) (xy 356.374024 -2.94038) (xy 356.42042 -2.939796) (xy 356.466815 -2.940407)
			(xy 356.559102 -2.950044) (xy 356.649886 -2.969231) (xy 356.73818 -2.997762) (xy 356.780846 -3.015996)
			(xy 356.790788 -3.019802) (xy 356.812052 -3.019802) (xy 356.821994 -3.015996) (xy 356.864654 -2.997745)
			(xy 356.952947 -2.969202) (xy 357.043733 -2.950011) (xy 357.136024 -2.94038) (xy 357.18242 -2.939796)
			(xy 357.228815 -2.940407) (xy 357.321102 -2.950044) (xy 357.411886 -2.969231) (xy 357.50018 -2.997762)
			(xy 357.542846 -3.015996) (xy 357.552788 -3.019802) (xy 357.574052 -3.019802) (xy 357.583994 -3.015996)
			(xy 357.626654 -2.997745) (xy 357.714947 -2.969202) (xy 357.805733 -2.950011) (xy 357.898024 -2.94038)
			(xy 357.94442 -2.939796) (xy 357.990815 -2.940407) (xy 358.083102 -2.950044) (xy 358.173886 -2.969231)
			(xy 358.26218 -2.997762) (xy 358.304846 -3.015996) (xy 358.314788 -3.019802) (xy 358.336052 -3.019802)
			(xy 358.345994 -3.015996) (xy 358.388594 -2.997768) (xy 358.476763 -2.969252) (xy 358.567419 -2.950061)
			(xy 358.65958 -2.940403) (xy 358.705912 -2.939796) (xy 358.70642 -2.939796) (xy 358.747523 -2.940248)
			(xy 358.829378 -2.947834) (xy 358.910184 -2.962941) (xy 358.989251 -2.985439) (xy 359.065905 -3.015137)
			(xy 359.139492 -3.051781) (xy 359.209385 -3.095058) (xy 359.274986 -3.144599) (xy 359.335736 -3.199981)
			(xy 359.391117 -3.260733) (xy 359.440656 -3.326335) (xy 359.483931 -3.396229) (xy 359.520573 -3.469817)
			(xy 359.550268 -3.546472) (xy 359.572764 -3.62554) (xy 359.587869 -3.706346) (xy 359.595454 -3.788201)
			(xy 359.595928 -3.829304) (xy 359.595928 -3.829812) (xy 359.595322 -3.876144) (xy 359.592786 -3.900309)
			(xy 361.865136 -3.900309) (xy 361.87186 -3.783404) (xy 361.886543 -3.667229) (xy 361.909117 -3.552327)
			(xy 361.939477 -3.439232) (xy 361.977481 -3.328472) (xy 362.022952 -3.220563) (xy 362.075679 -3.116006)
			(xy 362.135416 -3.015291) (xy 362.201884 -2.918885) (xy 362.274775 -2.827238) (xy 362.353747 -2.740777)
			(xy 362.438434 -2.659905) (xy 362.52844 -2.584998) (xy 362.623346 -2.516406) (xy 362.722711 -2.454448)
			(xy 362.826071 -2.399413) (xy 362.932945 -2.351557) (xy 363.042834 -2.311104) (xy 363.155227 -2.278241)
			(xy 363.269599 -2.253122) (xy 363.38542 -2.235864) (xy 363.502147 -2.226547) (xy 363.619238 -2.225214)
			(xy 363.736148 -2.231873) (xy 363.85233 -2.246491) (xy 363.967245 -2.269002) (xy 364.080357 -2.299299)
			(xy 364.191138 -2.337241) (xy 364.299073 -2.382653) (xy 364.403658 -2.435322) (xy 364.504407 -2.495003)
			(xy 364.60085 -2.561418) (xy 364.692537 -2.634257) (xy 364.736126 -2.67335) (xy 364.74371 -2.679623)
			(xy 364.762161 -2.686419) (xy 364.781815 -2.685801) (xy 364.79099 -2.68224) (xy 364.87608 -2.644394)
			(xy 364.88487 -2.640018) (xy 364.898503 -2.62591) (xy 364.905858 -2.607721) (xy 364.906306 -2.597912)
			(xy 364.906306 -2.597658) (xy 364.906052 -2.5908) (xy 364.906052 -2.589276) (xy 364.90662 -2.539112)
			(xy 364.914961 -2.439131) (xy 364.931528 -2.340179) (xy 364.956206 -2.242933) (xy 364.988828 -2.148056)
			(xy 365.02917 -2.056196) (xy 365.076958 -1.967979) (xy 365.131864 -1.884009) (xy 365.193515 -1.804857)
			(xy 365.261489 -1.731065) (xy 365.335323 -1.663135) (xy 365.414513 -1.601533) (xy 365.498517 -1.546678)
			(xy 365.586763 -1.498944) (xy 365.678648 -1.458658) (xy 365.773545 -1.426094) (xy 365.870806 -1.401475)
			(xy 365.969767 -1.384969) (xy 366.069754 -1.376689) (xy 366.119918 -1.376172) (xy 366.168816 -1.376589)
			(xy 366.266296 -1.38446) (xy 366.362826 -1.400149) (xy 366.457781 -1.423554) (xy 366.550544 -1.454524)
			(xy 366.640514 -1.492858) (xy 366.727109 -1.538308) (xy 366.809765 -1.590578) (xy 366.887947 -1.649329)
			(xy 366.961149 -1.714181) (xy 367.028894 -1.784712) (xy 367.090745 -1.860467) (xy 367.146299 -1.940952)
			(xy 367.195197 -2.025647) (xy 367.237122 -2.114001) (xy 367.271801 -2.205443) (xy 367.299009 -2.299379)
			(xy 367.318571 -2.395199) (xy 367.330359 -2.492283) (xy 367.334297 -2.59) (xy 367.334295 -2.590038)
			(xy 367.445547 -2.590038) (xy 367.449587 -2.491055) (xy 367.461682 -2.392732) (xy 367.481752 -2.295721)
			(xy 367.509662 -2.200669) (xy 367.545226 -2.108208) (xy 367.588209 -2.018953) (xy 367.638324 -1.933499)
			(xy 367.695237 -1.852414) (xy 367.75857 -1.776238) (xy 367.827901 -1.705478) (xy 367.90277 -1.640604)
			(xy 367.982677 -1.582049) (xy 368.067091 -1.530201) (xy 368.15545 -1.485407) (xy 368.247166 -1.447964)
			(xy 368.341629 -1.418121) (xy 368.43821 -1.396077) (xy 368.536267 -1.381978) (xy 368.635147 -1.375919)
			(xy 368.734191 -1.37794) (xy 368.832741 -1.388027) (xy 368.930141 -1.406113) (xy 369.025743 -1.432078)
			(xy 369.11891 -1.46575) (xy 369.209023 -1.506903) (xy 369.295481 -1.555264) (xy 369.37771 -1.610511)
			(xy 369.455162 -1.672277) (xy 369.527322 -1.740151) (xy 369.59371 -1.81368) (xy 369.653883 -1.892376)
			(xy 369.707441 -1.975715) (xy 369.754029 -2.063142) (xy 369.793335 -2.154075) (xy 369.825099 -2.24791)
			(xy 369.849108 -2.344021) (xy 369.865204 -2.44177) (xy 369.873279 -2.540506) (xy 369.873784 -2.590038)
			(xy 369.873279 -2.63957) (xy 369.872538 -2.648633) (xy 377.104648 -2.648633) (xy 377.104648 -2.531443)
			(xy 377.112645 -2.414525) (xy 377.128603 -2.298426) (xy 377.152446 -2.183686) (xy 377.184064 -2.070841)
			(xy 377.223309 -1.960417) (xy 377.269997 -1.852928) (xy 377.323913 -1.748876) (xy 377.384803 -1.648746)
			(xy 377.452385 -1.553005) (xy 377.526343 -1.462099) (xy 377.606331 -1.376451) (xy 377.691979 -1.296463)
			(xy 377.782885 -1.222505) (xy 377.878626 -1.154923) (xy 377.978756 -1.094033) (xy 378.082808 -1.040117)
			(xy 378.190297 -0.993429) (xy 378.300721 -0.954184) (xy 378.413566 -0.922566) (xy 378.528306 -0.898723)
			(xy 378.644405 -0.882765) (xy 378.761323 -0.874768) (xy 378.878513 -0.874768) (xy 378.995431 -0.882765)
			(xy 379.11153 -0.898723) (xy 379.22627 -0.922566) (xy 379.339115 -0.954184) (xy 379.449539 -0.993429)
			(xy 379.557028 -1.040117) (xy 379.66108 -1.094033) (xy 379.76121 -1.154923) (xy 379.856951 -1.222505)
			(xy 379.947857 -1.296463) (xy 380.033505 -1.376451) (xy 380.113493 -1.462099) (xy 380.187451 -1.553005)
			(xy 380.255033 -1.648746) (xy 380.315923 -1.748876) (xy 380.369839 -1.852928) (xy 380.416527 -1.960417)
			(xy 380.455772 -2.070841) (xy 380.48739 -2.183686) (xy 380.511233 -2.298426) (xy 380.527191 -2.414525)
			(xy 380.535188 -2.531443) (xy 380.535688 -2.590038) (xy 380.535188 -2.648633) (xy 380.527191 -2.765551)
			(xy 380.511233 -2.88165) (xy 380.48739 -2.99639) (xy 380.455772 -3.109235) (xy 380.416527 -3.219659)
			(xy 380.369839 -3.327148) (xy 380.315923 -3.4312) (xy 380.255033 -3.53133) (xy 380.187451 -3.627071)
			(xy 380.113493 -3.717977) (xy 380.033505 -3.803625) (xy 379.947857 -3.883613) (xy 379.856951 -3.957571)
			(xy 379.76121 -4.025153) (xy 379.66108 -4.086043) (xy 379.557028 -4.139959) (xy 379.449539 -4.186647)
			(xy 379.339115 -4.225892) (xy 379.22627 -4.25751) (xy 379.11153 -4.281353) (xy 378.995431 -4.297311)
			(xy 378.878513 -4.305308) (xy 378.761323 -4.305308) (xy 378.644405 -4.297311) (xy 378.528306 -4.281353)
			(xy 378.413566 -4.25751) (xy 378.300721 -4.225892) (xy 378.190297 -4.186647) (xy 378.082808 -4.139959)
			(xy 377.978756 -4.086043) (xy 377.878626 -4.025153) (xy 377.782885 -3.957571) (xy 377.691979 -3.883613)
			(xy 377.606331 -3.803625) (xy 377.526343 -3.717977) (xy 377.452385 -3.627071) (xy 377.384803 -3.53133)
			(xy 377.323913 -3.4312) (xy 377.269997 -3.327148) (xy 377.223309 -3.219659) (xy 377.184064 -3.109235)
			(xy 377.152446 -2.99639) (xy 377.128603 -2.88165) (xy 377.112645 -2.765551) (xy 377.104648 -2.648633)
			(xy 369.872538 -2.648633) (xy 369.865204 -2.738306) (xy 369.849108 -2.836055) (xy 369.825099 -2.932166)
			(xy 369.793335 -3.026001) (xy 369.754029 -3.116934) (xy 369.707441 -3.204361) (xy 369.653883 -3.2877)
			(xy 369.59371 -3.366396) (xy 369.527322 -3.439925) (xy 369.455162 -3.507799) (xy 369.37771 -3.569565)
			(xy 369.295481 -3.624812) (xy 369.209023 -3.673173) (xy 369.11891 -3.714326) (xy 369.025743 -3.747998)
			(xy 368.930141 -3.773963) (xy 368.832741 -3.792049) (xy 368.734191 -3.802136) (xy 368.635147 -3.804157)
			(xy 368.536267 -3.798098) (xy 368.43821 -3.783999) (xy 368.341629 -3.761955) (xy 368.247166 -3.732112)
			(xy 368.15545 -3.694669) (xy 368.067091 -3.649875) (xy 367.982677 -3.598027) (xy 367.90277 -3.539472)
			(xy 367.827901 -3.474598) (xy 367.75857 -3.403838) (xy 367.695237 -3.327662) (xy 367.638324 -3.246577)
			(xy 367.588209 -3.161123) (xy 367.545226 -3.071868) (xy 367.509662 -2.979407) (xy 367.481752 -2.884355)
			(xy 367.461682 -2.787344) (xy 367.449587 -2.689021) (xy 367.445547 -2.590038) (xy 367.334295 -2.590038)
			(xy 367.330359 -2.687717) (xy 367.318571 -2.784801) (xy 367.299009 -2.880621) (xy 367.271801 -2.974557)
			(xy 367.237122 -3.065999) (xy 367.195197 -3.154353) (xy 367.146299 -3.239048) (xy 367.090745 -3.319533)
			(xy 367.028894 -3.395288) (xy 366.961149 -3.465819) (xy 366.887947 -3.530671) (xy 366.809765 -3.589422)
			(xy 366.727109 -3.641692) (xy 366.640514 -3.687142) (xy 366.550544 -3.725476) (xy 366.457781 -3.756446)
			(xy 366.362826 -3.779851) (xy 366.266296 -3.79554) (xy 366.168816 -3.803411) (xy 366.119918 -3.803904)
			(xy 366.067892 -3.803373) (xy 365.964224 -3.794448) (xy 365.861701 -3.776681) (xy 365.761075 -3.750202)
			(xy 365.663086 -3.715204) (xy 365.568453 -3.671945) (xy 365.477871 -3.620743) (xy 365.434626 -3.591814)
			(xy 365.42218 -3.583178) (xy 365.391954 -3.58267) (xy 365.287306 -3.647948) (xy 365.274606 -3.67538)
			(xy 365.276892 -3.690366) (xy 365.284958 -3.748359) (xy 365.294081 -3.865102) (xy 365.295218 -3.982195)
			(xy 365.288365 -4.099093) (xy 365.273553 -4.215251) (xy 365.250851 -4.330129) (xy 365.220366 -4.44319)
			(xy 365.182239 -4.553907) (xy 365.136647 -4.661766) (xy 365.083804 -4.766264) (xy 365.023956 -4.866913)
			(xy 364.95738 -4.963245) (xy 364.884389 -5.054811) (xy 364.80532 -5.141184) (xy 364.720544 -5.221962)
			(xy 364.630454 -5.296769) (xy 364.535472 -5.365256) (xy 364.436038 -5.427103) (xy 364.332617 -5.482023)
			(xy 364.225691 -5.52976) (xy 364.115757 -5.570092) (xy 364.003327 -5.60283) (xy 363.888927 -5.627822)
			(xy 363.773088 -5.644952) (xy 363.65635 -5.654139) (xy 363.539257 -5.655341) (xy 363.422355 -5.648553)
			(xy 363.306189 -5.633805) (xy 363.191299 -5.611168) (xy 363.078221 -5.580745) (xy 362.967482 -5.542679)
			(xy 362.859598 -5.497148) (xy 362.755071 -5.444363) (xy 362.654389 -5.38457) (xy 362.55802 -5.318048)
			(xy 362.466413 -5.245107) (xy 362.379996 -5.166087) (xy 362.299171 -5.081355) (xy 362.224314 -4.991308)
			(xy 362.155775 -4.896363) (xy 362.093872 -4.796964) (xy 362.038895 -4.693573) (xy 361.991098 -4.586673)
			(xy 361.950706 -4.476762) (xy 361.917905 -4.36435) (xy 361.89285 -4.249964) (xy 361.875656 -4.134134)
			(xy 361.866404 -4.017401) (xy 361.865136 -3.900309) (xy 359.592786 -3.900309) (xy 359.58565 -3.968302)
			(xy 359.566455 -4.058956) (xy 359.537943 -4.147125) (xy 359.519728 -4.18973) (xy 359.515919 -4.199671)
			(xy 359.515921 -4.220936) (xy 359.519728 -4.230878) (xy 359.537975 -4.273539) (xy 359.566518 -4.361832)
			(xy 359.585711 -4.452617) (xy 359.595343 -4.544908) (xy 359.595928 -4.591304) (xy 359.595345 -4.6377)
			(xy 359.5857 -4.729988) (xy 359.566504 -4.820772) (xy 359.537966 -4.909065) (xy 359.519728 -4.95173)
			(xy 359.515919 -4.961671) (xy 359.515921 -4.982936) (xy 359.519728 -4.992878) (xy 359.537953 -5.03548)
			(xy 359.566469 -5.123648) (xy 359.585661 -5.214303) (xy 359.59532 -5.306464) (xy 359.595928 -5.352796)
			(xy 359.595928 -5.353304) (xy 359.595437 -5.394406) (xy 359.587852 -5.476259) (xy 359.572747 -5.557063)
			(xy 359.550251 -5.636129) (xy 359.520556 -5.712782) (xy 359.483914 -5.786368) (xy 359.44064 -5.85626)
			(xy 359.391101 -5.92186) (xy 359.335722 -5.98261) (xy 359.274973 -6.037991) (xy 359.209373 -6.087531)
			(xy 359.139482 -6.130807) (xy 359.065897 -6.167449) (xy 358.989245 -6.197146) (xy 358.910179 -6.219643)
			(xy 358.829375 -6.23475) (xy 358.747522 -6.242336) (xy 358.70642 -6.242812) (xy 358.705912 -6.242812)
			(xy 358.65958 -6.242199) (xy 358.567423 -6.232529) (xy 358.476769 -6.213336) (xy 358.3886 -6.184826)
			(xy 358.345994 -6.166612) (xy 358.336052 -6.162806) (xy 358.314788 -6.162806) (xy 358.304846 -6.166612)
			(xy 358.262181 -6.18485) (xy 358.17389 -6.213396) (xy 358.083106 -6.232591) (xy 357.990816 -6.242226)
			(xy 357.94442 -6.242812) (xy 357.898025 -6.242222) (xy 357.805736 -6.232579) (xy 357.714953 -6.213385)
			(xy 357.626659 -6.184849) (xy 357.583994 -6.166612) (xy 357.574052 -6.162806) (xy 357.552788 -6.162806)
			(xy 357.542846 -6.166612) (xy 357.500181 -6.18485) (xy 357.41189 -6.213396) (xy 357.321106 -6.232591)
			(xy 357.228816 -6.242226) (xy 357.18242 -6.242812) (xy 357.136025 -6.242222) (xy 357.043736 -6.232579)
			(xy 356.952953 -6.213385) (xy 356.864659 -6.184849) (xy 356.821994 -6.166612) (xy 356.812052 -6.162806)
			(xy 356.790788 -6.162806) (xy 356.780846 -6.166612) (xy 356.738181 -6.18485) (xy 356.64989 -6.213396)
			(xy 356.559106 -6.232591) (xy 356.466816 -6.242226) (xy 356.42042 -6.242812) (xy 356.374025 -6.242222)
			(xy 356.281736 -6.232579) (xy 356.190953 -6.213385) (xy 356.102659 -6.184849) (xy 356.059994 -6.166612)
			(xy 356.050052 -6.162806) (xy 356.028788 -6.162806) (xy 356.018846 -6.166612) (xy 355.976181 -6.18485)
			(xy 355.88789 -6.213396) (xy 355.797106 -6.232591) (xy 355.704816 -6.242226) (xy 355.65842 -6.242812)
			(xy 355.612025 -6.242222) (xy 355.519736 -6.232579) (xy 355.428953 -6.213385) (xy 355.340659 -6.184849)
			(xy 355.297994 -6.166612) (xy 355.288052 -6.162806) (xy 355.266788 -6.162806) (xy 355.256846 -6.166612)
			(xy 355.214241 -6.184828) (xy 355.126074 -6.213347) (xy 355.035419 -6.232541) (xy 354.94326 -6.242203)
			(xy 354.896928 -6.242812) (xy 354.89642 -6.242812) (xy 354.855317 -6.242329) (xy 354.773462 -6.234746)
			(xy 354.692656 -6.219642) (xy 354.613589 -6.197147) (xy 354.536934 -6.167452) (xy 354.463346 -6.130811)
			(xy 354.393453 -6.087537) (xy 354.327851 -6.037998) (xy 354.267099 -5.982618) (xy 354.211717 -5.921868)
			(xy 354.162177 -5.856267) (xy 354.1189 -5.786375) (xy 354.082257 -5.712788) (xy 354.052561 -5.636134)
			(xy 354.030063 -5.557067) (xy 354.014958 -5.476261) (xy 354.007372 -5.394407) (xy 354.006912 -5.353304)
			(xy 87.376285 -5.353304) (xy 87.376033 -5.375102) (xy 87.368448 -5.456957) (xy 87.353343 -5.537762)
			(xy 87.330847 -5.616829) (xy 87.301151 -5.693483) (xy 87.264509 -5.76707) (xy 87.221234 -5.836962)
			(xy 87.171694 -5.902563) (xy 87.116313 -5.963313) (xy 87.055563 -6.018694) (xy 86.989962 -6.068234)
			(xy 86.92007 -6.111509) (xy 86.846483 -6.148151) (xy 86.769829 -6.177847) (xy 86.690762 -6.200343)
			(xy 86.609957 -6.215448) (xy 86.528102 -6.223033) (xy 86.487 -6.223508) (xy 86.486492 -6.223508)
			(xy 86.44016 -6.222902) (xy 86.348002 -6.213231) (xy 86.257348 -6.194035) (xy 86.169179 -6.165523)
			(xy 86.126574 -6.147308) (xy 86.116632 -6.143502) (xy 86.095368 -6.143502) (xy 86.085426 -6.147308)
			(xy 86.042764 -6.165553) (xy 85.954471 -6.194097) (xy 85.863686 -6.21329) (xy 85.771396 -6.222923)
			(xy 85.725 -6.223508) (xy 85.678604 -6.222925) (xy 85.586316 -6.21328) (xy 85.495532 -6.194084) (xy 85.407239 -6.165546)
			(xy 85.364574 -6.147308) (xy 85.354632 -6.143502) (xy 85.333368 -6.143502) (xy 85.323426 -6.147308)
			(xy 85.280764 -6.165553) (xy 85.192471 -6.194097) (xy 85.101686 -6.21329) (xy 85.009396 -6.222923)
			(xy 84.963 -6.223508) (xy 84.916604 -6.222925) (xy 84.824316 -6.21328) (xy 84.733532 -6.194084) (xy 84.645239 -6.165546)
			(xy 84.602574 -6.147308) (xy 84.592632 -6.143502) (xy 84.571368 -6.143502) (xy 84.561426 -6.147308)
			(xy 84.518764 -6.165553) (xy 84.430471 -6.194097) (xy 84.339686 -6.21329) (xy 84.247396 -6.222923)
			(xy 84.201 -6.223508) (xy 84.154604 -6.222925) (xy 84.062316 -6.21328) (xy 83.971532 -6.194084) (xy 83.883239 -6.165546)
			(xy 83.840574 -6.147308) (xy 83.830632 -6.143502) (xy 83.809368 -6.143502) (xy 83.799426 -6.147308)
			(xy 83.756764 -6.165553) (xy 83.668471 -6.194097) (xy 83.577686 -6.21329) (xy 83.485396 -6.222923)
			(xy 83.439 -6.223508) (xy 83.392604 -6.222925) (xy 83.300316 -6.21328) (xy 83.209532 -6.194084) (xy 83.121239 -6.165546)
			(xy 83.078574 -6.147308) (xy 83.068632 -6.143502) (xy 83.047368 -6.143502) (xy 83.037426 -6.147308)
			(xy 82.994823 -6.16553) (xy 82.906656 -6.194048) (xy 82.816 -6.21324) (xy 82.72384 -6.2229) (xy 82.677508 -6.223508)
			(xy 82.677 -6.223508) (xy 82.635898 -6.223033) (xy 82.554043 -6.215448) (xy 82.473238 -6.200343)
			(xy 82.394171 -6.177847) (xy 82.317517 -6.148151) (xy 82.24393 -6.111509) (xy 82.174038 -6.068234)
			(xy 82.108437 -6.018694) (xy 82.047687 -5.963313) (xy 81.992306 -5.902563) (xy 81.942766 -5.836962)
			(xy 81.899491 -5.76707) (xy 81.862849 -5.693483) (xy 81.833153 -5.616829) (xy 81.810657 -5.537762)
			(xy 81.795552 -5.456957) (xy 81.787967 -5.375102) (xy 81.787492 -5.334) (xy 62.178873 -5.334) (xy 62.135479 -5.365288)
			(xy 62.036043 -5.427136) (xy 61.932619 -5.482057) (xy 61.82569 -5.529794) (xy 61.715754 -5.570126)
			(xy 61.603322 -5.602863) (xy 61.488918 -5.627855) (xy 61.373077 -5.644984) (xy 61.256336 -5.654171)
			(xy 61.139241 -5.655372) (xy 61.022337 -5.648582) (xy 60.906168 -5.633833) (xy 60.791276 -5.611194)
			(xy 60.678196 -5.58077) (xy 60.567455 -5.542702) (xy 60.459569 -5.497169) (xy 60.355041 -5.444382)
			(xy 60.254357 -5.384586) (xy 60.157987 -5.318062) (xy 60.066379 -5.245119) (xy 59.979961 -5.166096)
			(xy 59.899135 -5.081362) (xy 59.824278 -4.991311) (xy 59.755738 -4.896364) (xy 59.693835 -4.796962)
			(xy 59.638858 -4.693568) (xy 59.591062 -4.586666) (xy 59.55067 -4.476751) (xy 59.51787 -4.364337)
			(xy 59.492815 -4.249948) (xy 59.475623 -4.134116) (xy 59.466372 -4.01738) (xy 59.465106 -3.900286)
			(xy 0.646137 -3.900286) (xy 0.630394 -3.960748) (xy 0.590225 -4.147135) (xy 0.558002 -4.335059) (xy 0.533784 -4.524182)
			(xy 0.517614 -4.714162) (xy 0.509522 -4.904657) (xy 0.509016 -4.99999) (xy 0.509016 -17.272) (xy 111.565944 -17.272)
			(xy 111.565944 -17.271492) (xy 111.566546 -17.22516) (xy 111.576218 -17.133002) (xy 111.595414 -17.042348)
			(xy 111.623928 -16.954179) (xy 111.642144 -16.911574) (xy 111.645952 -16.901632) (xy 111.645952 -16.880368)
			(xy 111.642144 -16.870426) (xy 111.623902 -16.827762) (xy 111.595357 -16.739471) (xy 111.576163 -16.648686)
			(xy 111.566529 -16.556396) (xy 111.565944 -16.51) (xy 111.566522 -16.463604) (xy 111.576168 -16.371316)
			(xy 111.595365 -16.280532) (xy 111.623905 -16.192239) (xy 111.642144 -16.149574) (xy 111.645952 -16.139632)
			(xy 111.645952 -16.118368) (xy 111.642144 -16.108426) (xy 111.623902 -16.065762) (xy 111.595357 -15.977471)
			(xy 111.576163 -15.886686) (xy 111.566529 -15.794396) (xy 111.565944 -15.748) (xy 111.566522 -15.701604)
			(xy 111.576168 -15.609316) (xy 111.595365 -15.518532) (xy 111.623905 -15.430239) (xy 111.642144 -15.387574)
			(xy 111.645952 -15.377632) (xy 111.645952 -15.356368) (xy 111.642144 -15.346426) (xy 111.623902 -15.303762)
			(xy 111.595357 -15.215471) (xy 111.576163 -15.124686) (xy 111.566529 -15.032396) (xy 111.565944 -14.986)
			(xy 111.566522 -14.939604) (xy 111.576168 -14.847316) (xy 111.595365 -14.756532) (xy 111.623905 -14.668239)
			(xy 111.642144 -14.625574) (xy 111.645952 -14.615632) (xy 111.645952 -14.594368) (xy 111.642144 -14.584426)
			(xy 111.623919 -14.541824) (xy 111.595403 -14.453656) (xy 111.576211 -14.363) (xy 111.566552 -14.27084)
			(xy 111.565944 -14.224508) (xy 111.565944 -14.224) (xy 111.566467 -14.182899) (xy 111.574051 -14.101047)
			(xy 111.589155 -14.020245) (xy 111.61165 -13.94118) (xy 111.641344 -13.864529) (xy 111.677983 -13.790944)
			(xy 111.721256 -13.721053) (xy 111.770792 -13.655454) (xy 111.82617 -13.594704) (xy 111.886917 -13.539323)
			(xy 111.952514 -13.489783) (xy 112.022402 -13.446507) (xy 112.095985 -13.409863) (xy 112.172635 -13.380165)
			(xy 112.251698 -13.357666) (xy 112.3325 -13.342558) (xy 112.414351 -13.334969) (xy 112.455452 -13.334492)
			(xy 112.45596 -13.334492) (xy 112.502291 -13.335115) (xy 112.594449 -13.344781) (xy 112.685103 -13.363972)
			(xy 112.773272 -13.392479) (xy 112.815878 -13.410692) (xy 112.82582 -13.414498) (xy 112.847084 -13.414498)
			(xy 112.857026 -13.410692) (xy 112.899695 -13.392463) (xy 112.987985 -13.363915) (xy 113.078768 -13.344717)
			(xy 113.171056 -13.335079) (xy 113.217452 -13.334492) (xy 113.263847 -13.335092) (xy 113.356135 -13.344732)
			(xy 113.446919 -13.363923) (xy 113.535213 -13.392456) (xy 113.577878 -13.410692) (xy 113.58782 -13.414498)
			(xy 113.609084 -13.414498) (xy 113.619026 -13.410692) (xy 113.661695 -13.392463) (xy 113.749985 -13.363915)
			(xy 113.840768 -13.344717) (xy 113.933056 -13.335079) (xy 113.979452 -13.334492) (xy 114.025847 -13.335092)
			(xy 114.118135 -13.344732) (xy 114.208919 -13.363923) (xy 114.297213 -13.392456) (xy 114.339878 -13.410692)
			(xy 114.34982 -13.414498) (xy 114.371084 -13.414498) (xy 114.381026 -13.410692) (xy 114.423695 -13.392463)
			(xy 114.511985 -13.363915) (xy 114.602768 -13.344717) (xy 114.695056 -13.335079) (xy 114.741452 -13.334492)
			(xy 114.787847 -13.335092) (xy 114.880135 -13.344732) (xy 114.970919 -13.363923) (xy 115.059213 -13.392456)
			(xy 115.101878 -13.410692) (xy 115.11182 -13.414498) (xy 115.133084 -13.414498) (xy 115.143026 -13.410692)
			(xy 115.185635 -13.392486) (xy 115.2738 -13.363964) (xy 115.364454 -13.344767) (xy 115.456612 -13.335103)
			(xy 115.502944 -13.334492) (xy 115.503452 -13.334492) (xy 115.544554 -13.334998) (xy 115.626409 -13.342579)
			(xy 115.707215 -13.35768) (xy 115.786282 -13.380173) (xy 115.862937 -13.409865) (xy 115.936525 -13.446504)
			(xy 116.006418 -13.489777) (xy 116.072021 -13.539314) (xy 116.132772 -13.594694) (xy 116.188155 -13.655442)
			(xy 116.237696 -13.721042) (xy 116.280972 -13.790933) (xy 116.317615 -13.864519) (xy 116.347312 -13.941172)
			(xy 116.369809 -14.020239) (xy 116.384915 -14.101044) (xy 116.3925 -14.182898) (xy 116.39296 -14.224)
			(xy 116.39296 -14.224508) (xy 116.392358 -14.27084) (xy 116.382686 -14.362998) (xy 116.363489 -14.453652)
			(xy 116.334976 -14.541821) (xy 116.31676 -14.584426) (xy 116.312952 -14.594368) (xy 116.312952 -14.615632)
			(xy 116.31676 -14.625574) (xy 116.335002 -14.668237) (xy 116.363547 -14.756529) (xy 116.382741 -14.847314)
			(xy 116.392375 -14.939604) (xy 116.39296 -14.986) (xy 116.392381 -15.032396) (xy 116.382736 -15.124684)
			(xy 116.363539 -15.215468) (xy 116.334999 -15.303761) (xy 116.31676 -15.346426) (xy 116.312952 -15.356368)
			(xy 116.312952 -15.377632) (xy 116.31676 -15.387574) (xy 116.335002 -15.430237) (xy 116.363547 -15.518529)
			(xy 116.382741 -15.609314) (xy 116.392375 -15.701604) (xy 116.39296 -15.748) (xy 116.392381 -15.794396)
			(xy 116.382736 -15.886684) (xy 116.363539 -15.977468) (xy 116.334999 -16.065761) (xy 116.31676 -16.108426)
			(xy 116.312952 -16.118368) (xy 116.312952 -16.139632) (xy 116.31676 -16.149574) (xy 116.335002 -16.192237)
			(xy 116.363547 -16.280529) (xy 116.382741 -16.371314) (xy 116.392375 -16.463604) (xy 116.39296 -16.51)
			(xy 116.392381 -16.556396) (xy 116.382736 -16.648684) (xy 116.363539 -16.739468) (xy 116.334999 -16.827761)
			(xy 116.31676 -16.870426) (xy 116.312952 -16.880368) (xy 116.312952 -16.901632) (xy 116.31676 -16.911574)
			(xy 116.334985 -16.954176) (xy 116.363501 -17.042344) (xy 116.382693 -17.132999) (xy 116.392352 -17.22516)
			(xy 116.39296 -17.271492) (xy 116.39296 -17.272) (xy 116.392548 -17.313105) (xy 116.384962 -17.394963)
			(xy 116.369856 -17.475772) (xy 116.347357 -17.554843) (xy 116.317659 -17.6315) (xy 116.281014 -17.70509)
			(xy 116.237735 -17.774985) (xy 116.188192 -17.840588) (xy 116.132806 -17.90134) (xy 116.072051 -17.956722)
			(xy 116.006446 -18.006262) (xy 115.936548 -18.049538) (xy 115.862956 -18.086179) (xy 115.786297 -18.115873)
			(xy 115.707226 -18.138367) (xy 115.626415 -18.153469) (xy 115.544557 -18.16105) (xy 115.503452 -18.161508)
			(xy 115.502944 -18.161508) (xy 115.456613 -18.160884) (xy 115.364455 -18.151218) (xy 115.273801 -18.132027)
			(xy 115.185632 -18.103521) (xy 115.143026 -18.085308) (xy 115.133084 -18.081502) (xy 115.11182 -18.081502)
			(xy 115.101878 -18.085308) (xy 115.059209 -18.103536) (xy 114.970919 -18.132084) (xy 114.880136 -18.151282)
			(xy 114.787847 -18.16092) (xy 114.741452 -18.161508) (xy 114.695057 -18.160907) (xy 114.602769 -18.151267)
			(xy 114.511985 -18.132076) (xy 114.423691 -18.103543) (xy 114.381026 -18.085308) (xy 114.371084 -18.081502)
			(xy 114.34982 -18.081502) (xy 114.339878 -18.085308) (xy 114.297209 -18.103536) (xy 114.208919 -18.132084)
			(xy 114.118136 -18.151282) (xy 114.025847 -18.16092) (xy 113.979452 -18.161508) (xy 113.933057 -18.160907)
			(xy 113.840769 -18.151267) (xy 113.749985 -18.132076) (xy 113.661691 -18.103543) (xy 113.619026 -18.085308)
			(xy 113.609084 -18.081502) (xy 113.58782 -18.081502) (xy 113.577878 -18.085308) (xy 113.535209 -18.103536)
			(xy 113.446919 -18.132084) (xy 113.356136 -18.151282) (xy 113.263847 -18.16092) (xy 113.217452 -18.161508)
			(xy 113.171057 -18.160907) (xy 113.078769 -18.151267) (xy 112.987985 -18.132076) (xy 112.899691 -18.103543)
			(xy 112.857026 -18.085308) (xy 112.847084 -18.081502) (xy 112.82582 -18.081502) (xy 112.815878 -18.085308)
			(xy 112.773268 -18.103513) (xy 112.685103 -18.132035) (xy 112.59445 -18.151233) (xy 112.502292 -18.160897)
			(xy 112.45596 -18.161508) (xy 112.455452 -18.161508) (xy 112.414349 -18.161079) (xy 112.332493 -18.15349)
			(xy 112.251687 -18.138381) (xy 112.17262 -18.11588) (xy 112.095965 -18.086181) (xy 112.022379 -18.049535)
			(xy 111.952487 -18.006257) (xy 111.886886 -17.956714) (xy 111.826136 -17.90133) (xy 111.770755 -17.840577)
			(xy 111.721216 -17.774974) (xy 111.677941 -17.705079) (xy 111.6413 -17.631491) (xy 111.611604 -17.554835)
			(xy 111.589108 -17.475766) (xy 111.574003 -17.394959) (xy 111.566419 -17.313103) (xy 111.565944 -17.272)
			(xy 0.509016 -17.272) (xy 0.509016 -20.63857) (xy 56.730635 -20.63857) (xy 56.730635 -20.50943) (xy 56.738585 -20.380535)
			(xy 56.754455 -20.252375) (xy 56.778184 -20.125434) (xy 56.809683 -20.000195) (xy 56.848832 -19.877132)
			(xy 56.895483 -19.756713) (xy 56.949458 -19.639394) (xy 57.010553 -19.52562) (xy 57.078536 -19.415823)
			(xy 57.15315 -19.31042) (xy 57.234111 -19.20981) (xy 57.321111 -19.114375) (xy 57.413822 -19.024476)
			(xy 57.511892 -18.940455) (xy 57.614947 -18.862631) (xy 57.722598 -18.791299) (xy 57.834437 -18.726729)
			(xy 57.950038 -18.669167) (xy 58.068963 -18.61883) (xy 58.190762 -18.57591) (xy 58.314972 -18.540569)
			(xy 58.441121 -18.512942) (xy 58.568733 -18.493133) (xy 58.697322 -18.481217) (xy 58.8264 -18.477241)
			(xy 58.955478 -18.481217) (xy 59.084067 -18.493133) (xy 59.211679 -18.512942) (xy 59.337828 -18.540569)
			(xy 59.462038 -18.57591) (xy 59.583837 -18.61883) (xy 59.702762 -18.669167) (xy 59.818363 -18.726729)
			(xy 59.930202 -18.791299) (xy 60.037853 -18.862631) (xy 60.140908 -18.940455) (xy 60.238978 -19.024476)
			(xy 60.331689 -19.114375) (xy 60.418689 -19.20981) (xy 60.49965 -19.31042) (xy 60.574264 -19.415823)
			(xy 60.642247 -19.52562) (xy 60.703342 -19.639394) (xy 60.757317 -19.756713) (xy 60.803968 -19.877132)
			(xy 60.843117 -20.000195) (xy 60.874616 -20.125434) (xy 60.898345 -20.252375) (xy 60.914215 -20.380535)
			(xy 60.922165 -20.50943) (xy 60.922662 -20.574) (xy 60.922165 -20.63857) (xy 60.914215 -20.767465)
			(xy 60.898345 -20.895625) (xy 60.874616 -21.022566) (xy 60.843117 -21.147805) (xy 60.803968 -21.270868)
			(xy 60.757317 -21.391287) (xy 60.703342 -21.508606) (xy 60.642247 -21.62238) (xy 60.574264 -21.732177)
			(xy 60.49965 -21.83758) (xy 60.418689 -21.93819) (xy 60.331689 -22.033625) (xy 60.238978 -22.123524)
			(xy 60.140908 -22.207545) (xy 60.037853 -22.285369) (xy 59.988365 -22.318161) (xy 111.362994 -22.318161)
			(xy 111.362994 -22.233439) (xy 111.371047 -22.149102) (xy 111.387081 -22.065912) (xy 111.410949 -21.984622)
			(xy 111.442437 -21.90597) (xy 111.481259 -21.830667) (xy 111.527062 -21.759395) (xy 111.579433 -21.692799)
			(xy 111.637898 -21.631484) (xy 111.701926 -21.576003) (xy 111.770938 -21.52686) (xy 111.844308 -21.4845)
			(xy 111.921373 -21.449305) (xy 112.001435 -21.421596) (xy 112.083768 -21.401622) (xy 112.167627 -21.389565)
			(xy 112.252252 -21.385534) (xy 112.336877 -21.389565) (xy 112.420736 -21.401622) (xy 112.503069 -21.421596)
			(xy 112.583131 -21.449305) (xy 112.660196 -21.4845) (xy 112.733566 -21.52686) (xy 112.802578 -21.576003)
			(xy 112.866606 -21.631484) (xy 112.925071 -21.692799) (xy 112.977442 -21.759395) (xy 113.023245 -21.830667)
			(xy 113.062067 -21.90597) (xy 113.093555 -21.984622) (xy 113.117423 -22.065912) (xy 113.133457 -22.149102)
			(xy 113.14151 -22.233439) (xy 113.142014 -22.2758) (xy 113.14151 -22.318161) (xy 113.133457 -22.402498)
			(xy 113.117423 -22.485688) (xy 113.093555 -22.566978) (xy 113.062067 -22.64563) (xy 113.023245 -22.720933)
			(xy 112.977442 -22.792205) (xy 112.925071 -22.858801) (xy 112.866606 -22.920116) (xy 112.802578 -22.975597)
			(xy 112.733566 -23.02474) (xy 112.660196 -23.0671) (xy 112.583131 -23.102295) (xy 112.503069 -23.130004)
			(xy 112.420736 -23.149978) (xy 112.336877 -23.162035) (xy 112.252252 -23.166067) (xy 112.167627 -23.162035)
			(xy 112.083768 -23.149978) (xy 112.001435 -23.130004) (xy 111.921373 -23.102295) (xy 111.844308 -23.0671)
			(xy 111.770938 -23.02474) (xy 111.701926 -22.975597) (xy 111.637898 -22.920116) (xy 111.579433 -22.858801)
			(xy 111.527062 -22.792205) (xy 111.481259 -22.720933) (xy 111.442437 -22.64563) (xy 111.410949 -22.566978)
			(xy 111.387081 -22.485688) (xy 111.371047 -22.402498) (xy 111.362994 -22.318161) (xy 59.988365 -22.318161)
			(xy 59.930202 -22.356701) (xy 59.818363 -22.421271) (xy 59.702762 -22.478833) (xy 59.583837 -22.52917)
			(xy 59.462038 -22.57209) (xy 59.337828 -22.607431) (xy 59.211679 -22.635058) (xy 59.084067 -22.654867)
			(xy 58.955478 -22.666783) (xy 58.8264 -22.67076) (xy 58.697322 -22.666783) (xy 58.568733 -22.654867)
			(xy 58.441121 -22.635058) (xy 58.314972 -22.607431) (xy 58.190762 -22.57209) (xy 58.068963 -22.52917)
			(xy 57.950038 -22.478833) (xy 57.834437 -22.421271) (xy 57.722598 -22.356701) (xy 57.614947 -22.285369)
			(xy 57.511892 -22.207545) (xy 57.413822 -22.123524) (xy 57.321111 -22.033625) (xy 57.234111 -21.93819)
			(xy 57.15315 -21.83758) (xy 57.078536 -21.732177) (xy 57.010553 -21.62238) (xy 56.949458 -21.508606)
			(xy 56.895483 -21.391287) (xy 56.848832 -21.270868) (xy 56.809683 -21.147805) (xy 56.778184 -21.022566)
			(xy 56.754455 -20.895625) (xy 56.738585 -20.767465) (xy 56.730635 -20.63857) (xy 0.509016 -20.63857)
			(xy 0.509016 -28.5496) (xy 111.565944 -28.5496) (xy 111.565944 -28.549092) (xy 111.566546 -28.50276)
			(xy 111.576218 -28.410602) (xy 111.595414 -28.319948) (xy 111.623928 -28.231779) (xy 111.642144 -28.189174)
			(xy 111.645952 -28.179232) (xy 111.645952 -28.157968) (xy 111.642144 -28.148026) (xy 111.623902 -28.105362)
			(xy 111.595357 -28.017071) (xy 111.576163 -27.926286) (xy 111.566529 -27.833996) (xy 111.565944 -27.7876)
			(xy 111.566522 -27.741204) (xy 111.576168 -27.648916) (xy 111.595365 -27.558132) (xy 111.623905 -27.469839)
			(xy 111.642144 -27.427174) (xy 111.645952 -27.417232) (xy 111.645952 -27.395968) (xy 111.642144 -27.386026)
			(xy 111.623902 -27.343362) (xy 111.595357 -27.255071) (xy 111.576163 -27.164286) (xy 111.566529 -27.071996)
			(xy 111.565944 -27.0256) (xy 111.566522 -26.979204) (xy 111.576168 -26.886916) (xy 111.595365 -26.796132)
			(xy 111.623905 -26.707839) (xy 111.642144 -26.665174) (xy 111.645952 -26.655232) (xy 111.645952 -26.633968)
			(xy 111.642144 -26.624026) (xy 111.623902 -26.581362) (xy 111.595357 -26.493071) (xy 111.576163 -26.402286)
			(xy 111.566529 -26.309996) (xy 111.565944 -26.2636) (xy 111.566522 -26.217204) (xy 111.576168 -26.124916)
			(xy 111.595365 -26.034132) (xy 111.623905 -25.945839) (xy 111.642144 -25.903174) (xy 111.645952 -25.893232)
			(xy 111.645952 -25.871968) (xy 111.642144 -25.862026) (xy 111.623919 -25.819424) (xy 111.595403 -25.731256)
			(xy 111.576211 -25.6406) (xy 111.566552 -25.54844) (xy 111.565944 -25.502108) (xy 111.565944 -25.5016)
			(xy 111.566467 -25.460499) (xy 111.574051 -25.378647) (xy 111.589155 -25.297845) (xy 111.61165 -25.21878)
			(xy 111.641344 -25.142129) (xy 111.677983 -25.068544) (xy 111.721256 -24.998653) (xy 111.770792 -24.933054)
			(xy 111.82617 -24.872304) (xy 111.886917 -24.816923) (xy 111.952514 -24.767383) (xy 112.022402 -24.724107)
			(xy 112.095985 -24.687463) (xy 112.172635 -24.657765) (xy 112.251698 -24.635266) (xy 112.3325 -24.620158)
			(xy 112.414351 -24.612569) (xy 112.455452 -24.612092) (xy 112.45596 -24.612092) (xy 112.502291 -24.612715)
			(xy 112.594449 -24.622381) (xy 112.685103 -24.641572) (xy 112.773272 -24.670079) (xy 112.815878 -24.688292)
			(xy 112.82582 -24.692098) (xy 112.847084 -24.692098) (xy 112.857026 -24.688292) (xy 112.899695 -24.670063)
			(xy 112.987985 -24.641515) (xy 113.078768 -24.622317) (xy 113.171056 -24.612679) (xy 113.217452 -24.612092)
			(xy 113.263847 -24.612692) (xy 113.356135 -24.622332) (xy 113.446919 -24.641523) (xy 113.535213 -24.670056)
			(xy 113.577878 -24.688292) (xy 113.58782 -24.692098) (xy 113.609084 -24.692098) (xy 113.619026 -24.688292)
			(xy 113.661695 -24.670063) (xy 113.749985 -24.641515) (xy 113.840768 -24.622317) (xy 113.933056 -24.612679)
			(xy 113.979452 -24.612092) (xy 114.025847 -24.612692) (xy 114.118135 -24.622332) (xy 114.208919 -24.641523)
			(xy 114.297213 -24.670056) (xy 114.339878 -24.688292) (xy 114.34982 -24.692098) (xy 114.371084 -24.692098)
			(xy 114.381026 -24.688292) (xy 114.423695 -24.670063) (xy 114.511985 -24.641515) (xy 114.602768 -24.622317)
			(xy 114.695056 -24.612679) (xy 114.741452 -24.612092) (xy 114.787847 -24.612692) (xy 114.880135 -24.622332)
			(xy 114.970919 -24.641523) (xy 115.059213 -24.670056) (xy 115.101878 -24.688292) (xy 115.11182 -24.692098)
			(xy 115.133084 -24.692098) (xy 115.143026 -24.688292) (xy 115.185635 -24.670086) (xy 115.2738 -24.641564)
			(xy 115.364454 -24.622367) (xy 115.456612 -24.612703) (xy 115.502944 -24.612092) (xy 115.503452 -24.612092)
			(xy 115.544554 -24.612598) (xy 115.626409 -24.620179) (xy 115.707215 -24.63528) (xy 115.786282 -24.657773)
			(xy 115.862937 -24.687465) (xy 115.936525 -24.724104) (xy 116.006418 -24.767377) (xy 116.072021 -24.816914)
			(xy 116.132772 -24.872294) (xy 116.188155 -24.933042) (xy 116.237696 -24.998642) (xy 116.280972 -25.068533)
			(xy 116.317615 -25.142119) (xy 116.347312 -25.218772) (xy 116.369809 -25.297839) (xy 116.384915 -25.378644)
			(xy 116.3925 -25.460498) (xy 116.39296 -25.5016) (xy 116.39296 -25.502108) (xy 116.392358 -25.54844)
			(xy 116.382686 -25.640598) (xy 116.363489 -25.731252) (xy 116.334976 -25.819421) (xy 116.31676 -25.862026)
			(xy 116.312952 -25.871968) (xy 116.312952 -25.893232) (xy 116.31676 -25.903174) (xy 116.335002 -25.945837)
			(xy 116.363547 -26.034129) (xy 116.382741 -26.124914) (xy 116.392375 -26.217204) (xy 116.39296 -26.2636)
			(xy 116.392381 -26.309996) (xy 116.382736 -26.402284) (xy 116.363539 -26.493068) (xy 116.334999 -26.581361)
			(xy 116.31676 -26.624026) (xy 116.312952 -26.633968) (xy 116.312952 -26.655232) (xy 116.31676 -26.665174)
			(xy 116.335002 -26.707837) (xy 116.363547 -26.796129) (xy 116.382741 -26.886914) (xy 116.392375 -26.979204)
			(xy 116.39296 -27.0256) (xy 116.392381 -27.071996) (xy 116.382736 -27.164284) (xy 116.363539 -27.255068)
			(xy 116.334999 -27.343361) (xy 116.31676 -27.386026) (xy 116.312952 -27.395968) (xy 116.312952 -27.417232)
			(xy 116.31676 -27.427174) (xy 116.335002 -27.469837) (xy 116.363547 -27.558129) (xy 116.382741 -27.648914)
			(xy 116.392375 -27.741204) (xy 116.39296 -27.7876) (xy 116.392381 -27.833996) (xy 116.382736 -27.926284)
			(xy 116.363539 -28.017068) (xy 116.334999 -28.105361) (xy 116.31676 -28.148026) (xy 116.312952 -28.157968)
			(xy 116.312952 -28.179232) (xy 116.31676 -28.189174) (xy 116.334985 -28.231776) (xy 116.363501 -28.319944)
			(xy 116.382693 -28.410599) (xy 116.392352 -28.50276) (xy 116.39296 -28.549092) (xy 116.39296 -28.5496)
			(xy 116.392548 -28.590705) (xy 116.384962 -28.672563) (xy 116.369856 -28.753372) (xy 116.347357 -28.832443)
			(xy 116.317659 -28.9091) (xy 116.281014 -28.98269) (xy 116.237735 -29.052585) (xy 116.188192 -29.118188)
			(xy 116.132806 -29.17894) (xy 116.072051 -29.234322) (xy 116.006446 -29.283862) (xy 115.936548 -29.327138)
			(xy 115.862956 -29.363779) (xy 115.786297 -29.393473) (xy 115.707226 -29.415967) (xy 115.626415 -29.431069)
			(xy 115.544557 -29.43865) (xy 115.503452 -29.439108) (xy 115.502944 -29.439108) (xy 115.456613 -29.438484)
			(xy 115.364455 -29.428818) (xy 115.273801 -29.409627) (xy 115.185632 -29.381121) (xy 115.143026 -29.362908)
			(xy 115.133084 -29.359102) (xy 115.11182 -29.359102) (xy 115.101878 -29.362908) (xy 115.059209 -29.381136)
			(xy 114.970919 -29.409684) (xy 114.880136 -29.428882) (xy 114.787847 -29.43852) (xy 114.741452 -29.439108)
			(xy 114.695057 -29.438507) (xy 114.602769 -29.428867) (xy 114.511985 -29.409676) (xy 114.423691 -29.381143)
			(xy 114.381026 -29.362908) (xy 114.371084 -29.359102) (xy 114.34982 -29.359102) (xy 114.339878 -29.362908)
			(xy 114.297209 -29.381136) (xy 114.208919 -29.409684) (xy 114.118136 -29.428882) (xy 114.025847 -29.43852)
			(xy 113.979452 -29.439108) (xy 113.933057 -29.438507) (xy 113.840769 -29.428867) (xy 113.749985 -29.409676)
			(xy 113.661691 -29.381143) (xy 113.619026 -29.362908) (xy 113.609084 -29.359102) (xy 113.58782 -29.359102)
			(xy 113.577878 -29.362908) (xy 113.535209 -29.381136) (xy 113.446919 -29.409684) (xy 113.356136 -29.428882)
			(xy 113.263847 -29.43852) (xy 113.217452 -29.439108) (xy 113.171057 -29.438507) (xy 113.078769 -29.428867)
			(xy 112.987985 -29.409676) (xy 112.899691 -29.381143) (xy 112.857026 -29.362908) (xy 112.847084 -29.359102)
			(xy 112.82582 -29.359102) (xy 112.815878 -29.362908) (xy 112.773268 -29.381113) (xy 112.685103 -29.409635)
			(xy 112.59445 -29.428833) (xy 112.502292 -29.438497) (xy 112.45596 -29.439108) (xy 112.455452 -29.439108)
			(xy 112.414349 -29.438679) (xy 112.332493 -29.43109) (xy 112.251687 -29.415981) (xy 112.17262 -29.39348)
			(xy 112.095965 -29.363781) (xy 112.022379 -29.327135) (xy 111.952487 -29.283857) (xy 111.886886 -29.234314)
			(xy 111.826136 -29.17893) (xy 111.770755 -29.118177) (xy 111.721216 -29.052574) (xy 111.677941 -28.982679)
			(xy 111.6413 -28.909091) (xy 111.611604 -28.832435) (xy 111.589108 -28.753366) (xy 111.574003 -28.672559)
			(xy 111.566419 -28.590703) (xy 111.565944 -28.5496) (xy 0.509016 -28.5496) (xy 0.509016 -33.595761)
			(xy 111.362994 -33.595761) (xy 111.362994 -33.511039) (xy 111.371047 -33.426702) (xy 111.387081 -33.343512)
			(xy 111.410949 -33.262222) (xy 111.442437 -33.18357) (xy 111.481259 -33.108267) (xy 111.527062 -33.036995)
			(xy 111.579433 -32.970399) (xy 111.637898 -32.909084) (xy 111.701926 -32.853603) (xy 111.770938 -32.80446)
			(xy 111.844308 -32.7621) (xy 111.921373 -32.726905) (xy 112.001435 -32.699196) (xy 112.083768 -32.679222)
			(xy 112.167627 -32.667165) (xy 112.252252 -32.663134) (xy 112.336877 -32.667165) (xy 112.420736 -32.679222)
			(xy 112.503069 -32.699196) (xy 112.583131 -32.726905) (xy 112.660196 -32.7621) (xy 112.733566 -32.80446)
			(xy 112.802578 -32.853603) (xy 112.866606 -32.909084) (xy 112.925071 -32.970399) (xy 112.977442 -33.036995)
			(xy 113.023245 -33.108267) (xy 113.062067 -33.18357) (xy 113.093555 -33.262222) (xy 113.117423 -33.343512)
			(xy 113.133457 -33.426702) (xy 113.14151 -33.511039) (xy 113.142014 -33.5534) (xy 113.14151 -33.595761)
			(xy 113.133457 -33.680098) (xy 113.117423 -33.763288) (xy 113.093555 -33.844578) (xy 113.062067 -33.92323)
			(xy 113.023245 -33.998533) (xy 112.977442 -34.069805) (xy 112.925071 -34.136401) (xy 112.866606 -34.197716)
			(xy 112.802578 -34.253197) (xy 112.733566 -34.30234) (xy 112.660196 -34.3447) (xy 112.583131 -34.379895)
			(xy 112.503069 -34.407604) (xy 112.420736 -34.427578) (xy 112.336877 -34.439635) (xy 112.252252 -34.443667)
			(xy 112.167627 -34.439635) (xy 112.083768 -34.427578) (xy 112.001435 -34.407604) (xy 111.921373 -34.379895)
			(xy 111.844308 -34.3447) (xy 111.770938 -34.30234) (xy 111.701926 -34.253197) (xy 111.637898 -34.197716)
			(xy 111.579433 -34.136401) (xy 111.527062 -34.069805) (xy 111.481259 -33.998533) (xy 111.442437 -33.92323)
			(xy 111.410949 -33.844578) (xy 111.387081 -33.763288) (xy 111.371047 -33.680098) (xy 111.362994 -33.595761)
			(xy 0.509016 -33.595761) (xy 0.509016 -39.8272) (xy 111.565944 -39.8272) (xy 111.565944 -39.826692)
			(xy 111.566546 -39.78036) (xy 111.576218 -39.688202) (xy 111.595414 -39.597548) (xy 111.623928 -39.509379)
			(xy 111.642144 -39.466774) (xy 111.645952 -39.456832) (xy 111.645952 -39.435568) (xy 111.642144 -39.425626)
			(xy 111.623902 -39.382962) (xy 111.595357 -39.294671) (xy 111.576163 -39.203886) (xy 111.566529 -39.111596)
			(xy 111.565944 -39.0652) (xy 111.566522 -39.018804) (xy 111.576168 -38.926516) (xy 111.595365 -38.835732)
			(xy 111.623905 -38.747439) (xy 111.642144 -38.704774) (xy 111.645952 -38.694832) (xy 111.645952 -38.673568)
			(xy 111.642144 -38.663626) (xy 111.623902 -38.620962) (xy 111.595357 -38.532671) (xy 111.576163 -38.441886)
			(xy 111.566529 -38.349596) (xy 111.565944 -38.3032) (xy 111.566522 -38.256804) (xy 111.576168 -38.164516)
			(xy 111.595365 -38.073732) (xy 111.623905 -37.985439) (xy 111.642144 -37.942774) (xy 111.645952 -37.932832)
			(xy 111.645952 -37.911568) (xy 111.642144 -37.901626) (xy 111.623902 -37.858962) (xy 111.595357 -37.770671)
			(xy 111.576163 -37.679886) (xy 111.566529 -37.587596) (xy 111.565944 -37.5412) (xy 111.566522 -37.494804)
			(xy 111.576168 -37.402516) (xy 111.595365 -37.311732) (xy 111.623905 -37.223439) (xy 111.642144 -37.180774)
			(xy 111.645952 -37.170832) (xy 111.645952 -37.149568) (xy 111.642144 -37.139626) (xy 111.623919 -37.097024)
			(xy 111.595403 -37.008856) (xy 111.576211 -36.9182) (xy 111.566552 -36.82604) (xy 111.565944 -36.779708)
			(xy 111.565944 -36.7792) (xy 111.566467 -36.738099) (xy 111.574051 -36.656247) (xy 111.589155 -36.575445)
			(xy 111.61165 -36.49638) (xy 111.641344 -36.419729) (xy 111.677983 -36.346144) (xy 111.721256 -36.276253)
			(xy 111.770792 -36.210654) (xy 111.82617 -36.149904) (xy 111.886917 -36.094523) (xy 111.952514 -36.044983)
			(xy 112.022402 -36.001707) (xy 112.095985 -35.965063) (xy 112.172635 -35.935365) (xy 112.251698 -35.912866)
			(xy 112.3325 -35.897758) (xy 112.414351 -35.890169) (xy 112.455452 -35.889692) (xy 112.45596 -35.889692)
			(xy 112.502291 -35.890315) (xy 112.594449 -35.899981) (xy 112.685103 -35.919172) (xy 112.773272 -35.947679)
			(xy 112.815878 -35.965892) (xy 112.82582 -35.969698) (xy 112.847084 -35.969698) (xy 112.857026 -35.965892)
			(xy 112.899695 -35.947663) (xy 112.987985 -35.919115) (xy 113.078768 -35.899917) (xy 113.171056 -35.890279)
			(xy 113.217452 -35.889692) (xy 113.263847 -35.890292) (xy 113.356135 -35.899932) (xy 113.446919 -35.919123)
			(xy 113.535213 -35.947656) (xy 113.577878 -35.965892) (xy 113.58782 -35.969698) (xy 113.609084 -35.969698)
			(xy 113.619026 -35.965892) (xy 113.661695 -35.947663) (xy 113.749985 -35.919115) (xy 113.840768 -35.899917)
			(xy 113.933056 -35.890279) (xy 113.979452 -35.889692) (xy 114.025847 -35.890292) (xy 114.118135 -35.899932)
			(xy 114.208919 -35.919123) (xy 114.297213 -35.947656) (xy 114.339878 -35.965892) (xy 114.34982 -35.969698)
			(xy 114.371084 -35.969698) (xy 114.381026 -35.965892) (xy 114.423695 -35.947663) (xy 114.511985 -35.919115)
			(xy 114.602768 -35.899917) (xy 114.695056 -35.890279) (xy 114.741452 -35.889692) (xy 114.787847 -35.890292)
			(xy 114.880135 -35.899932) (xy 114.970919 -35.919123) (xy 115.059213 -35.947656) (xy 115.101878 -35.965892)
			(xy 115.11182 -35.969698) (xy 115.133084 -35.969698) (xy 115.143026 -35.965892) (xy 115.185635 -35.947686)
			(xy 115.2738 -35.919164) (xy 115.364454 -35.899967) (xy 115.456612 -35.890303) (xy 115.502944 -35.889692)
			(xy 115.503452 -35.889692) (xy 115.544554 -35.890198) (xy 115.626409 -35.897779) (xy 115.707215 -35.91288)
			(xy 115.786282 -35.935373) (xy 115.862937 -35.965065) (xy 115.936525 -36.001704) (xy 116.006418 -36.044977)
			(xy 116.072021 -36.094514) (xy 116.132772 -36.149894) (xy 116.188155 -36.210642) (xy 116.237696 -36.276242)
			(xy 116.280972 -36.346133) (xy 116.317615 -36.419719) (xy 116.347312 -36.496372) (xy 116.369809 -36.575439)
			(xy 116.384915 -36.656244) (xy 116.3925 -36.738098) (xy 116.39296 -36.7792) (xy 116.39296 -36.779708)
			(xy 116.392358 -36.82604) (xy 116.382686 -36.918198) (xy 116.363489 -37.008852) (xy 116.334976 -37.097021)
			(xy 116.31676 -37.139626) (xy 116.312952 -37.149568) (xy 116.312952 -37.170832) (xy 116.31676 -37.180774)
			(xy 116.335002 -37.223437) (xy 116.363547 -37.311729) (xy 116.382741 -37.402514) (xy 116.392375 -37.494804)
			(xy 116.39296 -37.5412) (xy 116.392381 -37.587596) (xy 116.382736 -37.679884) (xy 116.363539 -37.770668)
			(xy 116.334999 -37.858961) (xy 116.31676 -37.901626) (xy 116.312952 -37.911568) (xy 116.312952 -37.932832)
			(xy 116.31676 -37.942774) (xy 116.335002 -37.985437) (xy 116.363547 -38.073729) (xy 116.382741 -38.164514)
			(xy 116.392375 -38.256804) (xy 116.39296 -38.3032) (xy 116.392381 -38.349596) (xy 116.382736 -38.441884)
			(xy 116.363539 -38.532668) (xy 116.334999 -38.620961) (xy 116.31676 -38.663626) (xy 116.312952 -38.673568)
			(xy 116.312952 -38.694832) (xy 116.31676 -38.704774) (xy 116.335002 -38.747437) (xy 116.363547 -38.835729)
			(xy 116.382741 -38.926514) (xy 116.392375 -39.018804) (xy 116.39296 -39.0652) (xy 116.392381 -39.111596)
			(xy 116.382736 -39.203884) (xy 116.363539 -39.294668) (xy 116.334999 -39.382961) (xy 116.31676 -39.425626)
			(xy 116.312952 -39.435568) (xy 116.312952 -39.456832) (xy 116.31676 -39.466774) (xy 116.334985 -39.509376)
			(xy 116.363501 -39.597544) (xy 116.382693 -39.688199) (xy 116.392352 -39.78036) (xy 116.39296 -39.826692)
			(xy 116.39296 -39.8272) (xy 116.392548 -39.868305) (xy 116.384962 -39.950163) (xy 116.369856 -40.030972)
			(xy 116.347357 -40.110043) (xy 116.317659 -40.1867) (xy 116.281014 -40.26029) (xy 116.237735 -40.330185)
			(xy 116.188192 -40.395788) (xy 116.132806 -40.45654) (xy 116.072051 -40.511922) (xy 116.006446 -40.561462)
			(xy 115.936548 -40.604738) (xy 115.862956 -40.641379) (xy 115.786297 -40.671073) (xy 115.707226 -40.693567)
			(xy 115.626415 -40.708669) (xy 115.544557 -40.71625) (xy 115.503452 -40.716708) (xy 115.502944 -40.716708)
			(xy 115.456613 -40.716084) (xy 115.364455 -40.706418) (xy 115.273801 -40.687227) (xy 115.185632 -40.658721)
			(xy 115.143026 -40.640508) (xy 115.133084 -40.636702) (xy 115.11182 -40.636702) (xy 115.101878 -40.640508)
			(xy 115.059209 -40.658736) (xy 114.970919 -40.687284) (xy 114.880136 -40.706482) (xy 114.787847 -40.71612)
			(xy 114.741452 -40.716708) (xy 114.695057 -40.716107) (xy 114.602769 -40.706467) (xy 114.511985 -40.687276)
			(xy 114.423691 -40.658743) (xy 114.381026 -40.640508) (xy 114.371084 -40.636702) (xy 114.34982 -40.636702)
			(xy 114.339878 -40.640508) (xy 114.297209 -40.658736) (xy 114.208919 -40.687284) (xy 114.118136 -40.706482)
			(xy 114.025847 -40.71612) (xy 113.979452 -40.716708) (xy 113.933057 -40.716107) (xy 113.840769 -40.706467)
			(xy 113.749985 -40.687276) (xy 113.661691 -40.658743) (xy 113.619026 -40.640508) (xy 113.609084 -40.636702)
			(xy 113.58782 -40.636702) (xy 113.577878 -40.640508) (xy 113.535209 -40.658736) (xy 113.446919 -40.687284)
			(xy 113.356136 -40.706482) (xy 113.263847 -40.71612) (xy 113.217452 -40.716708) (xy 113.171057 -40.716107)
			(xy 113.078769 -40.706467) (xy 112.987985 -40.687276) (xy 112.899691 -40.658743) (xy 112.857026 -40.640508)
			(xy 112.847084 -40.636702) (xy 112.82582 -40.636702) (xy 112.815878 -40.640508) (xy 112.773268 -40.658713)
			(xy 112.685103 -40.687235) (xy 112.59445 -40.706433) (xy 112.502292 -40.716097) (xy 112.45596 -40.716708)
			(xy 112.455452 -40.716708) (xy 112.414349 -40.716279) (xy 112.332493 -40.70869) (xy 112.251687 -40.693581)
			(xy 112.17262 -40.67108) (xy 112.095965 -40.641381) (xy 112.022379 -40.604735) (xy 111.952487 -40.561457)
			(xy 111.886886 -40.511914) (xy 111.826136 -40.45653) (xy 111.770755 -40.395777) (xy 111.721216 -40.330174)
			(xy 111.677941 -40.260279) (xy 111.6413 -40.186691) (xy 111.611604 -40.110035) (xy 111.589108 -40.030966)
			(xy 111.574003 -39.950159) (xy 111.566419 -39.868303) (xy 111.565944 -39.8272) (xy 0.509016 -39.8272)
			(xy 0.509016 -42.474585) (xy 107.8931 -42.474585) (xy 107.8931 -42.389863) (xy 107.901153 -42.305526)
			(xy 107.917187 -42.222336) (xy 107.941055 -42.141046) (xy 107.972543 -42.062394) (xy 108.011365 -41.987091)
			(xy 108.057168 -41.915819) (xy 108.109539 -41.849223) (xy 108.168004 -41.787908) (xy 108.232032 -41.732427)
			(xy 108.301044 -41.683284) (xy 108.374414 -41.640924) (xy 108.451479 -41.605729) (xy 108.531541 -41.57802)
			(xy 108.613874 -41.558046) (xy 108.697733 -41.545989) (xy 108.782358 -41.541958) (xy 108.866983 -41.545989)
			(xy 108.950842 -41.558046) (xy 109.033175 -41.57802) (xy 109.113237 -41.605729) (xy 109.190302 -41.640924)
			(xy 109.263672 -41.683284) (xy 109.332684 -41.732427) (xy 109.396712 -41.787908) (xy 109.455177 -41.849223)
			(xy 109.507548 -41.915819) (xy 109.553351 -41.987091) (xy 109.592173 -42.062394) (xy 109.623661 -42.141046)
			(xy 109.647529 -42.222336) (xy 109.663563 -42.305526) (xy 109.671616 -42.389863) (xy 109.67212 -42.432224)
			(xy 109.671616 -42.474585) (xy 109.663563 -42.558922) (xy 109.647529 -42.642112) (xy 109.623661 -42.723402)
			(xy 109.592173 -42.802054) (xy 109.553351 -42.877357) (xy 109.507548 -42.948629) (xy 109.455177 -43.015225)
			(xy 109.396712 -43.07654) (xy 109.332684 -43.132021) (xy 109.263672 -43.181164) (xy 109.192316 -43.222361)
			(xy 110.388142 -43.222361) (xy 110.388142 -43.137639) (xy 110.396195 -43.053302) (xy 110.412229 -42.970112)
			(xy 110.436097 -42.888822) (xy 110.467585 -42.81017) (xy 110.506407 -42.734867) (xy 110.55221 -42.663595)
			(xy 110.604581 -42.596999) (xy 110.663046 -42.535684) (xy 110.727074 -42.480203) (xy 110.796086 -42.43106)
			(xy 110.869456 -42.3887) (xy 110.946521 -42.353505) (xy 111.026583 -42.325796) (xy 111.108916 -42.305822)
			(xy 111.192775 -42.293765) (xy 111.2774 -42.289734) (xy 111.362025 -42.293765) (xy 111.445884 -42.305822)
			(xy 111.528217 -42.325796) (xy 111.608279 -42.353505) (xy 111.685344 -42.3887) (xy 111.758714 -42.43106)
			(xy 111.827726 -42.480203) (xy 111.891754 -42.535684) (xy 111.950219 -42.596999) (xy 112.00259 -42.663595)
			(xy 112.048393 -42.734867) (xy 112.087215 -42.81017) (xy 112.118703 -42.888822) (xy 112.142571 -42.970112)
			(xy 112.158605 -43.053302) (xy 112.166658 -43.137639) (xy 112.167162 -43.18) (xy 112.166658 -43.222361)
			(xy 112.158605 -43.306698) (xy 112.142571 -43.389888) (xy 112.118703 -43.471178) (xy 112.087215 -43.54983)
			(xy 112.048393 -43.625133) (xy 112.00259 -43.696405) (xy 111.950219 -43.763001) (xy 111.891754 -43.824316)
			(xy 111.827726 -43.879797) (xy 111.758714 -43.92894) (xy 111.685344 -43.9713) (xy 111.608279 -44.006495)
			(xy 111.528217 -44.034204) (xy 111.445884 -44.054178) (xy 111.362025 -44.066235) (xy 111.2774 -44.070267)
			(xy 111.192775 -44.066235) (xy 111.108916 -44.054178) (xy 111.026583 -44.034204) (xy 110.946521 -44.006495)
			(xy 110.869456 -43.9713) (xy 110.796086 -43.92894) (xy 110.727074 -43.879797) (xy 110.663046 -43.824316)
			(xy 110.604581 -43.763001) (xy 110.55221 -43.696405) (xy 110.506407 -43.625133) (xy 110.467585 -43.54983)
			(xy 110.436097 -43.471178) (xy 110.412229 -43.389888) (xy 110.396195 -43.306698) (xy 110.388142 -43.222361)
			(xy 109.192316 -43.222361) (xy 109.190302 -43.223524) (xy 109.113237 -43.258719) (xy 109.033175 -43.286428)
			(xy 108.950842 -43.306402) (xy 108.866983 -43.318459) (xy 108.782358 -43.322491) (xy 108.697733 -43.318459)
			(xy 108.613874 -43.306402) (xy 108.531541 -43.286428) (xy 108.451479 -43.258719) (xy 108.374414 -43.223524)
			(xy 108.301044 -43.181164) (xy 108.232032 -43.132021) (xy 108.168004 -43.07654) (xy 108.109539 -43.015225)
			(xy 108.057168 -42.948629) (xy 108.011365 -42.877357) (xy 107.972543 -42.802054) (xy 107.941055 -42.723402)
			(xy 107.917187 -42.642112) (xy 107.901153 -42.558922) (xy 107.8931 -42.474585) (xy 0.509016 -42.474585)
			(xy 0.509016 -44.873361) (xy 111.362994 -44.873361) (xy 111.362994 -44.788639) (xy 111.371047 -44.704302)
			(xy 111.387081 -44.621112) (xy 111.410949 -44.539822) (xy 111.442437 -44.46117) (xy 111.481259 -44.385867)
			(xy 111.527062 -44.314595) (xy 111.579433 -44.247999) (xy 111.637898 -44.186684) (xy 111.701926 -44.131203)
			(xy 111.770938 -44.08206) (xy 111.844308 -44.0397) (xy 111.921373 -44.004505) (xy 112.001435 -43.976796)
			(xy 112.083768 -43.956822) (xy 112.167627 -43.944765) (xy 112.252252 -43.940734) (xy 112.336877 -43.944765)
			(xy 112.420736 -43.956822) (xy 112.503069 -43.976796) (xy 112.583131 -44.004505) (xy 112.660196 -44.0397)
			(xy 112.733566 -44.08206) (xy 112.802578 -44.131203) (xy 112.866606 -44.186684) (xy 112.925071 -44.247999)
			(xy 112.977442 -44.314595) (xy 113.023245 -44.385867) (xy 113.062067 -44.46117) (xy 113.093555 -44.539822)
			(xy 113.117423 -44.621112) (xy 113.133457 -44.704302) (xy 113.14151 -44.788639) (xy 113.142014 -44.831)
			(xy 113.14151 -44.873361) (xy 113.133457 -44.957698) (xy 113.117423 -45.040888) (xy 113.093555 -45.122178)
			(xy 113.062067 -45.20083) (xy 113.023245 -45.276133) (xy 112.977442 -45.347405) (xy 112.925071 -45.414001)
			(xy 112.866606 -45.475316) (xy 112.802578 -45.530797) (xy 112.733566 -45.57994) (xy 112.660196 -45.6223)
			(xy 112.583131 -45.657495) (xy 112.503069 -45.685204) (xy 112.420736 -45.705178) (xy 112.336877 -45.717235)
			(xy 112.252252 -45.721267) (xy 112.167627 -45.717235) (xy 112.083768 -45.705178) (xy 112.001435 -45.685204)
			(xy 111.921373 -45.657495) (xy 111.844308 -45.6223) (xy 111.770938 -45.57994) (xy 111.701926 -45.530797)
			(xy 111.637898 -45.475316) (xy 111.579433 -45.414001) (xy 111.527062 -45.347405) (xy 111.481259 -45.276133)
			(xy 111.442437 -45.20083) (xy 111.410949 -45.122178) (xy 111.387081 -45.040888) (xy 111.371047 -44.957698)
			(xy 111.362994 -44.873361) (xy 0.509016 -44.873361) (xy 0.509016 -50.919888) (xy 41.345622 -50.919888)
			(xy 41.349604 -50.829938) (xy 41.361521 -50.740691) (xy 41.381279 -50.652847) (xy 41.408723 -50.567093)
			(xy 41.443639 -50.4841) (xy 41.485753 -50.404518) (xy 41.534736 -50.328969) (xy 41.590204 -50.258045)
			(xy 41.651724 -50.1923) (xy 41.718813 -50.13225) (xy 41.790947 -50.078365) (xy 41.867561 -50.031065)
			(xy 41.948055 -49.990722) (xy 42.0318 -49.95765) (xy 42.118141 -49.93211) (xy 42.2064 -49.9143) (xy 42.295889 -49.90436)
			(xy 42.385905 -49.902369) (xy 42.475746 -49.90834) (xy 42.564707 -49.922229) (xy 42.652092 -49.943925)
			(xy 42.737218 -49.97326) (xy 42.819418 -50.010003) (xy 42.898049 -50.053867) (xy 42.972496 -50.104509)
			(xy 43.042176 -50.161533) (xy 43.106543 -50.224492) (xy 43.165094 -50.292893) (xy 43.217371 -50.366201)
			(xy 43.262964 -50.443843) (xy 43.301517 -50.52521) (xy 43.332728 -50.609666) (xy 43.356352 -50.69655)
			(xy 43.372205 -50.785182) (xy 43.380162 -50.874869) (xy 43.38066 -50.919888) (xy 60.903622 -50.919888)
			(xy 60.907604 -50.829938) (xy 60.919521 -50.740691) (xy 60.939279 -50.652847) (xy 60.966723 -50.567093)
			(xy 61.001639 -50.4841) (xy 61.043753 -50.404518) (xy 61.092736 -50.328969) (xy 61.148204 -50.258045)
			(xy 61.209724 -50.1923) (xy 61.276813 -50.13225) (xy 61.348947 -50.078365) (xy 61.425561 -50.031065)
			(xy 61.506055 -49.990722) (xy 61.5898 -49.95765) (xy 61.676141 -49.93211) (xy 61.7644 -49.9143) (xy 61.853889 -49.90436)
			(xy 61.943905 -49.902369) (xy 62.033746 -49.90834) (xy 62.122707 -49.922229) (xy 62.210092 -49.943925)
			(xy 62.295218 -49.97326) (xy 62.377418 -50.010003) (xy 62.456049 -50.053867) (xy 62.530496 -50.104509)
			(xy 62.600176 -50.161533) (xy 62.664543 -50.224492) (xy 62.723094 -50.292893) (xy 62.775371 -50.366201)
			(xy 62.820964 -50.443843) (xy 62.859517 -50.52521) (xy 62.890728 -50.609666) (xy 62.914352 -50.69655)
			(xy 62.930205 -50.785182) (xy 62.938162 -50.874869) (xy 62.93866 -50.919888) (xy 62.938162 -50.964907)
			(xy 62.930205 -51.054594) (xy 62.921225 -51.1048) (xy 111.565944 -51.1048) (xy 111.565944 -51.104292)
			(xy 111.566546 -51.05796) (xy 111.576218 -50.965802) (xy 111.595414 -50.875148) (xy 111.623928 -50.786979)
			(xy 111.642144 -50.744374) (xy 111.645952 -50.734432) (xy 111.645952 -50.713168) (xy 111.642144 -50.703226)
			(xy 111.623902 -50.660562) (xy 111.595357 -50.572271) (xy 111.576163 -50.481486) (xy 111.566529 -50.389196)
			(xy 111.565944 -50.3428) (xy 111.566522 -50.296404) (xy 111.576168 -50.204116) (xy 111.595365 -50.113332)
			(xy 111.623905 -50.025039) (xy 111.642144 -49.982374) (xy 111.645952 -49.972432) (xy 111.645952 -49.951168)
			(xy 111.642144 -49.941226) (xy 111.623902 -49.898562) (xy 111.595357 -49.810271) (xy 111.576163 -49.719486)
			(xy 111.566529 -49.627196) (xy 111.565944 -49.5808) (xy 111.566522 -49.534404) (xy 111.576168 -49.442116)
			(xy 111.595365 -49.351332) (xy 111.623905 -49.263039) (xy 111.642144 -49.220374) (xy 111.645952 -49.210432)
			(xy 111.645952 -49.189168) (xy 111.642144 -49.179226) (xy 111.623902 -49.136562) (xy 111.595357 -49.048271)
			(xy 111.576163 -48.957486) (xy 111.566529 -48.865196) (xy 111.565944 -48.8188) (xy 111.566522 -48.772404)
			(xy 111.576168 -48.680116) (xy 111.595365 -48.589332) (xy 111.623905 -48.501039) (xy 111.642144 -48.458374)
			(xy 111.645952 -48.448432) (xy 111.645952 -48.427168) (xy 111.642144 -48.417226) (xy 111.623919 -48.374624)
			(xy 111.595403 -48.286456) (xy 111.576211 -48.1958) (xy 111.566552 -48.10364) (xy 111.565944 -48.057308)
			(xy 111.565944 -48.0568) (xy 111.566467 -48.015699) (xy 111.574051 -47.933847) (xy 111.589155 -47.853045)
			(xy 111.61165 -47.77398) (xy 111.641344 -47.697329) (xy 111.677983 -47.623744) (xy 111.721256 -47.553853)
			(xy 111.770792 -47.488254) (xy 111.82617 -47.427504) (xy 111.886917 -47.372123) (xy 111.952514 -47.322583)
			(xy 112.022402 -47.279307) (xy 112.095985 -47.242663) (xy 112.172635 -47.212965) (xy 112.251698 -47.190466)
			(xy 112.3325 -47.175358) (xy 112.414351 -47.167769) (xy 112.455452 -47.167292) (xy 112.45596 -47.167292)
			(xy 112.502291 -47.167915) (xy 112.594449 -47.177581) (xy 112.685103 -47.196772) (xy 112.773272 -47.225279)
			(xy 112.815878 -47.243492) (xy 112.82582 -47.247298) (xy 112.847084 -47.247298) (xy 112.857026 -47.243492)
			(xy 112.899695 -47.225263) (xy 112.987985 -47.196715) (xy 113.078768 -47.177517) (xy 113.171056 -47.167879)
			(xy 113.217452 -47.167292) (xy 113.263847 -47.167892) (xy 113.356135 -47.177532) (xy 113.446919 -47.196723)
			(xy 113.535213 -47.225256) (xy 113.577878 -47.243492) (xy 113.58782 -47.247298) (xy 113.609084 -47.247298)
			(xy 113.619026 -47.243492) (xy 113.661695 -47.225263) (xy 113.749985 -47.196715) (xy 113.840768 -47.177517)
			(xy 113.933056 -47.167879) (xy 113.979452 -47.167292) (xy 114.025847 -47.167892) (xy 114.118135 -47.177532)
			(xy 114.208919 -47.196723) (xy 114.297213 -47.225256) (xy 114.339878 -47.243492) (xy 114.34982 -47.247298)
			(xy 114.371084 -47.247298) (xy 114.381026 -47.243492) (xy 114.423695 -47.225263) (xy 114.511985 -47.196715)
			(xy 114.602768 -47.177517) (xy 114.695056 -47.167879) (xy 114.741452 -47.167292) (xy 114.787847 -47.167892)
			(xy 114.880135 -47.177532) (xy 114.970919 -47.196723) (xy 115.059213 -47.225256) (xy 115.101878 -47.243492)
			(xy 115.11182 -47.247298) (xy 115.133084 -47.247298) (xy 115.143026 -47.243492) (xy 115.185635 -47.225286)
			(xy 115.2738 -47.196764) (xy 115.364454 -47.177567) (xy 115.456612 -47.167903) (xy 115.502944 -47.167292)
			(xy 115.503452 -47.167292) (xy 115.544554 -47.167798) (xy 115.626409 -47.175379) (xy 115.707215 -47.19048)
			(xy 115.786282 -47.212973) (xy 115.862937 -47.242665) (xy 115.936525 -47.279304) (xy 116.006418 -47.322577)
			(xy 116.072021 -47.372114) (xy 116.132772 -47.427494) (xy 116.188155 -47.488242) (xy 116.237696 -47.553842)
			(xy 116.280972 -47.623733) (xy 116.317615 -47.697319) (xy 116.347312 -47.773972) (xy 116.369809 -47.853039)
			(xy 116.384915 -47.933844) (xy 116.3925 -48.015698) (xy 116.39296 -48.0568) (xy 116.39296 -48.057308)
			(xy 116.392358 -48.10364) (xy 116.382686 -48.195798) (xy 116.363489 -48.286452) (xy 116.334976 -48.374621)
			(xy 116.31676 -48.417226) (xy 116.312952 -48.427168) (xy 116.312952 -48.448432) (xy 116.31676 -48.458374)
			(xy 116.335002 -48.501037) (xy 116.363547 -48.589329) (xy 116.382741 -48.680114) (xy 116.392375 -48.772404)
			(xy 116.39296 -48.8188) (xy 116.392381 -48.865196) (xy 116.382736 -48.957484) (xy 116.363539 -49.048268)
			(xy 116.334999 -49.136561) (xy 116.31676 -49.179226) (xy 116.312952 -49.189168) (xy 116.312952 -49.210432)
			(xy 116.31676 -49.220374) (xy 116.335002 -49.263037) (xy 116.363547 -49.351329) (xy 116.382741 -49.442114)
			(xy 116.392375 -49.534404) (xy 116.39296 -49.5808) (xy 116.392381 -49.627196) (xy 116.382736 -49.719484)
			(xy 116.363539 -49.810268) (xy 116.334999 -49.898561) (xy 116.31676 -49.941226) (xy 116.312952 -49.951168)
			(xy 116.312952 -49.972432) (xy 116.31676 -49.982374) (xy 116.335002 -50.025037) (xy 116.363547 -50.113329)
			(xy 116.382741 -50.204114) (xy 116.392375 -50.296404) (xy 116.39296 -50.3428) (xy 116.392381 -50.389196)
			(xy 116.382736 -50.481484) (xy 116.363539 -50.572268) (xy 116.334999 -50.660561) (xy 116.31676 -50.703226)
			(xy 116.312952 -50.713168) (xy 116.312952 -50.734432) (xy 116.31676 -50.744374) (xy 116.334985 -50.786976)
			(xy 116.363501 -50.875144) (xy 116.382693 -50.965799) (xy 116.392352 -51.05796) (xy 116.39296 -51.104292)
			(xy 116.39296 -51.1048) (xy 116.392548 -51.145905) (xy 116.384962 -51.227763) (xy 116.369856 -51.308572)
			(xy 116.347357 -51.387643) (xy 116.317659 -51.4643) (xy 116.281014 -51.53789) (xy 116.237735 -51.607785)
			(xy 116.188192 -51.673388) (xy 116.132806 -51.73414) (xy 116.072051 -51.789522) (xy 116.006446 -51.839062)
			(xy 115.936548 -51.882338) (xy 115.862956 -51.918979) (xy 115.786297 -51.948673) (xy 115.707226 -51.971167)
			(xy 115.626415 -51.986269) (xy 115.544557 -51.99385) (xy 115.503452 -51.994308) (xy 115.502944 -51.994308)
			(xy 115.456613 -51.993684) (xy 115.364455 -51.984018) (xy 115.273801 -51.964827) (xy 115.185632 -51.936321)
			(xy 115.143026 -51.918108) (xy 115.133084 -51.914302) (xy 115.11182 -51.914302) (xy 115.101878 -51.918108)
			(xy 115.059209 -51.936336) (xy 114.970919 -51.964884) (xy 114.880136 -51.984082) (xy 114.787847 -51.99372)
			(xy 114.741452 -51.994308) (xy 114.695057 -51.993707) (xy 114.602769 -51.984067) (xy 114.511985 -51.964876)
			(xy 114.423691 -51.936343) (xy 114.381026 -51.918108) (xy 114.371084 -51.914302) (xy 114.34982 -51.914302)
			(xy 114.339878 -51.918108) (xy 114.297209 -51.936336) (xy 114.208919 -51.964884) (xy 114.118136 -51.984082)
			(xy 114.025847 -51.99372) (xy 113.979452 -51.994308) (xy 113.933057 -51.993707) (xy 113.840769 -51.984067)
			(xy 113.749985 -51.964876) (xy 113.661691 -51.936343) (xy 113.619026 -51.918108) (xy 113.609084 -51.914302)
			(xy 113.58782 -51.914302) (xy 113.577878 -51.918108) (xy 113.535209 -51.936336) (xy 113.446919 -51.964884)
			(xy 113.356136 -51.984082) (xy 113.263847 -51.99372) (xy 113.217452 -51.994308) (xy 113.171057 -51.993707)
			(xy 113.078769 -51.984067) (xy 112.987985 -51.964876) (xy 112.899691 -51.936343) (xy 112.857026 -51.918108)
			(xy 112.847084 -51.914302) (xy 112.82582 -51.914302) (xy 112.815878 -51.918108) (xy 112.773268 -51.936313)
			(xy 112.685103 -51.964835) (xy 112.59445 -51.984033) (xy 112.502292 -51.993697) (xy 112.45596 -51.994308)
			(xy 112.455452 -51.994308) (xy 112.414349 -51.993879) (xy 112.332493 -51.98629) (xy 112.251687 -51.971181)
			(xy 112.17262 -51.94868) (xy 112.095965 -51.918981) (xy 112.022379 -51.882335) (xy 111.952487 -51.839057)
			(xy 111.886886 -51.789514) (xy 111.826136 -51.73413) (xy 111.770755 -51.673377) (xy 111.721216 -51.607774)
			(xy 111.677941 -51.537879) (xy 111.6413 -51.464291) (xy 111.611604 -51.387635) (xy 111.589108 -51.308566)
			(xy 111.574003 -51.227759) (xy 111.566419 -51.145903) (xy 111.565944 -51.1048) (xy 62.921225 -51.1048)
			(xy 62.914352 -51.143226) (xy 62.890728 -51.23011) (xy 62.859517 -51.314566) (xy 62.820964 -51.395933)
			(xy 62.775371 -51.473575) (xy 62.723094 -51.546883) (xy 62.664543 -51.615284) (xy 62.600176 -51.678243)
			(xy 62.530496 -51.735267) (xy 62.456049 -51.785909) (xy 62.377418 -51.829773) (xy 62.295218 -51.866516)
			(xy 62.210092 -51.895851) (xy 62.122707 -51.917547) (xy 62.033746 -51.931436) (xy 61.943905 -51.937407)
			(xy 61.853889 -51.935416) (xy 61.7644 -51.925476) (xy 61.676141 -51.907666) (xy 61.5898 -51.882126)
			(xy 61.506055 -51.849054) (xy 61.425561 -51.808711) (xy 61.348947 -51.761411) (xy 61.276813 -51.707526)
			(xy 61.209724 -51.647476) (xy 61.148204 -51.581731) (xy 61.092736 -51.510807) (xy 61.043753 -51.435258)
			(xy 61.001639 -51.355676) (xy 60.966723 -51.272683) (xy 60.939279 -51.186929) (xy 60.919521 -51.099085)
			(xy 60.907604 -51.009838) (xy 60.903622 -50.919888) (xy 43.38066 -50.919888) (xy 43.380162 -50.964907)
			(xy 43.372205 -51.054594) (xy 43.356352 -51.143226) (xy 43.332728 -51.23011) (xy 43.301517 -51.314566)
			(xy 43.262964 -51.395933) (xy 43.217371 -51.473575) (xy 43.165094 -51.546883) (xy 43.106543 -51.615284)
			(xy 43.042176 -51.678243) (xy 42.972496 -51.735267) (xy 42.898049 -51.785909) (xy 42.819418 -51.829773)
			(xy 42.737218 -51.866516) (xy 42.652092 -51.895851) (xy 42.564707 -51.917547) (xy 42.475746 -51.931436)
			(xy 42.385905 -51.937407) (xy 42.295889 -51.935416) (xy 42.2064 -51.925476) (xy 42.118141 -51.907666)
			(xy 42.0318 -51.882126) (xy 41.948055 -51.849054) (xy 41.867561 -51.808711) (xy 41.790947 -51.761411)
			(xy 41.718813 -51.707526) (xy 41.651724 -51.647476) (xy 41.590204 -51.581731) (xy 41.534736 -51.510807)
			(xy 41.485753 -51.435258) (xy 41.443639 -51.355676) (xy 41.408723 -51.272683) (xy 41.381279 -51.186929)
			(xy 41.361521 -51.099085) (xy 41.349604 -51.009838) (xy 41.345622 -50.919888) (xy 0.509016 -50.919888)
			(xy 0.509016 -53.735167) (xy 108.485174 -53.735167) (xy 108.485174 -53.650445) (xy 108.493227 -53.566108)
			(xy 108.509261 -53.482918) (xy 108.533129 -53.401628) (xy 108.564617 -53.322976) (xy 108.603439 -53.247673)
			(xy 108.649242 -53.176401) (xy 108.701613 -53.109805) (xy 108.760078 -53.04849) (xy 108.824106 -52.993009)
			(xy 108.893118 -52.943866) (xy 108.966488 -52.901506) (xy 109.043553 -52.866311) (xy 109.123615 -52.838602)
			(xy 109.205948 -52.818628) (xy 109.289807 -52.806571) (xy 109.374432 -52.80254) (xy 109.459057 -52.806571)
			(xy 109.542916 -52.818628) (xy 109.625249 -52.838602) (xy 109.705311 -52.866311) (xy 109.782376 -52.901506)
			(xy 109.855746 -52.943866) (xy 109.924758 -52.993009) (xy 109.988786 -53.04849) (xy 110.047251 -53.109805)
			(xy 110.099622 -53.176401) (xy 110.145425 -53.247673) (xy 110.184247 -53.322976) (xy 110.215735 -53.401628)
			(xy 110.239603 -53.482918) (xy 110.255637 -53.566108) (xy 110.26369 -53.650445) (xy 110.264194 -53.692806)
			(xy 110.26369 -53.735167) (xy 110.255637 -53.819504) (xy 110.239603 -53.902694) (xy 110.215735 -53.983984)
			(xy 110.184247 -54.062636) (xy 110.145425 -54.137939) (xy 110.099622 -54.209211) (xy 110.047251 -54.275807)
			(xy 109.988786 -54.337122) (xy 109.924758 -54.392603) (xy 109.855746 -54.441746) (xy 109.782376 -54.484106)
			(xy 109.705311 -54.519301) (xy 109.687801 -54.525361) (xy 110.388142 -54.525361) (xy 110.388142 -54.440639)
			(xy 110.396195 -54.356302) (xy 110.412229 -54.273112) (xy 110.436097 -54.191822) (xy 110.467585 -54.11317)
			(xy 110.506407 -54.037867) (xy 110.55221 -53.966595) (xy 110.604581 -53.899999) (xy 110.663046 -53.838684)
			(xy 110.727074 -53.783203) (xy 110.796086 -53.73406) (xy 110.869456 -53.6917) (xy 110.946521 -53.656505)
			(xy 111.026583 -53.628796) (xy 111.108916 -53.608822) (xy 111.192775 -53.596765) (xy 111.2774 -53.592734)
			(xy 111.362025 -53.596765) (xy 111.445884 -53.608822) (xy 111.528217 -53.628796) (xy 111.608279 -53.656505)
			(xy 111.685344 -53.6917) (xy 111.758714 -53.73406) (xy 111.827726 -53.783203) (xy 111.891754 -53.838684)
			(xy 111.950219 -53.899999) (xy 112.00259 -53.966595) (xy 112.048393 -54.037867) (xy 112.087215 -54.11317)
			(xy 112.118703 -54.191822) (xy 112.142571 -54.273112) (xy 112.158605 -54.356302) (xy 112.166658 -54.440639)
			(xy 112.167162 -54.483) (xy 112.166658 -54.525361) (xy 112.158605 -54.609698) (xy 112.142571 -54.692888)
			(xy 112.118703 -54.774178) (xy 112.087215 -54.85283) (xy 112.048393 -54.928133) (xy 112.00259 -54.999405)
			(xy 111.950219 -55.066001) (xy 111.891754 -55.127316) (xy 111.827726 -55.182797) (xy 111.758714 -55.23194)
			(xy 111.685344 -55.2743) (xy 111.608279 -55.309495) (xy 111.528217 -55.337204) (xy 111.445884 -55.357178)
			(xy 111.362025 -55.369235) (xy 111.2774 -55.373267) (xy 111.192775 -55.369235) (xy 111.108916 -55.357178)
			(xy 111.026583 -55.337204) (xy 110.946521 -55.309495) (xy 110.869456 -55.2743) (xy 110.796086 -55.23194)
			(xy 110.727074 -55.182797) (xy 110.663046 -55.127316) (xy 110.604581 -55.066001) (xy 110.55221 -54.999405)
			(xy 110.506407 -54.928133) (xy 110.467585 -54.85283) (xy 110.436097 -54.774178) (xy 110.412229 -54.692888)
			(xy 110.396195 -54.609698) (xy 110.388142 -54.525361) (xy 109.687801 -54.525361) (xy 109.625249 -54.54701)
			(xy 109.542916 -54.566984) (xy 109.459057 -54.579041) (xy 109.374432 -54.583073) (xy 109.289807 -54.579041)
			(xy 109.205948 -54.566984) (xy 109.123615 -54.54701) (xy 109.043553 -54.519301) (xy 108.966488 -54.484106)
			(xy 108.893118 -54.441746) (xy 108.824106 -54.392603) (xy 108.760078 -54.337122) (xy 108.701613 -54.275807)
			(xy 108.649242 -54.209211) (xy 108.603439 -54.137939) (xy 108.564617 -54.062636) (xy 108.533129 -53.983984)
			(xy 108.509261 -53.902694) (xy 108.493227 -53.819504) (xy 108.485174 -53.735167) (xy 0.509016 -53.735167)
			(xy 0.509016 -56.150961) (xy 111.362994 -56.150961) (xy 111.362994 -56.066239) (xy 111.371047 -55.981902)
			(xy 111.387081 -55.898712) (xy 111.410949 -55.817422) (xy 111.442437 -55.73877) (xy 111.481259 -55.663467)
			(xy 111.527062 -55.592195) (xy 111.579433 -55.525599) (xy 111.637898 -55.464284) (xy 111.701926 -55.408803)
			(xy 111.770938 -55.35966) (xy 111.844308 -55.3173) (xy 111.921373 -55.282105) (xy 112.001435 -55.254396)
			(xy 112.083768 -55.234422) (xy 112.167627 -55.222365) (xy 112.252252 -55.218334) (xy 112.336877 -55.222365)
			(xy 112.420736 -55.234422) (xy 112.503069 -55.254396) (xy 112.583131 -55.282105) (xy 112.660196 -55.3173)
			(xy 112.733566 -55.35966) (xy 112.802578 -55.408803) (xy 112.866606 -55.464284) (xy 112.925071 -55.525599)
			(xy 112.977442 -55.592195) (xy 113.023245 -55.663467) (xy 113.062067 -55.73877) (xy 113.093555 -55.817422)
			(xy 113.117423 -55.898712) (xy 113.133457 -55.981902) (xy 113.14151 -56.066239) (xy 113.142014 -56.1086)
			(xy 113.14151 -56.150961) (xy 113.133457 -56.235298) (xy 113.117423 -56.318488) (xy 113.093555 -56.399778)
			(xy 113.062067 -56.47843) (xy 113.023245 -56.553733) (xy 112.977442 -56.625005) (xy 112.925071 -56.691601)
			(xy 112.866606 -56.752916) (xy 112.802578 -56.808397) (xy 112.733566 -56.85754) (xy 112.660196 -56.8999)
			(xy 112.583131 -56.935095) (xy 112.503069 -56.962804) (xy 112.420736 -56.982778) (xy 112.336877 -56.994835)
			(xy 112.252252 -56.998867) (xy 112.167627 -56.994835) (xy 112.083768 -56.982778) (xy 112.001435 -56.962804)
			(xy 111.921373 -56.935095) (xy 111.844308 -56.8999) (xy 111.770938 -56.85754) (xy 111.701926 -56.808397)
			(xy 111.637898 -56.752916) (xy 111.579433 -56.691601) (xy 111.527062 -56.625005) (xy 111.481259 -56.553733)
			(xy 111.442437 -56.47843) (xy 111.410949 -56.399778) (xy 111.387081 -56.318488) (xy 111.371047 -56.235298)
			(xy 111.362994 -56.150961) (xy 0.509016 -56.150961) (xy 0.509016 -60.099956) (xy 12.484104 -60.099956)
			(xy 12.488134 -59.957621) (xy 12.500209 -59.815741) (xy 12.520292 -59.674773) (xy 12.548319 -59.535166)
			(xy 12.584199 -59.397368) (xy 12.627817 -59.261821) (xy 12.679034 -59.128959) (xy 12.737685 -58.999207)
			(xy 12.803583 -58.872981) (xy 12.876517 -58.750685) (xy 12.956254 -58.632712) (xy 13.042536 -58.519439)
			(xy 13.135089 -58.411228) (xy 13.233616 -58.308427) (xy 13.337801 -58.211365) (xy 13.44731 -58.120353)
			(xy 13.561793 -58.035681) (xy 13.680883 -57.957623) (xy 13.804198 -57.886427) (xy 13.931344 -57.822321)
			(xy 14.061913 -57.765512) (xy 14.195487 -57.71618) (xy 14.331638 -57.674484) (xy 14.469929 -57.640558)
			(xy 14.609919 -57.61451) (xy 14.751158 -57.596424) (xy 14.893194 -57.586357) (xy 15.035572 -57.584342)
			(xy 15.177836 -57.590385) (xy 15.31953 -57.604467) (xy 15.4602 -57.626543) (xy 15.599397 -57.656543)
			(xy 15.736673 -57.694369) (xy 15.871589 -57.739901) (xy 16.003713 -57.792992) (xy 16.132622 -57.853474)
			(xy 16.257903 -57.921152) (xy 16.379154 -57.995809) (xy 16.495987 -58.077207) (xy 16.608028 -58.165084)
			(xy 16.714918 -58.259159) (xy 16.816315 -58.359131) (xy 16.871434 -58.42) (xy 40.838131 -58.42) (xy 40.842106 -58.309941)
			(xy 40.854014 -58.200455) (xy 40.87379 -58.092114) (xy 40.901333 -57.985483) (xy 40.936498 -57.881117)
			(xy 40.979102 -57.77956) (xy 41.028923 -57.681343) (xy 41.085702 -57.586976) (xy 41.149141 -57.496952)
			(xy 41.218912 -57.411741) (xy 41.294649 -57.331786) (xy 41.375958 -57.257505) (xy 41.462415 -57.189285)
			(xy 41.553569 -57.12748) (xy 41.648946 -57.072415) (xy 41.748047 -57.024375) (xy 41.850356 -56.983611)
			(xy 41.95534 -56.950336) (xy 42.062451 -56.924723) (xy 42.171131 -56.906906) (xy 42.280814 -56.896977)
			(xy 42.390927 -56.894989) (xy 42.500897 -56.900951) (xy 42.61015 -56.914833) (xy 42.718116 -56.936563)
			(xy 42.824233 -56.966026) (xy 42.927947 -57.003069) (xy 43.028718 -57.0475) (xy 43.12602 -57.099087)
			(xy 43.219346 -57.157559) (xy 43.308209 -57.222614) (xy 43.392147 -57.293912) (xy 43.470722 -57.37108)
			(xy 43.543523 -57.453717) (xy 43.610171 -57.541391) (xy 43.67032 -57.633647) (xy 43.723654 -57.730002)
			(xy 43.769897 -57.829954) (xy 43.808807 -57.932982) (xy 43.840181 -58.03855) (xy 43.863856 -58.146106)
			(xy 43.879708 -58.25509) (xy 43.887655 -58.364934) (xy 43.888152 -58.42) (xy 60.396131 -58.42) (xy 60.400106 -58.309941)
			(xy 60.412014 -58.200455) (xy 60.43179 -58.092114) (xy 60.459333 -57.985483) (xy 60.494498 -57.881117)
			(xy 60.537102 -57.77956) (xy 60.586923 -57.681343) (xy 60.643702 -57.586976) (xy 60.707141 -57.496952)
			(xy 60.776912 -57.411741) (xy 60.852649 -57.331786) (xy 60.933958 -57.257505) (xy 61.020415 -57.189285)
			(xy 61.111569 -57.12748) (xy 61.206946 -57.072415) (xy 61.306047 -57.024375) (xy 61.408356 -56.983611)
			(xy 61.51334 -56.950336) (xy 61.620451 -56.924723) (xy 61.729131 -56.906906) (xy 61.838814 -56.896977)
			(xy 61.948927 -56.894989) (xy 62.058897 -56.900951) (xy 62.16815 -56.914833) (xy 62.276116 -56.936563)
			(xy 62.382233 -56.966026) (xy 62.485947 -57.003069) (xy 62.586718 -57.0475) (xy 62.68402 -57.099087)
			(xy 62.777346 -57.157559) (xy 62.866209 -57.222614) (xy 62.950147 -57.293912) (xy 63.028722 -57.37108)
			(xy 63.101523 -57.453717) (xy 63.168171 -57.541391) (xy 63.22832 -57.633647) (xy 63.281654 -57.730002)
			(xy 63.327897 -57.829954) (xy 63.366807 -57.932982) (xy 63.398181 -58.03855) (xy 63.421856 -58.146106)
			(xy 63.437708 -58.25509) (xy 63.445655 -58.364934) (xy 63.446152 -58.42) (xy 63.445655 -58.475066)
			(xy 63.437708 -58.58491) (xy 63.421856 -58.693894) (xy 63.398181 -58.80145) (xy 63.366807 -58.907018)
			(xy 63.327897 -59.010046) (xy 63.281654 -59.109998) (xy 63.22832 -59.206353) (xy 63.168171 -59.298609)
			(xy 63.101523 -59.386283) (xy 63.028722 -59.46892) (xy 62.950147 -59.546088) (xy 62.866209 -59.617386)
			(xy 62.777346 -59.682441) (xy 62.68402 -59.740913) (xy 62.586718 -59.7925) (xy 62.485947 -59.836931)
			(xy 62.382233 -59.873974) (xy 62.276116 -59.903437) (xy 62.16815 -59.925167) (xy 62.058897 -59.939049)
			(xy 61.948927 -59.945011) (xy 61.838814 -59.943023) (xy 61.729131 -59.933094) (xy 61.620451 -59.915277)
			(xy 61.51334 -59.889664) (xy 61.408356 -59.856389) (xy 61.306047 -59.815625) (xy 61.206946 -59.767585)
			(xy 61.111569 -59.71252) (xy 61.020415 -59.650715) (xy 60.933958 -59.582495) (xy 60.852649 -59.508214)
			(xy 60.776912 -59.428259) (xy 60.707141 -59.343048) (xy 60.643702 -59.253024) (xy 60.586923 -59.158657)
			(xy 60.537102 -59.06044) (xy 60.494498 -58.958883) (xy 60.459333 -58.854517) (xy 60.43179 -58.747886)
			(xy 60.412014 -58.639545) (xy 60.400106 -58.530059) (xy 60.396131 -58.42) (xy 43.888152 -58.42) (xy 43.887655 -58.475066)
			(xy 43.879708 -58.58491) (xy 43.863856 -58.693894) (xy 43.840181 -58.80145) (xy 43.808807 -58.907018)
			(xy 43.769897 -59.010046) (xy 43.723654 -59.109998) (xy 43.67032 -59.206353) (xy 43.610171 -59.298609)
			(xy 43.543523 -59.386283) (xy 43.470722 -59.46892) (xy 43.392147 -59.546088) (xy 43.308209 -59.617386)
			(xy 43.219346 -59.682441) (xy 43.12602 -59.740913) (xy 43.028718 -59.7925) (xy 42.927947 -59.836931)
			(xy 42.824233 -59.873974) (xy 42.718116 -59.903437) (xy 42.61015 -59.925167) (xy 42.500897 -59.939049)
			(xy 42.390927 -59.945011) (xy 42.280814 -59.943023) (xy 42.171131 -59.933094) (xy 42.062451 -59.915277)
			(xy 41.95534 -59.889664) (xy 41.850356 -59.856389) (xy 41.748047 -59.815625) (xy 41.648946 -59.767585)
			(xy 41.553569 -59.71252) (xy 41.462415 -59.650715) (xy 41.375958 -59.582495) (xy 41.294649 -59.508214)
			(xy 41.218912 -59.428259) (xy 41.149141 -59.343048) (xy 41.085702 -59.253024) (xy 41.028923 -59.158657)
			(xy 40.979102 -59.06044) (xy 40.936498 -58.958883) (xy 40.901333 -58.854517) (xy 40.87379 -58.747886)
			(xy 40.854014 -58.639545) (xy 40.842106 -58.530059) (xy 40.838131 -58.42) (xy 16.871434 -58.42) (xy 16.911893 -58.464679)
			(xy 17.001347 -58.575465) (xy 17.084389 -58.691134) (xy 17.160755 -58.811317) (xy 17.230199 -58.935627)
			(xy 17.292499 -59.063668) (xy 17.347455 -59.195027) (xy 17.394892 -59.329286) (xy 17.434656 -59.466013)
			(xy 17.466622 -59.604771) (xy 17.490687 -59.745115) (xy 17.506773 -59.886596) (xy 17.514828 -60.02876)
			(xy 17.515332 -60.099956) (xy 17.514828 -60.171152) (xy 17.506773 -60.313316) (xy 17.490687 -60.454797)
			(xy 17.466622 -60.595141) (xy 17.434656 -60.733899) (xy 17.394892 -60.870626) (xy 17.347455 -61.004885)
			(xy 17.292499 -61.136244) (xy 17.230199 -61.264285) (xy 17.160755 -61.388595) (xy 17.084389 -61.508778)
			(xy 17.001347 -61.624447) (xy 16.911893 -61.735233) (xy 16.816315 -61.840781) (xy 16.714918 -61.940753)
			(xy 16.608028 -62.034828) (xy 16.495987 -62.122705) (xy 16.379154 -62.204103) (xy 16.257903 -62.27876)
			(xy 16.132622 -62.346438) (xy 16.055974 -62.3824) (xy 111.565944 -62.3824) (xy 111.565944 -62.381892)
			(xy 111.566546 -62.33556) (xy 111.576218 -62.243402) (xy 111.595414 -62.152748) (xy 111.623928 -62.064579)
			(xy 111.642144 -62.021974) (xy 111.645952 -62.012032) (xy 111.645952 -61.990768) (xy 111.642144 -61.980826)
			(xy 111.623902 -61.938162) (xy 111.595357 -61.849871) (xy 111.576163 -61.759086) (xy 111.566529 -61.666796)
			(xy 111.565944 -61.6204) (xy 111.566522 -61.574004) (xy 111.576168 -61.481716) (xy 111.595365 -61.390932)
			(xy 111.623905 -61.302639) (xy 111.642144 -61.259974) (xy 111.645952 -61.250032) (xy 111.645952 -61.228768)
			(xy 111.642144 -61.218826) (xy 111.623902 -61.176162) (xy 111.595357 -61.087871) (xy 111.576163 -60.997086)
			(xy 111.566529 -60.904796) (xy 111.565944 -60.8584) (xy 111.566522 -60.812004) (xy 111.576168 -60.719716)
			(xy 111.595365 -60.628932) (xy 111.623905 -60.540639) (xy 111.642144 -60.497974) (xy 111.645952 -60.488032)
			(xy 111.645952 -60.466768) (xy 111.642144 -60.456826) (xy 111.623902 -60.414162) (xy 111.595357 -60.325871)
			(xy 111.576163 -60.235086) (xy 111.566529 -60.142796) (xy 111.565944 -60.0964) (xy 111.566522 -60.050004)
			(xy 111.576168 -59.957716) (xy 111.595365 -59.866932) (xy 111.623905 -59.778639) (xy 111.642144 -59.735974)
			(xy 111.645952 -59.726032) (xy 111.645952 -59.704768) (xy 111.642144 -59.694826) (xy 111.623919 -59.652224)
			(xy 111.595403 -59.564056) (xy 111.576211 -59.4734) (xy 111.566552 -59.38124) (xy 111.565944 -59.334908)
			(xy 111.565944 -59.3344) (xy 111.566467 -59.293299) (xy 111.574051 -59.211447) (xy 111.589155 -59.130645)
			(xy 111.61165 -59.05158) (xy 111.641344 -58.974929) (xy 111.677983 -58.901344) (xy 111.721256 -58.831453)
			(xy 111.770792 -58.765854) (xy 111.82617 -58.705104) (xy 111.886917 -58.649723) (xy 111.952514 -58.600183)
			(xy 112.022402 -58.556907) (xy 112.095985 -58.520263) (xy 112.172635 -58.490565) (xy 112.251698 -58.468066)
			(xy 112.3325 -58.452958) (xy 112.414351 -58.445369) (xy 112.455452 -58.444892) (xy 112.45596 -58.444892)
			(xy 112.502291 -58.445515) (xy 112.594449 -58.455181) (xy 112.685103 -58.474372) (xy 112.773272 -58.502879)
			(xy 112.815878 -58.521092) (xy 112.82582 -58.524898) (xy 112.847084 -58.524898) (xy 112.857026 -58.521092)
			(xy 112.899695 -58.502863) (xy 112.987985 -58.474315) (xy 113.078768 -58.455117) (xy 113.171056 -58.445479)
			(xy 113.217452 -58.444892) (xy 113.263847 -58.445492) (xy 113.356135 -58.455132) (xy 113.446919 -58.474323)
			(xy 113.535213 -58.502856) (xy 113.577878 -58.521092) (xy 113.58782 -58.524898) (xy 113.609084 -58.524898)
			(xy 113.619026 -58.521092) (xy 113.661695 -58.502863) (xy 113.749985 -58.474315) (xy 113.840768 -58.455117)
			(xy 113.933056 -58.445479) (xy 113.979452 -58.444892) (xy 114.025847 -58.445492) (xy 114.118135 -58.455132)
			(xy 114.208919 -58.474323) (xy 114.297213 -58.502856) (xy 114.339878 -58.521092) (xy 114.34982 -58.524898)
			(xy 114.371084 -58.524898) (xy 114.381026 -58.521092) (xy 114.423695 -58.502863) (xy 114.511985 -58.474315)
			(xy 114.602768 -58.455117) (xy 114.695056 -58.445479) (xy 114.741452 -58.444892) (xy 114.787847 -58.445492)
			(xy 114.880135 -58.455132) (xy 114.970919 -58.474323) (xy 115.059213 -58.502856) (xy 115.101878 -58.521092)
			(xy 115.11182 -58.524898) (xy 115.133084 -58.524898) (xy 115.143026 -58.521092) (xy 115.185635 -58.502886)
			(xy 115.2738 -58.474364) (xy 115.364454 -58.455167) (xy 115.456612 -58.445503) (xy 115.502944 -58.444892)
			(xy 115.503452 -58.444892) (xy 115.544554 -58.445398) (xy 115.626409 -58.452979) (xy 115.707215 -58.46808)
			(xy 115.786282 -58.490573) (xy 115.862937 -58.520265) (xy 115.936525 -58.556904) (xy 116.006418 -58.600177)
			(xy 116.072021 -58.649714) (xy 116.132772 -58.705094) (xy 116.188155 -58.765842) (xy 116.237696 -58.831442)
			(xy 116.280972 -58.901333) (xy 116.317615 -58.974919) (xy 116.347312 -59.051572) (xy 116.369809 -59.130639)
			(xy 116.384915 -59.211444) (xy 116.3925 -59.293298) (xy 116.39296 -59.3344) (xy 116.39296 -59.334908)
			(xy 116.392358 -59.38124) (xy 116.382686 -59.473398) (xy 116.363489 -59.564052) (xy 116.334976 -59.652221)
			(xy 116.31676 -59.694826) (xy 116.312952 -59.704768) (xy 116.312952 -59.726032) (xy 116.31676 -59.735974)
			(xy 116.335002 -59.778637) (xy 116.363547 -59.866929) (xy 116.382741 -59.957714) (xy 116.392375 -60.050004)
			(xy 116.39296 -60.0964) (xy 116.392381 -60.142796) (xy 116.382736 -60.235084) (xy 116.363539 -60.325868)
			(xy 116.334999 -60.414161) (xy 116.31676 -60.456826) (xy 116.312952 -60.466768) (xy 116.312952 -60.488032)
			(xy 116.31676 -60.497974) (xy 116.335002 -60.540637) (xy 116.363547 -60.628929) (xy 116.382741 -60.719714)
			(xy 116.392375 -60.812004) (xy 116.39296 -60.8584) (xy 116.392381 -60.904796) (xy 116.382736 -60.997084)
			(xy 116.363539 -61.087868) (xy 116.334999 -61.176161) (xy 116.31676 -61.218826) (xy 116.312952 -61.228768)
			(xy 116.312952 -61.250032) (xy 116.31676 -61.259974) (xy 116.335002 -61.302637) (xy 116.363547 -61.390929)
			(xy 116.382741 -61.481714) (xy 116.392375 -61.574004) (xy 116.39296 -61.6204) (xy 116.392381 -61.666796)
			(xy 116.382736 -61.759084) (xy 116.363539 -61.849868) (xy 116.334999 -61.938161) (xy 116.31676 -61.980826)
			(xy 116.312952 -61.990768) (xy 116.312952 -62.012032) (xy 116.31676 -62.021974) (xy 116.334985 -62.064576)
			(xy 116.363501 -62.152744) (xy 116.382693 -62.243399) (xy 116.392352 -62.33556) (xy 116.39296 -62.381892)
			(xy 116.39296 -62.3824) (xy 116.392548 -62.423505) (xy 116.384962 -62.505363) (xy 116.369856 -62.586172)
			(xy 116.347357 -62.665243) (xy 116.317659 -62.7419) (xy 116.281014 -62.81549) (xy 116.237735 -62.885385)
			(xy 116.188192 -62.950988) (xy 116.132806 -63.01174) (xy 116.072051 -63.067122) (xy 116.006446 -63.116662)
			(xy 115.936548 -63.159938) (xy 115.862956 -63.196579) (xy 115.786297 -63.226273) (xy 115.707226 -63.248767)
			(xy 115.626415 -63.263869) (xy 115.544557 -63.27145) (xy 115.503452 -63.271908) (xy 115.502944 -63.271908)
			(xy 115.456613 -63.271284) (xy 115.364455 -63.261618) (xy 115.273801 -63.242427) (xy 115.185632 -63.213921)
			(xy 115.143026 -63.195708) (xy 115.133084 -63.191902) (xy 115.11182 -63.191902) (xy 115.101878 -63.195708)
			(xy 115.059209 -63.213936) (xy 114.970919 -63.242484) (xy 114.880136 -63.261682) (xy 114.787847 -63.27132)
			(xy 114.741452 -63.271908) (xy 114.695057 -63.271307) (xy 114.602769 -63.261667) (xy 114.511985 -63.242476)
			(xy 114.423691 -63.213943) (xy 114.381026 -63.195708) (xy 114.371084 -63.191902) (xy 114.34982 -63.191902)
			(xy 114.339878 -63.195708) (xy 114.297209 -63.213936) (xy 114.208919 -63.242484) (xy 114.118136 -63.261682)
			(xy 114.025847 -63.27132) (xy 113.979452 -63.271908) (xy 113.933057 -63.271307) (xy 113.840769 -63.261667)
			(xy 113.749985 -63.242476) (xy 113.661691 -63.213943) (xy 113.619026 -63.195708) (xy 113.609084 -63.191902)
			(xy 113.58782 -63.191902) (xy 113.577878 -63.195708) (xy 113.535209 -63.213936) (xy 113.446919 -63.242484)
			(xy 113.356136 -63.261682) (xy 113.263847 -63.27132) (xy 113.217452 -63.271908) (xy 113.171057 -63.271307)
			(xy 113.078769 -63.261667) (xy 112.987985 -63.242476) (xy 112.899691 -63.213943) (xy 112.857026 -63.195708)
			(xy 112.847084 -63.191902) (xy 112.82582 -63.191902) (xy 112.815878 -63.195708) (xy 112.773268 -63.213913)
			(xy 112.685103 -63.242435) (xy 112.59445 -63.261633) (xy 112.502292 -63.271297) (xy 112.45596 -63.271908)
			(xy 112.455452 -63.271908) (xy 112.414349 -63.271479) (xy 112.332493 -63.26389) (xy 112.251687 -63.248781)
			(xy 112.17262 -63.22628) (xy 112.095965 -63.196581) (xy 112.022379 -63.159935) (xy 111.952487 -63.116657)
			(xy 111.886886 -63.067114) (xy 111.826136 -63.01173) (xy 111.770755 -62.950977) (xy 111.721216 -62.885374)
			(xy 111.677941 -62.815479) (xy 111.6413 -62.741891) (xy 111.611604 -62.665235) (xy 111.589108 -62.586166)
			(xy 111.574003 -62.505359) (xy 111.566419 -62.423503) (xy 111.565944 -62.3824) (xy 16.055974 -62.3824)
			(xy 16.003713 -62.40692) (xy 15.871589 -62.460011) (xy 15.736673 -62.505543) (xy 15.599397 -62.543369)
			(xy 15.4602 -62.573369) (xy 15.31953 -62.595445) (xy 15.177836 -62.609527) (xy 15.035572 -62.61557)
			(xy 14.893194 -62.613555) (xy 14.751158 -62.603488) (xy 14.609919 -62.585402) (xy 14.469929 -62.559354)
			(xy 14.331638 -62.525428) (xy 14.195487 -62.483732) (xy 14.061913 -62.4344) (xy 13.931344 -62.377591)
			(xy 13.804198 -62.313485) (xy 13.680883 -62.242289) (xy 13.561793 -62.164231) (xy 13.44731 -62.079559)
			(xy 13.337801 -61.988547) (xy 13.233616 -61.891485) (xy 13.135089 -61.788684) (xy 13.042536 -61.680473)
			(xy 12.956254 -61.5672) (xy 12.876517 -61.449227) (xy 12.803583 -61.326931) (xy 12.737685 -61.200705)
			(xy 12.679034 -61.070953) (xy 12.627817 -60.938091) (xy 12.584199 -60.802544) (xy 12.548319 -60.664746)
			(xy 12.520292 -60.525139) (xy 12.500209 -60.384171) (xy 12.488134 -60.242291) (xy 12.484104 -60.099956)
			(xy 0.509016 -60.099956) (xy 0.509016 -67.428561) (xy 111.362994 -67.428561) (xy 111.362994 -67.343839)
			(xy 111.371047 -67.259502) (xy 111.387081 -67.176312) (xy 111.410949 -67.095022) (xy 111.442437 -67.01637)
			(xy 111.481259 -66.941067) (xy 111.527062 -66.869795) (xy 111.579433 -66.803199) (xy 111.637898 -66.741884)
			(xy 111.701926 -66.686403) (xy 111.770938 -66.63726) (xy 111.844308 -66.5949) (xy 111.921373 -66.559705)
			(xy 112.001435 -66.531996) (xy 112.083768 -66.512022) (xy 112.167627 -66.499965) (xy 112.252252 -66.495934)
			(xy 112.336877 -66.499965) (xy 112.420736 -66.512022) (xy 112.503069 -66.531996) (xy 112.583131 -66.559705)
			(xy 112.660196 -66.5949) (xy 112.733566 -66.63726) (xy 112.802578 -66.686403) (xy 112.866606 -66.741884)
			(xy 112.925071 -66.803199) (xy 112.977442 -66.869795) (xy 113.023245 -66.941067) (xy 113.062067 -67.01637)
			(xy 113.093555 -67.095022) (xy 113.117423 -67.176312) (xy 113.133457 -67.259502) (xy 113.14151 -67.343839)
			(xy 113.142014 -67.3862) (xy 113.14151 -67.428561) (xy 113.133457 -67.512898) (xy 113.117423 -67.596088)
			(xy 113.093555 -67.677378) (xy 113.062067 -67.75603) (xy 113.023245 -67.831333) (xy 112.977442 -67.902605)
			(xy 112.925071 -67.969201) (xy 112.866606 -68.030516) (xy 112.802578 -68.085997) (xy 112.733566 -68.13514)
			(xy 112.660196 -68.1775) (xy 112.583131 -68.212695) (xy 112.503069 -68.240404) (xy 112.420736 -68.260378)
			(xy 112.336877 -68.272435) (xy 112.252252 -68.276467) (xy 112.167627 -68.272435) (xy 112.083768 -68.260378)
			(xy 112.001435 -68.240404) (xy 111.921373 -68.212695) (xy 111.844308 -68.1775) (xy 111.770938 -68.13514)
			(xy 111.701926 -68.085997) (xy 111.637898 -68.030516) (xy 111.579433 -67.969201) (xy 111.527062 -67.902605)
			(xy 111.481259 -67.831333) (xy 111.442437 -67.75603) (xy 111.410949 -67.677378) (xy 111.387081 -67.596088)
			(xy 111.371047 -67.512898) (xy 111.362994 -67.428561) (xy 0.509016 -67.428561) (xy 0.509016 -71.239888)
			(xy 41.345622 -71.239888) (xy 41.349604 -71.149938) (xy 41.361521 -71.060691) (xy 41.381279 -70.972847)
			(xy 41.408723 -70.887093) (xy 41.443639 -70.8041) (xy 41.485753 -70.724518) (xy 41.534736 -70.648969)
			(xy 41.590204 -70.578045) (xy 41.651724 -70.5123) (xy 41.718813 -70.45225) (xy 41.790947 -70.398365)
			(xy 41.867561 -70.351065) (xy 41.948055 -70.310722) (xy 42.0318 -70.27765) (xy 42.118141 -70.25211)
			(xy 42.2064 -70.2343) (xy 42.295889 -70.22436) (xy 42.385905 -70.222369) (xy 42.475746 -70.22834)
			(xy 42.564707 -70.242229) (xy 42.652092 -70.263925) (xy 42.737218 -70.29326) (xy 42.819418 -70.330003)
			(xy 42.898049 -70.373867) (xy 42.972496 -70.424509) (xy 43.042176 -70.481533) (xy 43.106543 -70.544492)
			(xy 43.165094 -70.612893) (xy 43.217371 -70.686201) (xy 43.262964 -70.763843) (xy 43.301517 -70.84521)
			(xy 43.332728 -70.929666) (xy 43.356352 -71.01655) (xy 43.372205 -71.105182) (xy 43.380162 -71.194869)
			(xy 43.38066 -71.239888) (xy 60.903622 -71.239888) (xy 60.907604 -71.149938) (xy 60.919521 -71.060691)
			(xy 60.939279 -70.972847) (xy 60.966723 -70.887093) (xy 61.001639 -70.8041) (xy 61.043753 -70.724518)
			(xy 61.092736 -70.648969) (xy 61.148204 -70.578045) (xy 61.209724 -70.5123) (xy 61.276813 -70.45225)
			(xy 61.348947 -70.398365) (xy 61.425561 -70.351065) (xy 61.506055 -70.310722) (xy 61.5898 -70.27765)
			(xy 61.676141 -70.25211) (xy 61.7644 -70.2343) (xy 61.853889 -70.22436) (xy 61.943905 -70.222369)
			(xy 62.033746 -70.22834) (xy 62.122707 -70.242229) (xy 62.210092 -70.263925) (xy 62.295218 -70.29326)
			(xy 62.377418 -70.330003) (xy 62.456049 -70.373867) (xy 62.530496 -70.424509) (xy 62.600176 -70.481533)
			(xy 62.664543 -70.544492) (xy 62.723094 -70.612893) (xy 62.775371 -70.686201) (xy 62.820964 -70.763843)
			(xy 62.859517 -70.84521) (xy 62.890728 -70.929666) (xy 62.914352 -71.01655) (xy 62.930205 -71.105182)
			(xy 62.938162 -71.194869) (xy 62.93866 -71.239888) (xy 62.938162 -71.284907) (xy 62.930205 -71.374594)
			(xy 62.914352 -71.463226) (xy 62.890728 -71.55011) (xy 62.859517 -71.634566) (xy 62.820964 -71.715933)
			(xy 62.775371 -71.793575) (xy 62.723094 -71.866883) (xy 62.664543 -71.935284) (xy 62.600176 -71.998243)
			(xy 62.530496 -72.055267) (xy 62.456049 -72.105909) (xy 62.377418 -72.149773) (xy 62.295218 -72.186516)
			(xy 62.210092 -72.215851) (xy 62.122707 -72.237547) (xy 62.033746 -72.251436) (xy 61.943905 -72.257407)
			(xy 61.853889 -72.255416) (xy 61.7644 -72.245476) (xy 61.676141 -72.227666) (xy 61.5898 -72.202126)
			(xy 61.506055 -72.169054) (xy 61.425561 -72.128711) (xy 61.348947 -72.081411) (xy 61.276813 -72.027526)
			(xy 61.209724 -71.967476) (xy 61.148204 -71.901731) (xy 61.092736 -71.830807) (xy 61.043753 -71.755258)
			(xy 61.001639 -71.675676) (xy 60.966723 -71.592683) (xy 60.939279 -71.506929) (xy 60.919521 -71.419085)
			(xy 60.907604 -71.329838) (xy 60.903622 -71.239888) (xy 43.38066 -71.239888) (xy 43.380162 -71.284907)
			(xy 43.372205 -71.374594) (xy 43.356352 -71.463226) (xy 43.332728 -71.55011) (xy 43.301517 -71.634566)
			(xy 43.262964 -71.715933) (xy 43.217371 -71.793575) (xy 43.165094 -71.866883) (xy 43.106543 -71.935284)
			(xy 43.042176 -71.998243) (xy 42.972496 -72.055267) (xy 42.898049 -72.105909) (xy 42.819418 -72.149773)
			(xy 42.737218 -72.186516) (xy 42.652092 -72.215851) (xy 42.564707 -72.237547) (xy 42.475746 -72.251436)
			(xy 42.385905 -72.257407) (xy 42.295889 -72.255416) (xy 42.2064 -72.245476) (xy 42.118141 -72.227666)
			(xy 42.0318 -72.202126) (xy 41.948055 -72.169054) (xy 41.867561 -72.128711) (xy 41.790947 -72.081411)
			(xy 41.718813 -72.027526) (xy 41.651724 -71.967476) (xy 41.590204 -71.901731) (xy 41.534736 -71.830807)
			(xy 41.485753 -71.755258) (xy 41.443639 -71.675676) (xy 41.408723 -71.592683) (xy 41.381279 -71.506929)
			(xy 41.361521 -71.419085) (xy 41.349604 -71.329838) (xy 41.345622 -71.239888) (xy 0.509016 -71.239888)
			(xy 0.509016 -73.66) (xy 111.565944 -73.66) (xy 111.565944 -73.659492) (xy 111.566546 -73.61316)
			(xy 111.576218 -73.521002) (xy 111.595414 -73.430348) (xy 111.623928 -73.342179) (xy 111.642144 -73.299574)
			(xy 111.645952 -73.289632) (xy 111.645952 -73.268368) (xy 111.642144 -73.258426) (xy 111.623902 -73.215762)
			(xy 111.595357 -73.127471) (xy 111.576163 -73.036686) (xy 111.566529 -72.944396) (xy 111.565944 -72.898)
			(xy 111.566522 -72.851604) (xy 111.576168 -72.759316) (xy 111.595365 -72.668532) (xy 111.623905 -72.580239)
			(xy 111.642144 -72.537574) (xy 111.645952 -72.527632) (xy 111.645952 -72.506368) (xy 111.642144 -72.496426)
			(xy 111.623902 -72.453762) (xy 111.595357 -72.365471) (xy 111.576163 -72.274686) (xy 111.566529 -72.182396)
			(xy 111.565944 -72.136) (xy 111.566522 -72.089604) (xy 111.576168 -71.997316) (xy 111.595365 -71.906532)
			(xy 111.623905 -71.818239) (xy 111.642144 -71.775574) (xy 111.645952 -71.765632) (xy 111.645952 -71.744368)
			(xy 111.642144 -71.734426) (xy 111.623902 -71.691762) (xy 111.595357 -71.603471) (xy 111.576163 -71.512686)
			(xy 111.566529 -71.420396) (xy 111.565944 -71.374) (xy 111.566522 -71.327604) (xy 111.576168 -71.235316)
			(xy 111.595365 -71.144532) (xy 111.623905 -71.056239) (xy 111.642144 -71.013574) (xy 111.645952 -71.003632)
			(xy 111.645952 -70.982368) (xy 111.642144 -70.972426) (xy 111.623919 -70.929824) (xy 111.595403 -70.841656)
			(xy 111.576211 -70.751) (xy 111.566552 -70.65884) (xy 111.565944 -70.612508) (xy 111.565944 -70.612)
			(xy 111.566467 -70.570899) (xy 111.574051 -70.489047) (xy 111.589155 -70.408245) (xy 111.61165 -70.32918)
			(xy 111.641344 -70.252529) (xy 111.677983 -70.178944) (xy 111.721256 -70.109053) (xy 111.770792 -70.043454)
			(xy 111.82617 -69.982704) (xy 111.886917 -69.927323) (xy 111.952514 -69.877783) (xy 112.022402 -69.834507)
			(xy 112.095985 -69.797863) (xy 112.172635 -69.768165) (xy 112.251698 -69.745666) (xy 112.3325 -69.730558)
			(xy 112.414351 -69.722969) (xy 112.455452 -69.722492) (xy 112.45596 -69.722492) (xy 112.502291 -69.723115)
			(xy 112.594449 -69.732781) (xy 112.685103 -69.751972) (xy 112.773272 -69.780479) (xy 112.815878 -69.798692)
			(xy 112.82582 -69.802498) (xy 112.847084 -69.802498) (xy 112.857026 -69.798692) (xy 112.899695 -69.780463)
			(xy 112.987985 -69.751915) (xy 113.078768 -69.732717) (xy 113.171056 -69.723079) (xy 113.217452 -69.722492)
			(xy 113.263847 -69.723092) (xy 113.356135 -69.732732) (xy 113.446919 -69.751923) (xy 113.535213 -69.780456)
			(xy 113.577878 -69.798692) (xy 113.58782 -69.802498) (xy 113.609084 -69.802498) (xy 113.619026 -69.798692)
			(xy 113.661695 -69.780463) (xy 113.749985 -69.751915) (xy 113.840768 -69.732717) (xy 113.933056 -69.723079)
			(xy 113.979452 -69.722492) (xy 114.025847 -69.723092) (xy 114.118135 -69.732732) (xy 114.208919 -69.751923)
			(xy 114.297213 -69.780456) (xy 114.339878 -69.798692) (xy 114.34982 -69.802498) (xy 114.371084 -69.802498)
			(xy 114.381026 -69.798692) (xy 114.423695 -69.780463) (xy 114.511985 -69.751915) (xy 114.602768 -69.732717)
			(xy 114.695056 -69.723079) (xy 114.741452 -69.722492) (xy 114.787847 -69.723092) (xy 114.880135 -69.732732)
			(xy 114.970919 -69.751923) (xy 115.059213 -69.780456) (xy 115.101878 -69.798692) (xy 115.11182 -69.802498)
			(xy 115.133084 -69.802498) (xy 115.143026 -69.798692) (xy 115.185635 -69.780486) (xy 115.2738 -69.751964)
			(xy 115.364454 -69.732767) (xy 115.456612 -69.723103) (xy 115.502944 -69.722492) (xy 115.503452 -69.722492)
			(xy 115.544554 -69.722998) (xy 115.626409 -69.730579) (xy 115.707215 -69.74568) (xy 115.786282 -69.768173)
			(xy 115.862937 -69.797865) (xy 115.936525 -69.834504) (xy 116.006418 -69.877777) (xy 116.072021 -69.927314)
			(xy 116.132772 -69.982694) (xy 116.188155 -70.043442) (xy 116.237696 -70.109042) (xy 116.280972 -70.178933)
			(xy 116.317615 -70.252519) (xy 116.347312 -70.329172) (xy 116.369809 -70.408239) (xy 116.384915 -70.489044)
			(xy 116.3925 -70.570898) (xy 116.39296 -70.612) (xy 116.39296 -70.612508) (xy 116.392358 -70.65884)
			(xy 116.382686 -70.750998) (xy 116.363489 -70.841652) (xy 116.334976 -70.929821) (xy 116.31676 -70.972426)
			(xy 116.312952 -70.982368) (xy 116.312952 -71.003632) (xy 116.31676 -71.013574) (xy 116.335002 -71.056237)
			(xy 116.363547 -71.144529) (xy 116.382741 -71.235314) (xy 116.392375 -71.327604) (xy 116.39296 -71.374)
			(xy 116.392381 -71.420396) (xy 116.382736 -71.512684) (xy 116.363539 -71.603468) (xy 116.334999 -71.691761)
			(xy 116.31676 -71.734426) (xy 116.312952 -71.744368) (xy 116.312952 -71.765632) (xy 116.31676 -71.775574)
			(xy 116.335002 -71.818237) (xy 116.363547 -71.906529) (xy 116.382741 -71.997314) (xy 116.392375 -72.089604)
			(xy 116.39296 -72.136) (xy 116.392381 -72.182396) (xy 116.382736 -72.274684) (xy 116.363539 -72.365468)
			(xy 116.334999 -72.453761) (xy 116.31676 -72.496426) (xy 116.312952 -72.506368) (xy 116.312952 -72.527632)
			(xy 116.31676 -72.537574) (xy 116.335002 -72.580237) (xy 116.363547 -72.668529) (xy 116.382741 -72.759314)
			(xy 116.392375 -72.851604) (xy 116.39296 -72.898) (xy 116.392381 -72.944396) (xy 116.382736 -73.036684)
			(xy 116.363539 -73.127468) (xy 116.334999 -73.215761) (xy 116.31676 -73.258426) (xy 116.312952 -73.268368)
			(xy 116.312952 -73.289632) (xy 116.31676 -73.299574) (xy 116.334985 -73.342176) (xy 116.363501 -73.430344)
			(xy 116.382693 -73.520999) (xy 116.392352 -73.61316) (xy 116.39296 -73.659492) (xy 116.39296 -73.66)
			(xy 116.392548 -73.701105) (xy 116.384962 -73.782963) (xy 116.369856 -73.863772) (xy 116.347357 -73.942843)
			(xy 116.317659 -74.0195) (xy 116.281014 -74.09309) (xy 116.237735 -74.162985) (xy 116.188192 -74.228588)
			(xy 116.132806 -74.28934) (xy 116.072051 -74.344722) (xy 116.006446 -74.394262) (xy 115.936548 -74.437538)
			(xy 115.862956 -74.474179) (xy 115.786297 -74.503873) (xy 115.707226 -74.526367) (xy 115.626415 -74.541469)
			(xy 115.544557 -74.54905) (xy 115.503452 -74.549508) (xy 115.502944 -74.549508) (xy 115.456613 -74.548884)
			(xy 115.364455 -74.539218) (xy 115.273801 -74.520027) (xy 115.185632 -74.491521) (xy 115.143026 -74.473308)
			(xy 115.133084 -74.469502) (xy 115.11182 -74.469502) (xy 115.101878 -74.473308) (xy 115.059209 -74.491536)
			(xy 114.970919 -74.520084) (xy 114.880136 -74.539282) (xy 114.787847 -74.54892) (xy 114.741452 -74.549508)
			(xy 114.695057 -74.548907) (xy 114.602769 -74.539267) (xy 114.511985 -74.520076) (xy 114.423691 -74.491543)
			(xy 114.381026 -74.473308) (xy 114.371084 -74.469502) (xy 114.34982 -74.469502) (xy 114.339878 -74.473308)
			(xy 114.297209 -74.491536) (xy 114.208919 -74.520084) (xy 114.118136 -74.539282) (xy 114.025847 -74.54892)
			(xy 113.979452 -74.549508) (xy 113.933057 -74.548907) (xy 113.840769 -74.539267) (xy 113.749985 -74.520076)
			(xy 113.661691 -74.491543) (xy 113.619026 -74.473308) (xy 113.609084 -74.469502) (xy 113.58782 -74.469502)
			(xy 113.577878 -74.473308) (xy 113.535209 -74.491536) (xy 113.446919 -74.520084) (xy 113.356136 -74.539282)
			(xy 113.263847 -74.54892) (xy 113.217452 -74.549508) (xy 113.171057 -74.548907) (xy 113.078769 -74.539267)
			(xy 112.987985 -74.520076) (xy 112.899691 -74.491543) (xy 112.857026 -74.473308) (xy 112.847084 -74.469502)
			(xy 112.82582 -74.469502) (xy 112.815878 -74.473308) (xy 112.773268 -74.491513) (xy 112.685103 -74.520035)
			(xy 112.59445 -74.539233) (xy 112.502292 -74.548897) (xy 112.45596 -74.549508) (xy 112.455452 -74.549508)
			(xy 112.414349 -74.549079) (xy 112.332493 -74.54149) (xy 112.251687 -74.526381) (xy 112.17262 -74.50388)
			(xy 112.095965 -74.474181) (xy 112.022379 -74.437535) (xy 111.952487 -74.394257) (xy 111.886886 -74.344714)
			(xy 111.826136 -74.28933) (xy 111.770755 -74.228577) (xy 111.721216 -74.162974) (xy 111.677941 -74.093079)
			(xy 111.6413 -74.019491) (xy 111.611604 -73.942835) (xy 111.589108 -73.863766) (xy 111.574003 -73.782959)
			(xy 111.566419 -73.701103) (xy 111.565944 -73.66) (xy 0.509016 -73.66) (xy 0.509016 -78.74) (xy 40.838131 -78.74)
			(xy 40.842106 -78.629941) (xy 40.854014 -78.520455) (xy 40.87379 -78.412114) (xy 40.901333 -78.305483)
			(xy 40.936498 -78.201117) (xy 40.979102 -78.09956) (xy 41.028923 -78.001343) (xy 41.085702 -77.906976)
			(xy 41.149141 -77.816952) (xy 41.218912 -77.731741) (xy 41.294649 -77.651786) (xy 41.375958 -77.577505)
			(xy 41.462415 -77.509285) (xy 41.553569 -77.44748) (xy 41.648946 -77.392415) (xy 41.748047 -77.344375)
			(xy 41.850356 -77.303611) (xy 41.95534 -77.270336) (xy 42.062451 -77.244723) (xy 42.171131 -77.226906)
			(xy 42.280814 -77.216977) (xy 42.390927 -77.214989) (xy 42.500897 -77.220951) (xy 42.61015 -77.234833)
			(xy 42.718116 -77.256563) (xy 42.824233 -77.286026) (xy 42.927947 -77.323069) (xy 43.028718 -77.3675)
			(xy 43.12602 -77.419087) (xy 43.219346 -77.477559) (xy 43.308209 -77.542614) (xy 43.392147 -77.613912)
			(xy 43.470722 -77.69108) (xy 43.543523 -77.773717) (xy 43.610171 -77.861391) (xy 43.67032 -77.953647)
			(xy 43.723654 -78.050002) (xy 43.769897 -78.149954) (xy 43.808807 -78.252982) (xy 43.840181 -78.35855)
			(xy 43.863856 -78.466106) (xy 43.879708 -78.57509) (xy 43.887655 -78.684934) (xy 43.888152 -78.74)
			(xy 60.396131 -78.74) (xy 60.400106 -78.629941) (xy 60.412014 -78.520455) (xy 60.43179 -78.412114)
			(xy 60.459333 -78.305483) (xy 60.494498 -78.201117) (xy 60.537102 -78.09956) (xy 60.586923 -78.001343)
			(xy 60.643702 -77.906976) (xy 60.707141 -77.816952) (xy 60.776912 -77.731741) (xy 60.852649 -77.651786)
			(xy 60.933958 -77.577505) (xy 61.020415 -77.509285) (xy 61.111569 -77.44748) (xy 61.206946 -77.392415)
			(xy 61.306047 -77.344375) (xy 61.408356 -77.303611) (xy 61.51334 -77.270336) (xy 61.620451 -77.244723)
			(xy 61.729131 -77.226906) (xy 61.838814 -77.216977) (xy 61.948927 -77.214989) (xy 62.058897 -77.220951)
			(xy 62.16815 -77.234833) (xy 62.276116 -77.256563) (xy 62.382233 -77.286026) (xy 62.485947 -77.323069)
			(xy 62.586718 -77.3675) (xy 62.68402 -77.419087) (xy 62.777346 -77.477559) (xy 62.866209 -77.542614)
			(xy 62.950147 -77.613912) (xy 63.028722 -77.69108) (xy 63.101523 -77.773717) (xy 63.168171 -77.861391)
			(xy 63.22832 -77.953647) (xy 63.281654 -78.050002) (xy 63.327897 -78.149954) (xy 63.366807 -78.252982)
			(xy 63.398181 -78.35855) (xy 63.421856 -78.466106) (xy 63.437708 -78.57509) (xy 63.445655 -78.684934)
			(xy 63.445847 -78.706161) (xy 111.362994 -78.706161) (xy 111.362994 -78.621439) (xy 111.371047 -78.537102)
			(xy 111.387081 -78.453912) (xy 111.410949 -78.372622) (xy 111.442437 -78.29397) (xy 111.481259 -78.218667)
			(xy 111.527062 -78.147395) (xy 111.579433 -78.080799) (xy 111.637898 -78.019484) (xy 111.701926 -77.964003)
			(xy 111.770938 -77.91486) (xy 111.844308 -77.8725) (xy 111.921373 -77.837305) (xy 112.001435 -77.809596)
			(xy 112.083768 -77.789622) (xy 112.167627 -77.777565) (xy 112.252252 -77.773534) (xy 112.336877 -77.777565)
			(xy 112.420736 -77.789622) (xy 112.503069 -77.809596) (xy 112.583131 -77.837305) (xy 112.660196 -77.8725)
			(xy 112.733566 -77.91486) (xy 112.802578 -77.964003) (xy 112.866606 -78.019484) (xy 112.925071 -78.080799)
			(xy 112.977442 -78.147395) (xy 113.023245 -78.218667) (xy 113.062067 -78.29397) (xy 113.093555 -78.372622)
			(xy 113.117423 -78.453912) (xy 113.133457 -78.537102) (xy 113.14151 -78.621439) (xy 113.142014 -78.6638)
			(xy 113.14151 -78.706161) (xy 113.133457 -78.790498) (xy 113.117423 -78.873688) (xy 113.093555 -78.954978)
			(xy 113.062067 -79.03363) (xy 113.023245 -79.108933) (xy 112.977442 -79.180205) (xy 112.925071 -79.246801)
			(xy 112.866606 -79.308116) (xy 112.802578 -79.363597) (xy 112.733566 -79.41274) (xy 112.660196 -79.4551)
			(xy 112.583131 -79.490295) (xy 112.503069 -79.518004) (xy 112.420736 -79.537978) (xy 112.336877 -79.550035)
			(xy 112.252252 -79.554067) (xy 112.167627 -79.550035) (xy 112.083768 -79.537978) (xy 112.001435 -79.518004)
			(xy 111.921373 -79.490295) (xy 111.844308 -79.4551) (xy 111.770938 -79.41274) (xy 111.701926 -79.363597)
			(xy 111.637898 -79.308116) (xy 111.579433 -79.246801) (xy 111.527062 -79.180205) (xy 111.481259 -79.108933)
			(xy 111.442437 -79.03363) (xy 111.410949 -78.954978) (xy 111.387081 -78.873688) (xy 111.371047 -78.790498)
			(xy 111.362994 -78.706161) (xy 63.445847 -78.706161) (xy 63.446152 -78.74) (xy 63.445655 -78.795066)
			(xy 63.437708 -78.90491) (xy 63.421856 -79.013894) (xy 63.398181 -79.12145) (xy 63.366807 -79.227018)
			(xy 63.327897 -79.330046) (xy 63.281654 -79.429998) (xy 63.22832 -79.526353) (xy 63.168171 -79.618609)
			(xy 63.101523 -79.706283) (xy 63.028722 -79.78892) (xy 62.950147 -79.866088) (xy 62.930237 -79.883)
			(xy 122.3264 -79.883) (xy 122.3264 -13.081) (xy 122.326939 -13.047741) (xy 122.335625 -12.981791)
			(xy 122.352847 -12.91754) (xy 122.378311 -12.856089) (xy 122.411582 -12.798488) (xy 122.452088 -12.745724)
			(xy 122.475244 -12.721844) (xy 123.110244 -12.086844) (xy 123.134129 -12.063692) (xy 123.186889 -12.023179)
			(xy 123.244488 -11.989903) (xy 123.305939 -11.964434) (xy 123.37019 -11.947209) (xy 123.43614 -11.938521)
			(xy 123.4694 -11.938) (xy 156.980382 -11.938) (xy 157.013641 -11.938551) (xy 157.07959 -11.947234)
			(xy 157.143841 -11.964454) (xy 157.205292 -11.989916) (xy 157.262894 -12.023184) (xy 157.315658 -12.063689)
			(xy 157.339538 -12.086844) (xy 161.039556 -15.786862) (xy 161.062716 -15.810739) (xy 161.103229 -15.863501)
			(xy 161.136504 -15.921101) (xy 161.161971 -15.982554) (xy 161.179195 -16.046806) (xy 161.18788 -16.112758)
			(xy 161.1884 -16.146018) (xy 161.1884 -22.560114) (xy 205.177635 -22.560114) (xy 205.177635 -22.389758)
			(xy 205.18562 -22.21959) (xy 205.201572 -22.049983) (xy 205.225457 -21.881311) (xy 205.257221 -21.713943)
			(xy 205.296796 -21.548248) (xy 205.344093 -21.38459) (xy 205.39901 -21.223329) (xy 205.461425 -21.064819)
			(xy 205.531201 -20.909409) (xy 205.608184 -20.757441) (xy 205.692206 -20.609247) (xy 205.783082 -20.465155)
			(xy 205.880612 -20.325481) (xy 205.984582 -20.190532) (xy 206.094763 -20.060604) (xy 206.210912 -19.935984)
			(xy 206.332776 -19.816945) (xy 206.460084 -19.703749) (xy 206.592559 -19.596644) (xy 206.729909 -19.495867)
			(xy 206.871831 -19.401638) (xy 207.018013 -19.314165) (xy 207.168136 -19.23364) (xy 207.321867 -19.16024)
			(xy 207.47887 -19.094126) (xy 207.6388 -19.035444) (xy 207.801304 -18.984323) (xy 207.966025 -18.940875)
			(xy 208.132603 -18.905196) (xy 208.300669 -18.877364) (xy 208.469855 -18.85744) (xy 208.639789 -18.845468)
			(xy 208.810098 -18.841475) (xy 208.980407 -18.845468) (xy 209.150341 -18.85744) (xy 209.319527 -18.877364)
			(xy 209.487593 -18.905196) (xy 209.654171 -18.940875) (xy 209.818892 -18.984323) (xy 209.981396 -19.035444)
			(xy 210.141326 -19.094126) (xy 210.298329 -19.16024) (xy 210.45206 -19.23364) (xy 210.602183 -19.314165)
			(xy 210.748365 -19.401638) (xy 210.890287 -19.495867) (xy 211.027637 -19.596644) (xy 211.160112 -19.703749)
			(xy 211.28742 -19.816945) (xy 211.409284 -19.935984) (xy 211.525433 -20.060604) (xy 211.635614 -20.190532)
			(xy 211.739584 -20.325481) (xy 211.837114 -20.465155) (xy 211.92799 -20.609247) (xy 212.012012 -20.757441)
			(xy 212.088995 -20.909409) (xy 212.158771 -21.064819) (xy 212.221186 -21.223329) (xy 212.276103 -21.38459)
			(xy 212.3234 -21.548248) (xy 212.362975 -21.713943) (xy 212.394739 -21.881311) (xy 212.418624 -22.049983)
			(xy 212.434576 -22.21959) (xy 212.442561 -22.389758) (xy 212.44306 -22.474936) (xy 212.442561 -22.560114)
			(xy 235.177575 -22.560114) (xy 235.177575 -22.389758) (xy 235.18556 -22.21959) (xy 235.201512 -22.049983)
			(xy 235.225397 -21.881311) (xy 235.257161 -21.713943) (xy 235.296736 -21.548248) (xy 235.344033 -21.38459)
			(xy 235.39895 -21.223329) (xy 235.461365 -21.064819) (xy 235.531141 -20.909409) (xy 235.608124 -20.757441)
			(xy 235.692146 -20.609247) (xy 235.783022 -20.465155) (xy 235.880552 -20.325481) (xy 235.984522 -20.190532)
			(xy 236.094703 -20.060604) (xy 236.210852 -19.935984) (xy 236.332716 -19.816945) (xy 236.460024 -19.703749)
			(xy 236.592499 -19.596644) (xy 236.729849 -19.495867) (xy 236.871771 -19.401638) (xy 237.017953 -19.314165)
			(xy 237.168076 -19.23364) (xy 237.321807 -19.16024) (xy 237.47881 -19.094126) (xy 237.63874 -19.035444)
			(xy 237.801244 -18.984323) (xy 237.965965 -18.940875) (xy 238.132543 -18.905196) (xy 238.300609 -18.877364)
			(xy 238.469795 -18.85744) (xy 238.639729 -18.845468) (xy 238.810038 -18.841475) (xy 238.980347 -18.845468)
			(xy 239.150281 -18.85744) (xy 239.319467 -18.877364) (xy 239.487533 -18.905196) (xy 239.654111 -18.940875)
			(xy 239.818832 -18.984323) (xy 239.981336 -19.035444) (xy 240.141266 -19.094126) (xy 240.298269 -19.16024)
			(xy 240.452 -19.23364) (xy 240.602123 -19.314165) (xy 240.748305 -19.401638) (xy 240.890227 -19.495867)
			(xy 241.027577 -19.596644) (xy 241.160052 -19.703749) (xy 241.28736 -19.816945) (xy 241.409224 -19.935984)
			(xy 241.525373 -20.060604) (xy 241.635554 -20.190532) (xy 241.739524 -20.325481) (xy 241.837054 -20.465155)
			(xy 241.92793 -20.609247) (xy 242.011952 -20.757441) (xy 242.088935 -20.909409) (xy 242.158711 -21.064819)
			(xy 242.221126 -21.223329) (xy 242.276043 -21.38459) (xy 242.32334 -21.548248) (xy 242.362915 -21.713943)
			(xy 242.394679 -21.881311) (xy 242.418564 -22.049983) (xy 242.434516 -22.21959) (xy 242.442501 -22.389758)
			(xy 242.443 -22.474936) (xy 242.442501 -22.560114) (xy 242.434516 -22.730282) (xy 242.418564 -22.899889)
			(xy 242.394679 -23.068561) (xy 242.362915 -23.235929) (xy 242.32334 -23.401624) (xy 242.276043 -23.565282)
			(xy 242.221126 -23.726543) (xy 242.158711 -23.885053) (xy 242.088935 -24.040463) (xy 242.011952 -24.192431)
			(xy 241.92793 -24.340625) (xy 241.837054 -24.484717) (xy 241.739524 -24.624391) (xy 241.635554 -24.75934)
			(xy 241.525373 -24.889268) (xy 241.409224 -25.013888) (xy 241.28736 -25.132927) (xy 241.160052 -25.246123)
			(xy 241.027577 -25.353228) (xy 240.890227 -25.454005) (xy 240.748305 -25.548234) (xy 240.602123 -25.635707)
			(xy 240.452 -25.716232) (xy 240.298269 -25.789632) (xy 240.141266 -25.855746) (xy 239.981336 -25.914428)
			(xy 239.818832 -25.965549) (xy 239.654111 -26.008997) (xy 239.487533 -26.044676) (xy 239.319467 -26.072508)
			(xy 239.150281 -26.092432) (xy 238.980347 -26.104404) (xy 238.810038 -26.108398) (xy 238.639729 -26.104404)
			(xy 238.469795 -26.092432) (xy 238.300609 -26.072508) (xy 238.132543 -26.044676) (xy 237.965965 -26.008997)
			(xy 237.801244 -25.965549) (xy 237.63874 -25.914428) (xy 237.47881 -25.855746) (xy 237.321807 -25.789632)
			(xy 237.168076 -25.716232) (xy 237.017953 -25.635707) (xy 236.871771 -25.548234) (xy 236.729849 -25.454005)
			(xy 236.592499 -25.353228) (xy 236.460024 -25.246123) (xy 236.332716 -25.132927) (xy 236.210852 -25.013888)
			(xy 236.094703 -24.889268) (xy 235.984522 -24.75934) (xy 235.880552 -24.624391) (xy 235.783022 -24.484717)
			(xy 235.692146 -24.340625) (xy 235.608124 -24.192431) (xy 235.531141 -24.040463) (xy 235.461365 -23.885053)
			(xy 235.39895 -23.726543) (xy 235.344033 -23.565282) (xy 235.296736 -23.401624) (xy 235.257161 -23.235929)
			(xy 235.225397 -23.068561) (xy 235.201512 -22.899889) (xy 235.18556 -22.730282) (xy 235.177575 -22.560114)
			(xy 212.442561 -22.560114) (xy 212.434576 -22.730282) (xy 212.418624 -22.899889) (xy 212.394739 -23.068561)
			(xy 212.362975 -23.235929) (xy 212.3234 -23.401624) (xy 212.276103 -23.565282) (xy 212.221186 -23.726543)
			(xy 212.158771 -23.885053) (xy 212.088995 -24.040463) (xy 212.012012 -24.192431) (xy 211.92799 -24.340625)
			(xy 211.837114 -24.484717) (xy 211.739584 -24.624391) (xy 211.635614 -24.75934) (xy 211.525433 -24.889268)
			(xy 211.409284 -25.013888) (xy 211.28742 -25.132927) (xy 211.160112 -25.246123) (xy 211.027637 -25.353228)
			(xy 210.890287 -25.454005) (xy 210.748365 -25.548234) (xy 210.602183 -25.635707) (xy 210.45206 -25.716232)
			(xy 210.298329 -25.789632) (xy 210.141326 -25.855746) (xy 209.981396 -25.914428) (xy 209.818892 -25.965549)
			(xy 209.654171 -26.008997) (xy 209.487593 -26.044676) (xy 209.319527 -26.072508) (xy 209.150341 -26.092432)
			(xy 208.980407 -26.104404) (xy 208.810098 -26.108398) (xy 208.639789 -26.104404) (xy 208.469855 -26.092432)
			(xy 208.300669 -26.072508) (xy 208.132603 -26.044676) (xy 207.966025 -26.008997) (xy 207.801304 -25.965549)
			(xy 207.6388 -25.914428) (xy 207.47887 -25.855746) (xy 207.321867 -25.789632) (xy 207.168136 -25.716232)
			(xy 207.018013 -25.635707) (xy 206.871831 -25.548234) (xy 206.729909 -25.454005) (xy 206.592559 -25.353228)
			(xy 206.460084 -25.246123) (xy 206.332776 -25.132927) (xy 206.210912 -25.013888) (xy 206.094763 -24.889268)
			(xy 205.984582 -24.75934) (xy 205.880612 -24.624391) (xy 205.783082 -24.484717) (xy 205.692206 -24.340625)
			(xy 205.608184 -24.192431) (xy 205.531201 -24.040463) (xy 205.461425 -23.885053) (xy 205.39901 -23.726543)
			(xy 205.344093 -23.565282) (xy 205.296796 -23.401624) (xy 205.257221 -23.235929) (xy 205.225457 -23.068561)
			(xy 205.201572 -22.899889) (xy 205.18562 -22.730282) (xy 205.177635 -22.560114) (xy 161.1884 -22.560114)
			(xy 161.1884 -26.950924) (xy 161.188786 -26.960998) (xy 161.196532 -26.979597) (xy 161.203386 -26.986992)
			(xy 162.141408 -27.925014) (xy 162.14881 -27.931852) (xy 162.167408 -27.939572) (xy 162.177476 -27.94)
			(xy 209.1944 -27.94) (xy 209.227659 -27.940539) (xy 209.293609 -27.949225) (xy 209.35786 -27.966447)
			(xy 209.419311 -27.991911) (xy 209.476912 -28.025182) (xy 209.529676 -28.065688) (xy 209.553556 -28.088844)
			(xy 211.331556 -29.866844) (xy 211.354708 -29.890729) (xy 211.395221 -29.943489) (xy 211.428497 -30.001088)
			(xy 211.453966 -30.062539) (xy 211.471191 -30.12679) (xy 211.479879 -30.19274) (xy 211.4804 -30.226)
			(xy 211.4804 -46.99) (xy 228.854 -46.99) (xy 228.854 -30.226) (xy 228.854539 -30.192741) (xy 228.863225 -30.126791)
			(xy 228.880447 -30.06254) (xy 228.905911 -30.001089) (xy 228.939182 -29.943488) (xy 228.979688 -29.890724)
			(xy 229.002844 -29.866844) (xy 230.780844 -28.088844) (xy 230.804729 -28.065692) (xy 230.857489 -28.025179)
			(xy 230.915088 -27.991903) (xy 230.976539 -27.966434) (xy 231.04079 -27.949209) (xy 231.10674 -27.940521)
			(xy 231.14 -27.94) (xy 278.156924 -27.94) (xy 278.166998 -27.939614) (xy 278.185597 -27.931868) (xy 278.192992 -27.925014)
			(xy 279.131014 -26.986992) (xy 279.137852 -26.97959) (xy 279.145572 -26.960992) (xy 279.146 -26.950924)
			(xy 279.146 -16.146018) (xy 279.146551 -16.112759) (xy 279.155234 -16.04681) (xy 279.172454 -15.982559)
			(xy 279.197916 -15.921108) (xy 279.231184 -15.863506) (xy 279.271689 -15.810742) (xy 279.294844 -15.786862)
			(xy 282.994862 -12.086844) (xy 283.018739 -12.063684) (xy 283.071501 -12.023171) (xy 283.129101 -11.989896)
			(xy 283.190554 -11.964429) (xy 283.254806 -11.947205) (xy 283.320758 -11.93852) (xy 283.354018 -11.938)
			(xy 323.977 -11.938) (xy 324.010259 -11.938539) (xy 324.076209 -11.947225) (xy 324.14046 -11.964447)
			(xy 324.201911 -11.989911) (xy 324.259512 -12.023182) (xy 324.312276 -12.063688) (xy 324.336156 -12.086844)
			(xy 324.971156 -12.721844) (xy 324.994308 -12.745729) (xy 325.034821 -12.798489) (xy 325.068097 -12.856088)
			(xy 325.093566 -12.917539) (xy 325.110791 -12.98179) (xy 325.119479 -13.04774) (xy 325.12 -13.081)
			(xy 325.12 -17.288961) (xy 334.478626 -17.288961) (xy 334.478626 -17.204239) (xy 334.486679 -17.119902)
			(xy 334.502713 -17.036712) (xy 334.526581 -16.955422) (xy 334.558069 -16.87677) (xy 334.596891 -16.801467)
			(xy 334.642694 -16.730195) (xy 334.695065 -16.663599) (xy 334.75353 -16.602284) (xy 334.817558 -16.546803)
			(xy 334.88657 -16.49766) (xy 334.95994 -16.4553) (xy 335.037005 -16.420105) (xy 335.117067 -16.392396)
			(xy 335.1994 -16.372422) (xy 335.283259 -16.360365) (xy 335.367884 -16.356334) (xy 335.452509 -16.360365)
			(xy 335.536368 -16.372422) (xy 335.618701 -16.392396) (xy 335.698763 -16.420105) (xy 335.775828 -16.4553)
			(xy 335.849198 -16.49766) (xy 335.91821 -16.546803) (xy 335.982238 -16.602284) (xy 336.040703 -16.663599)
			(xy 336.093074 -16.730195) (xy 336.138877 -16.801467) (xy 336.177699 -16.87677) (xy 336.209187 -16.955422)
			(xy 336.233055 -17.036712) (xy 336.249089 -17.119902) (xy 336.257142 -17.204239) (xy 336.257646 -17.2466)
			(xy 336.257142 -17.288961) (xy 336.249089 -17.373298) (xy 336.233055 -17.456488) (xy 336.209187 -17.537778)
			(xy 336.177699 -17.61643) (xy 336.138877 -17.691733) (xy 336.093074 -17.763005) (xy 336.040703 -17.829601)
			(xy 335.982238 -17.890916) (xy 335.91821 -17.946397) (xy 335.849198 -17.99554) (xy 335.775828 -18.0379)
			(xy 335.698763 -18.073095) (xy 335.618701 -18.100804) (xy 335.536368 -18.120778) (xy 335.452509 -18.132835)
			(xy 335.367884 -18.136867) (xy 335.283259 -18.132835) (xy 335.1994 -18.120778) (xy 335.117067 -18.100804)
			(xy 335.037005 -18.073095) (xy 334.95994 -18.0379) (xy 334.88657 -17.99554) (xy 334.817558 -17.946397)
			(xy 334.75353 -17.890916) (xy 334.695065 -17.829601) (xy 334.642694 -17.763005) (xy 334.596891 -17.691733)
			(xy 334.558069 -17.61643) (xy 334.526581 -17.537778) (xy 334.502713 -17.456488) (xy 334.486679 -17.373298)
			(xy 334.478626 -17.288961) (xy 325.12 -17.288961) (xy 325.12 -23.0886) (xy 331.266292 -23.0886) (xy 331.266292 -23.088092)
			(xy 331.266898 -23.04176) (xy 331.276569 -22.949602) (xy 331.295765 -22.858948) (xy 331.324277 -22.770779)
			(xy 331.342492 -22.728174) (xy 331.346298 -22.718232) (xy 331.346298 -22.696968) (xy 331.342492 -22.687026)
			(xy 331.324247 -22.644364) (xy 331.295703 -22.556071) (xy 331.27651 -22.465286) (xy 331.266877 -22.372996)
			(xy 331.266292 -22.3266) (xy 331.266875 -22.280204) (xy 331.27652 -22.187916) (xy 331.295716 -22.097132)
			(xy 331.324254 -22.008839) (xy 331.342492 -21.966174) (xy 331.346298 -21.956232) (xy 331.346298 -21.934968)
			(xy 331.342492 -21.925026) (xy 331.324247 -21.882364) (xy 331.295703 -21.794071) (xy 331.27651 -21.703286)
			(xy 331.266877 -21.610996) (xy 331.266292 -21.5646) (xy 331.266875 -21.518204) (xy 331.27652 -21.425916)
			(xy 331.295716 -21.335132) (xy 331.324254 -21.246839) (xy 331.342492 -21.204174) (xy 331.346298 -21.194232)
			(xy 331.346298 -21.172968) (xy 331.342492 -21.163026) (xy 331.324247 -21.120364) (xy 331.295703 -21.032071)
			(xy 331.27651 -20.941286) (xy 331.266877 -20.848996) (xy 331.266292 -20.8026) (xy 331.266875 -20.756204)
			(xy 331.27652 -20.663916) (xy 331.295716 -20.573132) (xy 331.324254 -20.484839) (xy 331.342492 -20.442174)
			(xy 331.346298 -20.432232) (xy 331.346298 -20.410968) (xy 331.342492 -20.401026) (xy 331.32427 -20.358423)
			(xy 331.295752 -20.270256) (xy 331.27656 -20.1796) (xy 331.2669 -20.08744) (xy 331.266292 -20.041108)
			(xy 331.266292 -20.0406) (xy 331.266767 -19.999498) (xy 331.274352 -19.917643) (xy 331.289457 -19.836838)
			(xy 331.311953 -19.757771) (xy 331.341649 -19.681117) (xy 331.378291 -19.60753) (xy 331.421566 -19.537638)
			(xy 331.471106 -19.472037) (xy 331.526487 -19.411287) (xy 331.587237 -19.355906) (xy 331.652838 -19.306366)
			(xy 331.72273 -19.263091) (xy 331.796317 -19.226449) (xy 331.872971 -19.196753) (xy 331.952038 -19.174257)
			(xy 332.032843 -19.159152) (xy 332.114698 -19.151567) (xy 332.1558 -19.151092) (xy 332.156308 -19.151092)
			(xy 332.20264 -19.151698) (xy 332.294798 -19.161369) (xy 332.385452 -19.180565) (xy 332.473621 -19.209077)
			(xy 332.516226 -19.227292) (xy 332.526168 -19.231098) (xy 332.547432 -19.231098) (xy 332.557374 -19.227292)
			(xy 332.600036 -19.209047) (xy 332.688329 -19.180503) (xy 332.779114 -19.16131) (xy 332.871404 -19.151677)
			(xy 332.9178 -19.151092) (xy 332.964196 -19.151675) (xy 333.056484 -19.16132) (xy 333.147268 -19.180516)
			(xy 333.235561 -19.209054) (xy 333.278226 -19.227292) (xy 333.288168 -19.231098) (xy 333.309432 -19.231098)
			(xy 333.319374 -19.227292) (xy 333.362036 -19.209047) (xy 333.450329 -19.180503) (xy 333.541114 -19.16131)
			(xy 333.633404 -19.151677) (xy 333.6798 -19.151092) (xy 333.726196 -19.151675) (xy 333.818484 -19.16132)
			(xy 333.909268 -19.180516) (xy 333.997561 -19.209054) (xy 334.040226 -19.227292) (xy 334.050168 -19.231098)
			(xy 334.071432 -19.231098) (xy 334.081374 -19.227292) (xy 334.124036 -19.209047) (xy 334.212329 -19.180503)
			(xy 334.303114 -19.16131) (xy 334.395404 -19.151677) (xy 334.4418 -19.151092) (xy 334.488196 -19.151675)
			(xy 334.580484 -19.16132) (xy 334.671268 -19.180516) (xy 334.759561 -19.209054) (xy 334.802226 -19.227292)
			(xy 334.812168 -19.231098) (xy 334.833432 -19.231098) (xy 334.843374 -19.227292) (xy 334.885977 -19.20907)
			(xy 334.974144 -19.180552) (xy 335.0648 -19.16136) (xy 335.15696 -19.1517) (xy 335.203292 -19.151092)
			(xy 335.2038 -19.151092) (xy 335.244902 -19.151567) (xy 335.326757 -19.159152) (xy 335.407562 -19.174257)
			(xy 335.486629 -19.196753) (xy 335.563283 -19.226449) (xy 335.63687 -19.263091) (xy 335.706762 -19.306366)
			(xy 335.772363 -19.355906) (xy 335.833113 -19.411287) (xy 335.888494 -19.472037) (xy 335.938034 -19.537638)
			(xy 335.981309 -19.60753) (xy 336.017951 -19.681117) (xy 336.047647 -19.757771) (xy 336.070143 -19.836838)
			(xy 336.085248 -19.917643) (xy 336.092833 -19.999498) (xy 336.09288 -20.00357) (xy 386.295635 -20.00357)
			(xy 386.295635 -19.87443) (xy 386.303585 -19.745535) (xy 386.319455 -19.617375) (xy 386.343184 -19.490434)
			(xy 386.374683 -19.365195) (xy 386.413832 -19.242132) (xy 386.460483 -19.121713) (xy 386.514458 -19.004394)
			(xy 386.575553 -18.89062) (xy 386.643536 -18.780823) (xy 386.71815 -18.67542) (xy 386.799111 -18.57481)
			(xy 386.886111 -18.479375) (xy 386.978822 -18.389476) (xy 387.076892 -18.305455) (xy 387.179947 -18.227631)
			(xy 387.287598 -18.156299) (xy 387.399437 -18.091729) (xy 387.515038 -18.034167) (xy 387.633963 -17.98383)
			(xy 387.755762 -17.94091) (xy 387.879972 -17.905569) (xy 388.006121 -17.877942) (xy 388.133733 -17.858133)
			(xy 388.262322 -17.846217) (xy 388.3914 -17.842241) (xy 388.520478 -17.846217) (xy 388.649067 -17.858133)
			(xy 388.776679 -17.877942) (xy 388.902828 -17.905569) (xy 389.027038 -17.94091) (xy 389.148837 -17.98383)
			(xy 389.267762 -18.034167) (xy 389.383363 -18.091729) (xy 389.495202 -18.156299) (xy 389.602853 -18.227631)
			(xy 389.705908 -18.305455) (xy 389.803978 -18.389476) (xy 389.896689 -18.479375) (xy 389.983689 -18.57481)
			(xy 390.06465 -18.67542) (xy 390.139264 -18.780823) (xy 390.207247 -18.89062) (xy 390.268342 -19.004394)
			(xy 390.322317 -19.121713) (xy 390.368968 -19.242132) (xy 390.408117 -19.365195) (xy 390.439616 -19.490434)
			(xy 390.463345 -19.617375) (xy 390.479215 -19.745535) (xy 390.487165 -19.87443) (xy 390.487662 -19.939)
			(xy 390.487165 -20.00357) (xy 390.479215 -20.132465) (xy 390.463345 -20.260625) (xy 390.439616 -20.387566)
			(xy 390.408117 -20.512805) (xy 390.368968 -20.635868) (xy 390.322317 -20.756287) (xy 390.268342 -20.873606)
			(xy 390.207247 -20.98738) (xy 390.139264 -21.097177) (xy 390.06465 -21.20258) (xy 389.983689 -21.30319)
			(xy 389.896689 -21.398625) (xy 389.803978 -21.488524) (xy 389.705908 -21.572545) (xy 389.602853 -21.650369)
			(xy 389.495202 -21.721701) (xy 389.383363 -21.786271) (xy 389.267762 -21.843833) (xy 389.148837 -21.89417)
			(xy 389.027038 -21.93709) (xy 388.902828 -21.972431) (xy 388.776679 -22.000058) (xy 388.649067 -22.019867)
			(xy 388.520478 -22.031783) (xy 388.3914 -22.03576) (xy 388.262322 -22.031783) (xy 388.133733 -22.019867)
			(xy 388.006121 -22.000058) (xy 387.879972 -21.972431) (xy 387.755762 -21.93709) (xy 387.633963 -21.89417)
			(xy 387.515038 -21.843833) (xy 387.399437 -21.786271) (xy 387.287598 -21.721701) (xy 387.179947 -21.650369)
			(xy 387.076892 -21.572545) (xy 386.978822 -21.488524) (xy 386.886111 -21.398625) (xy 386.799111 -21.30319)
			(xy 386.71815 -21.20258) (xy 386.643536 -21.097177) (xy 386.575553 -20.98738) (xy 386.514458 -20.873606)
			(xy 386.460483 -20.756287) (xy 386.413832 -20.635868) (xy 386.374683 -20.512805) (xy 386.343184 -20.387566)
			(xy 386.319455 -20.260625) (xy 386.303585 -20.132465) (xy 386.295635 -20.00357) (xy 336.09288 -20.00357)
			(xy 336.093308 -20.0406) (xy 336.093308 -20.041108) (xy 336.092702 -20.08744) (xy 336.083031 -20.179598)
			(xy 336.063835 -20.270252) (xy 336.035323 -20.358421) (xy 336.017108 -20.401026) (xy 336.013302 -20.410968)
			(xy 336.013302 -20.432232) (xy 336.017108 -20.442174) (xy 336.035353 -20.484836) (xy 336.063897 -20.573129)
			(xy 336.08309 -20.663914) (xy 336.092723 -20.756204) (xy 336.093308 -20.8026) (xy 336.092725 -20.848996)
			(xy 336.08308 -20.941284) (xy 336.063884 -21.032068) (xy 336.035346 -21.120361) (xy 336.017108 -21.163026)
			(xy 336.013302 -21.172968) (xy 336.013302 -21.194232) (xy 336.017108 -21.204174) (xy 336.035353 -21.246836)
			(xy 336.063897 -21.335129) (xy 336.08309 -21.425914) (xy 336.092723 -21.518204) (xy 336.093308 -21.5646)
			(xy 336.092725 -21.610996) (xy 336.08308 -21.703284) (xy 336.063884 -21.794068) (xy 336.035346 -21.882361)
			(xy 336.017108 -21.925026) (xy 336.013302 -21.934968) (xy 336.013302 -21.956232) (xy 336.017108 -21.966174)
			(xy 336.035353 -22.008836) (xy 336.063897 -22.097129) (xy 336.08309 -22.187914) (xy 336.092723 -22.280204)
			(xy 336.093308 -22.3266) (xy 336.092725 -22.372996) (xy 336.08308 -22.465284) (xy 336.063884 -22.556068)
			(xy 336.035346 -22.644361) (xy 336.017108 -22.687026) (xy 336.013302 -22.696968) (xy 336.013302 -22.718232)
			(xy 336.017108 -22.728174) (xy 336.03533 -22.770777) (xy 336.063848 -22.858944) (xy 336.08304 -22.9496)
			(xy 336.0927 -23.04176) (xy 336.093308 -23.088092) (xy 336.093308 -23.0886) (xy 336.092833 -23.129702)
			(xy 336.085248 -23.211557) (xy 336.070143 -23.292362) (xy 336.047647 -23.371429) (xy 336.017951 -23.448083)
			(xy 335.981309 -23.52167) (xy 335.938034 -23.591562) (xy 335.888494 -23.657163) (xy 335.833113 -23.717913)
			(xy 335.772363 -23.773294) (xy 335.706762 -23.822834) (xy 335.63687 -23.866109) (xy 335.563283 -23.902751)
			(xy 335.486629 -23.932447) (xy 335.407562 -23.954943) (xy 335.326757 -23.970048) (xy 335.244902 -23.977633)
			(xy 335.2038 -23.978108) (xy 335.203292 -23.978108) (xy 335.15696 -23.977502) (xy 335.064802 -23.967831)
			(xy 334.974148 -23.948635) (xy 334.885979 -23.920123) (xy 334.843374 -23.901908) (xy 334.833432 -23.898102)
			(xy 334.812168 -23.898102) (xy 334.802226 -23.901908) (xy 334.759564 -23.920153) (xy 334.671271 -23.948697)
			(xy 334.580486 -23.96789) (xy 334.488196 -23.977523) (xy 334.4418 -23.978108) (xy 334.395404 -23.977525)
			(xy 334.303116 -23.96788) (xy 334.212332 -23.948684) (xy 334.124039 -23.920146) (xy 334.081374 -23.901908)
			(xy 334.071432 -23.898102) (xy 334.050168 -23.898102) (xy 334.040226 -23.901908) (xy 333.997564 -23.920153)
			(xy 333.909271 -23.948697) (xy 333.818486 -23.96789) (xy 333.726196 -23.977523) (xy 333.6798 -23.978108)
			(xy 333.633404 -23.977525) (xy 333.541116 -23.96788) (xy 333.450332 -23.948684) (xy 333.362039 -23.920146)
			(xy 333.319374 -23.901908) (xy 333.309432 -23.898102) (xy 333.288168 -23.898102) (xy 333.278226 -23.901908)
			(xy 333.235564 -23.920153) (xy 333.147271 -23.948697) (xy 333.056486 -23.96789) (xy 332.964196 -23.977523)
			(xy 332.9178 -23.978108) (xy 332.871404 -23.977525) (xy 332.779116 -23.96788) (xy 332.688332 -23.948684)
			(xy 332.600039 -23.920146) (xy 332.557374 -23.901908) (xy 332.547432 -23.898102) (xy 332.526168 -23.898102)
			(xy 332.516226 -23.901908) (xy 332.473623 -23.92013) (xy 332.385456 -23.948648) (xy 332.2948 -23.96784)
			(xy 332.20264 -23.9775) (xy 332.156308 -23.978108) (xy 332.1558 -23.978108) (xy 332.114698 -23.977633)
			(xy 332.032843 -23.970048) (xy 331.952038 -23.954943) (xy 331.872971 -23.932447) (xy 331.796317 -23.902751)
			(xy 331.72273 -23.866109) (xy 331.652838 -23.822834) (xy 331.587237 -23.773294) (xy 331.526487 -23.717913)
			(xy 331.471106 -23.657163) (xy 331.421566 -23.591562) (xy 331.378291 -23.52167) (xy 331.341649 -23.448083)
			(xy 331.311953 -23.371429) (xy 331.289457 -23.292362) (xy 331.274352 -23.211557) (xy 331.266767 -23.129702)
			(xy 331.266292 -23.0886) (xy 325.12 -23.0886) (xy 325.12 -28.566561) (xy 334.478626 -28.566561) (xy 334.478626 -28.481839)
			(xy 334.486679 -28.397502) (xy 334.502713 -28.314312) (xy 334.526581 -28.233022) (xy 334.558069 -28.15437)
			(xy 334.596891 -28.079067) (xy 334.642694 -28.007795) (xy 334.695065 -27.941199) (xy 334.75353 -27.879884)
			(xy 334.817558 -27.824403) (xy 334.88657 -27.77526) (xy 334.95994 -27.7329) (xy 335.037005 -27.697705)
			(xy 335.117067 -27.669996) (xy 335.1994 -27.650022) (xy 335.283259 -27.637965) (xy 335.367884 -27.633934)
			(xy 335.452509 -27.637965) (xy 335.536368 -27.650022) (xy 335.618701 -27.669996) (xy 335.698763 -27.697705)
			(xy 335.775828 -27.7329) (xy 335.849198 -27.77526) (xy 335.91821 -27.824403) (xy 335.982238 -27.879884)
			(xy 336.040703 -27.941199) (xy 336.093074 -28.007795) (xy 336.138877 -28.079067) (xy 336.177699 -28.15437)
			(xy 336.209187 -28.233022) (xy 336.233055 -28.314312) (xy 336.249089 -28.397502) (xy 336.257142 -28.481839)
			(xy 336.257646 -28.5242) (xy 336.257142 -28.566561) (xy 336.249089 -28.650898) (xy 336.233055 -28.734088)
			(xy 336.209187 -28.815378) (xy 336.177699 -28.89403) (xy 336.138877 -28.969333) (xy 336.093074 -29.040605)
			(xy 336.040703 -29.107201) (xy 335.982238 -29.168516) (xy 335.91821 -29.223997) (xy 335.849198 -29.27314)
			(xy 335.775828 -29.3155) (xy 335.698763 -29.350695) (xy 335.618701 -29.378404) (xy 335.536368 -29.398378)
			(xy 335.452509 -29.410435) (xy 335.367884 -29.414467) (xy 335.283259 -29.410435) (xy 335.1994 -29.398378)
			(xy 335.117067 -29.378404) (xy 335.037005 -29.350695) (xy 334.95994 -29.3155) (xy 334.88657 -29.27314)
			(xy 334.817558 -29.223997) (xy 334.75353 -29.168516) (xy 334.695065 -29.107201) (xy 334.642694 -29.040605)
			(xy 334.596891 -28.969333) (xy 334.558069 -28.89403) (xy 334.526581 -28.815378) (xy 334.502713 -28.734088)
			(xy 334.486679 -28.650898) (xy 334.478626 -28.566561) (xy 325.12 -28.566561) (xy 325.12 -34.3662)
			(xy 331.266292 -34.3662) (xy 331.266292 -34.365692) (xy 331.266898 -34.31936) (xy 331.276569 -34.227202)
			(xy 331.295765 -34.136548) (xy 331.324277 -34.048379) (xy 331.342492 -34.005774) (xy 331.346298 -33.995832)
			(xy 331.346298 -33.974568) (xy 331.342492 -33.964626) (xy 331.324247 -33.921964) (xy 331.295703 -33.833671)
			(xy 331.27651 -33.742886) (xy 331.266877 -33.650596) (xy 331.266292 -33.6042) (xy 331.266875 -33.557804)
			(xy 331.27652 -33.465516) (xy 331.295716 -33.374732) (xy 331.324254 -33.286439) (xy 331.342492 -33.243774)
			(xy 331.346298 -33.233832) (xy 331.346298 -33.212568) (xy 331.342492 -33.202626) (xy 331.324247 -33.159964)
			(xy 331.295703 -33.071671) (xy 331.27651 -32.980886) (xy 331.266877 -32.888596) (xy 331.266292 -32.8422)
			(xy 331.266875 -32.795804) (xy 331.27652 -32.703516) (xy 331.295716 -32.612732) (xy 331.324254 -32.524439)
			(xy 331.342492 -32.481774) (xy 331.346298 -32.471832) (xy 331.346298 -32.450568) (xy 331.342492 -32.440626)
			(xy 331.324247 -32.397964) (xy 331.295703 -32.309671) (xy 331.27651 -32.218886) (xy 331.266877 -32.126596)
			(xy 331.266292 -32.0802) (xy 331.266875 -32.033804) (xy 331.27652 -31.941516) (xy 331.295716 -31.850732)
			(xy 331.324254 -31.762439) (xy 331.342492 -31.719774) (xy 331.346298 -31.709832) (xy 331.346298 -31.688568)
			(xy 331.342492 -31.678626) (xy 331.32427 -31.636023) (xy 331.295752 -31.547856) (xy 331.27656 -31.4572)
			(xy 331.2669 -31.36504) (xy 331.266292 -31.318708) (xy 331.266292 -31.3182) (xy 331.266767 -31.277098)
			(xy 331.274352 -31.195243) (xy 331.289457 -31.114438) (xy 331.311953 -31.035371) (xy 331.341649 -30.958717)
			(xy 331.378291 -30.88513) (xy 331.421566 -30.815238) (xy 331.471106 -30.749637) (xy 331.526487 -30.688887)
			(xy 331.587237 -30.633506) (xy 331.652838 -30.583966) (xy 331.72273 -30.540691) (xy 331.796317 -30.504049)
			(xy 331.872971 -30.474353) (xy 331.952038 -30.451857) (xy 332.032843 -30.436752) (xy 332.114698 -30.429167)
			(xy 332.1558 -30.428692) (xy 332.156308 -30.428692) (xy 332.20264 -30.429298) (xy 332.294798 -30.438969)
			(xy 332.385452 -30.458165) (xy 332.473621 -30.486677) (xy 332.516226 -30.504892) (xy 332.526168 -30.508698)
			(xy 332.547432 -30.508698) (xy 332.557374 -30.504892) (xy 332.600036 -30.486647) (xy 332.688329 -30.458103)
			(xy 332.779114 -30.43891) (xy 332.871404 -30.429277) (xy 332.9178 -30.428692) (xy 332.964196 -30.429275)
			(xy 333.056484 -30.43892) (xy 333.147268 -30.458116) (xy 333.235561 -30.486654) (xy 333.278226 -30.504892)
			(xy 333.288168 -30.508698) (xy 333.309432 -30.508698) (xy 333.319374 -30.504892) (xy 333.362036 -30.486647)
			(xy 333.450329 -30.458103) (xy 333.541114 -30.43891) (xy 333.633404 -30.429277) (xy 333.6798 -30.428692)
			(xy 333.726196 -30.429275) (xy 333.818484 -30.43892) (xy 333.909268 -30.458116) (xy 333.997561 -30.486654)
			(xy 334.040226 -30.504892) (xy 334.050168 -30.508698) (xy 334.071432 -30.508698) (xy 334.081374 -30.504892)
			(xy 334.124036 -30.486647) (xy 334.212329 -30.458103) (xy 334.303114 -30.43891) (xy 334.395404 -30.429277)
			(xy 334.4418 -30.428692) (xy 334.488196 -30.429275) (xy 334.580484 -30.43892) (xy 334.671268 -30.458116)
			(xy 334.759561 -30.486654) (xy 334.802226 -30.504892) (xy 334.812168 -30.508698) (xy 334.833432 -30.508698)
			(xy 334.843374 -30.504892) (xy 334.885977 -30.48667) (xy 334.974144 -30.458152) (xy 335.0648 -30.43896)
			(xy 335.15696 -30.4293) (xy 335.203292 -30.428692) (xy 335.2038 -30.428692) (xy 335.244902 -30.429167)
			(xy 335.326757 -30.436752) (xy 335.407562 -30.451857) (xy 335.486629 -30.474353) (xy 335.563283 -30.504049)
			(xy 335.63687 -30.540691) (xy 335.706762 -30.583966) (xy 335.772363 -30.633506) (xy 335.833113 -30.688887)
			(xy 335.888494 -30.749637) (xy 335.938034 -30.815238) (xy 335.981309 -30.88513) (xy 336.017951 -30.958717)
			(xy 336.047647 -31.035371) (xy 336.070143 -31.114438) (xy 336.085248 -31.195243) (xy 336.092833 -31.277098)
			(xy 336.093308 -31.3182) (xy 336.093308 -31.318708) (xy 336.092702 -31.36504) (xy 336.083031 -31.457198)
			(xy 336.063835 -31.547852) (xy 336.035323 -31.636021) (xy 336.017108 -31.678626) (xy 336.013302 -31.688568)
			(xy 336.013302 -31.709832) (xy 336.017108 -31.719774) (xy 336.035353 -31.762436) (xy 336.063897 -31.850729)
			(xy 336.08309 -31.941514) (xy 336.092723 -32.033804) (xy 336.093308 -32.0802) (xy 336.092725 -32.126596)
			(xy 336.08308 -32.218884) (xy 336.063884 -32.309668) (xy 336.035346 -32.397961) (xy 336.017108 -32.440626)
			(xy 336.013302 -32.450568) (xy 336.013302 -32.471832) (xy 336.017108 -32.481774) (xy 336.035353 -32.524436)
			(xy 336.063897 -32.612729) (xy 336.08309 -32.703514) (xy 336.092723 -32.795804) (xy 336.093308 -32.8422)
			(xy 336.092725 -32.888596) (xy 336.08308 -32.980884) (xy 336.063884 -33.071668) (xy 336.035346 -33.159961)
			(xy 336.017108 -33.202626) (xy 336.013302 -33.212568) (xy 336.013302 -33.233832) (xy 336.017108 -33.243774)
			(xy 336.035353 -33.286436) (xy 336.063897 -33.374729) (xy 336.08309 -33.465514) (xy 336.092723 -33.557804)
			(xy 336.093308 -33.6042) (xy 336.092725 -33.650596) (xy 336.08308 -33.742884) (xy 336.063884 -33.833668)
			(xy 336.035346 -33.921961) (xy 336.017108 -33.964626) (xy 336.013302 -33.974568) (xy 336.013302 -33.995832)
			(xy 336.017108 -34.005774) (xy 336.03533 -34.048377) (xy 336.063848 -34.136544) (xy 336.08304 -34.2272)
			(xy 336.0927 -34.31936) (xy 336.093308 -34.365692) (xy 336.093308 -34.3662) (xy 336.092833 -34.407302)
			(xy 336.085248 -34.489157) (xy 336.070143 -34.569962) (xy 336.047647 -34.649029) (xy 336.017951 -34.725683)
			(xy 335.981309 -34.79927) (xy 335.938034 -34.869162) (xy 335.888494 -34.934763) (xy 335.833113 -34.995513)
			(xy 335.772363 -35.050894) (xy 335.706762 -35.100434) (xy 335.63687 -35.143709) (xy 335.563283 -35.180351)
			(xy 335.486629 -35.210047) (xy 335.407562 -35.232543) (xy 335.326757 -35.247648) (xy 335.244902 -35.255233)
			(xy 335.2038 -35.255708) (xy 335.203292 -35.255708) (xy 335.15696 -35.255102) (xy 335.064802 -35.245431)
			(xy 334.974148 -35.226235) (xy 334.885979 -35.197723) (xy 334.843374 -35.179508) (xy 334.833432 -35.175702)
			(xy 334.812168 -35.175702) (xy 334.802226 -35.179508) (xy 334.759564 -35.197753) (xy 334.671271 -35.226297)
			(xy 334.580486 -35.24549) (xy 334.488196 -35.255123) (xy 334.4418 -35.255708) (xy 334.395404 -35.255125)
			(xy 334.303116 -35.24548) (xy 334.212332 -35.226284) (xy 334.124039 -35.197746) (xy 334.081374 -35.179508)
			(xy 334.071432 -35.175702) (xy 334.050168 -35.175702) (xy 334.040226 -35.179508) (xy 333.997564 -35.197753)
			(xy 333.909271 -35.226297) (xy 333.818486 -35.24549) (xy 333.726196 -35.255123) (xy 333.6798 -35.255708)
			(xy 333.633404 -35.255125) (xy 333.541116 -35.24548) (xy 333.450332 -35.226284) (xy 333.362039 -35.197746)
			(xy 333.319374 -35.179508) (xy 333.309432 -35.175702) (xy 333.288168 -35.175702) (xy 333.278226 -35.179508)
			(xy 333.235564 -35.197753) (xy 333.147271 -35.226297) (xy 333.056486 -35.24549) (xy 332.964196 -35.255123)
			(xy 332.9178 -35.255708) (xy 332.871404 -35.255125) (xy 332.779116 -35.24548) (xy 332.688332 -35.226284)
			(xy 332.600039 -35.197746) (xy 332.557374 -35.179508) (xy 332.547432 -35.175702) (xy 332.526168 -35.175702)
			(xy 332.516226 -35.179508) (xy 332.473623 -35.19773) (xy 332.385456 -35.226248) (xy 332.2948 -35.24544)
			(xy 332.20264 -35.2551) (xy 332.156308 -35.255708) (xy 332.1558 -35.255708) (xy 332.114698 -35.255233)
			(xy 332.032843 -35.247648) (xy 331.952038 -35.232543) (xy 331.872971 -35.210047) (xy 331.796317 -35.180351)
			(xy 331.72273 -35.143709) (xy 331.652838 -35.100434) (xy 331.587237 -35.050894) (xy 331.526487 -34.995513)
			(xy 331.471106 -34.934763) (xy 331.421566 -34.869162) (xy 331.378291 -34.79927) (xy 331.341649 -34.725683)
			(xy 331.311953 -34.649029) (xy 331.289457 -34.569962) (xy 331.274352 -34.489157) (xy 331.266767 -34.407302)
			(xy 331.266292 -34.3662) (xy 325.12 -34.3662) (xy 325.12 -37.289429) (xy 337.982302 -37.289429) (xy 337.982302 -37.204707)
			(xy 337.990355 -37.12037) (xy 338.006389 -37.03718) (xy 338.030257 -36.95589) (xy 338.061745 -36.877238)
			(xy 338.100567 -36.801935) (xy 338.14637 -36.730663) (xy 338.198741 -36.664067) (xy 338.257206 -36.602752)
			(xy 338.321234 -36.547271) (xy 338.390246 -36.498128) (xy 338.463616 -36.455768) (xy 338.540681 -36.420573)
			(xy 338.620743 -36.392864) (xy 338.703076 -36.37289) (xy 338.786935 -36.360833) (xy 338.87156 -36.356802)
			(xy 338.956185 -36.360833) (xy 339.040044 -36.37289) (xy 339.122377 -36.392864) (xy 339.202439 -36.420573)
			(xy 339.279504 -36.455768) (xy 339.352874 -36.498128) (xy 339.421886 -36.547271) (xy 339.485914 -36.602752)
			(xy 339.544379 -36.664067) (xy 339.59675 -36.730663) (xy 339.642553 -36.801935) (xy 339.681375 -36.877238)
			(xy 339.712863 -36.95589) (xy 339.736731 -37.03718) (xy 339.752765 -37.12037) (xy 339.760818 -37.204707)
			(xy 339.761322 -37.247068) (xy 339.760818 -37.289429) (xy 339.752765 -37.373766) (xy 339.736731 -37.456956)
			(xy 339.712863 -37.538246) (xy 339.681375 -37.616898) (xy 339.642553 -37.692201) (xy 339.59675 -37.763473)
			(xy 339.544379 -37.830069) (xy 339.485914 -37.891384) (xy 339.421886 -37.946865) (xy 339.352874 -37.996008)
			(xy 339.279504 -38.038368) (xy 339.202439 -38.073563) (xy 339.122377 -38.101272) (xy 339.040044 -38.121246)
			(xy 338.956185 -38.133303) (xy 338.87156 -38.137335) (xy 338.786935 -38.133303) (xy 338.703076 -38.121246)
			(xy 338.620743 -38.101272) (xy 338.540681 -38.073563) (xy 338.463616 -38.038368) (xy 338.390246 -37.996008)
			(xy 338.321234 -37.946865) (xy 338.257206 -37.891384) (xy 338.198741 -37.830069) (xy 338.14637 -37.763473)
			(xy 338.100567 -37.692201) (xy 338.061745 -37.616898) (xy 338.030257 -37.538246) (xy 338.006389 -37.456956)
			(xy 337.990355 -37.373766) (xy 337.982302 -37.289429) (xy 325.12 -37.289429) (xy 325.12 -39.787831)
			(xy 334.477997 -39.787831) (xy 334.483261 -39.704146) (xy 334.496377 -39.621328) (xy 334.517229 -39.540112)
			(xy 334.545631 -39.461218) (xy 334.581332 -39.385348) (xy 334.624014 -39.313173) (xy 334.673299 -39.245336)
			(xy 334.728749 -39.182438) (xy 334.789873 -39.125038) (xy 334.856127 -39.073645) (xy 334.926923 -39.028714)
			(xy 335.001634 -38.990646) (xy 335.079595 -38.959777) (xy 335.160116 -38.936382) (xy 335.242481 -38.920669)
			(xy 335.325959 -38.912776) (xy 335.367884 -38.912292) (xy 335.368392 -38.912292) (xy 335.404819 -38.912666)
			(xy 335.477428 -38.918641) (xy 335.513426 -38.92423) (xy 335.528472 -38.926165) (xy 335.558521 -38.922119)
			(xy 335.586063 -38.909441) (xy 335.608678 -38.889246) (xy 335.624379 -38.863308) (xy 335.631785 -38.833906)
			(xy 335.630246 -38.803626) (xy 335.619897 -38.775127) (xy 335.611216 -38.762686) (xy 335.586864 -38.729613)
			(xy 335.543671 -38.659752) (xy 335.507099 -38.586206) (xy 335.477461 -38.509604) (xy 335.455009 -38.430596)
			(xy 335.439934 -38.349855) (xy 335.432365 -38.268068) (xy 335.431892 -38.227) (xy 335.432376 -38.185075)
			(xy 335.440267 -38.101596) (xy 335.455979 -38.019231) (xy 335.479372 -37.938709) (xy 335.51024 -37.860747)
			(xy 335.548307 -37.786036) (xy 335.593237 -37.715238) (xy 335.644629 -37.648983) (xy 335.702029 -37.587859)
			(xy 335.764926 -37.532407) (xy 335.832763 -37.483121) (xy 335.904937 -37.440438) (xy 335.980807 -37.404736)
			(xy 336.0597 -37.376332) (xy 336.140917 -37.355479) (xy 336.223735 -37.342362) (xy 336.30742 -37.337097)
			(xy 336.39123 -37.339731) (xy 336.474419 -37.35024) (xy 336.55625 -37.368532) (xy 336.635997 -37.394443)
			(xy 336.712951 -37.427744) (xy 336.78643 -37.46814) (xy 336.855782 -37.515271) (xy 336.92039 -37.568719)
			(xy 336.979681 -37.62801) (xy 337.033129 -37.692618) (xy 337.08026 -37.76197) (xy 337.120656 -37.835449)
			(xy 337.153957 -37.912403) (xy 337.179868 -37.99215) (xy 337.19816 -38.073981) (xy 337.208669 -38.15717)
			(xy 337.211303 -38.24098) (xy 337.206038 -38.324665) (xy 337.192921 -38.407483) (xy 337.172068 -38.4887)
			(xy 337.143664 -38.567593) (xy 337.107962 -38.643463) (xy 337.065279 -38.715637) (xy 337.015993 -38.783474)
			(xy 336.960541 -38.846371) (xy 336.899417 -38.903771) (xy 336.833162 -38.955163) (xy 336.762364 -39.000093)
			(xy 336.687653 -39.03816) (xy 336.609691 -39.069028) (xy 336.529169 -39.092421) (xy 336.446804 -39.108133)
			(xy 336.363325 -39.116024) (xy 336.3214 -39.116508) (xy 336.320892 -39.116508) (xy 336.284465 -39.116136)
			(xy 336.211856 -39.110159) (xy 336.175858 -39.10457) (xy 336.160814 -39.102622) (xy 336.130765 -39.106672)
			(xy 336.103223 -39.119352) (xy 336.080609 -39.139549) (xy 336.064909 -39.165489) (xy 336.057502 -39.194891)
			(xy 336.05904 -39.225172) (xy 336.069388 -39.253672) (xy 336.078068 -39.266114) (xy 336.102418 -39.299188)
			(xy 336.145612 -39.36905) (xy 336.182184 -39.442594) (xy 336.211822 -39.519197) (xy 336.234274 -39.598205)
			(xy 336.249349 -39.678945) (xy 336.256919 -39.760732) (xy 336.257392 -39.8018) (xy 336.256924 -39.843725)
			(xy 336.249033 -39.927203) (xy 336.233322 -40.009569) (xy 336.209928 -40.090089) (xy 336.179061 -40.168052)
			(xy 336.140994 -40.242763) (xy 336.096065 -40.31356) (xy 336.044672 -40.379815) (xy 335.987273 -40.440939)
			(xy 335.924376 -40.496391) (xy 335.85654 -40.545677) (xy 335.784367 -40.588361) (xy 335.708497 -40.624063)
			(xy 335.629604 -40.652466) (xy 335.548388 -40.67332) (xy 335.46557 -40.686437) (xy 335.381885 -40.691703)
			(xy 335.298076 -40.689069) (xy 335.214887 -40.678561) (xy 335.133056 -40.66027) (xy 335.053309 -40.634359)
			(xy 334.976355 -40.601059) (xy 334.902876 -40.560664) (xy 334.833525 -40.513534) (xy 334.768916 -40.460086)
			(xy 334.709625 -40.400796) (xy 334.656176 -40.336188) (xy 334.609044 -40.266838) (xy 334.568648 -40.19336)
			(xy 334.535346 -40.116406) (xy 334.509434 -40.03666) (xy 334.491142 -39.954829) (xy 334.480632 -39.87164)
			(xy 334.477997 -39.787831) (xy 325.12 -39.787831) (xy 325.12 -45.6438) (xy 331.266292 -45.6438) (xy 331.266292 -45.643292)
			(xy 331.266898 -45.59696) (xy 331.276569 -45.504802) (xy 331.295765 -45.414148) (xy 331.324277 -45.325979)
			(xy 331.342492 -45.283374) (xy 331.346298 -45.273432) (xy 331.346298 -45.252168) (xy 331.342492 -45.242226)
			(xy 331.324247 -45.199564) (xy 331.295703 -45.111271) (xy 331.27651 -45.020486) (xy 331.266877 -44.928196)
			(xy 331.266292 -44.8818) (xy 331.266875 -44.835404) (xy 331.27652 -44.743116) (xy 331.295716 -44.652332)
			(xy 331.324254 -44.564039) (xy 331.342492 -44.521374) (xy 331.346298 -44.511432) (xy 331.346298 -44.490168)
			(xy 331.342492 -44.480226) (xy 331.324247 -44.437564) (xy 331.295703 -44.349271) (xy 331.27651 -44.258486)
			(xy 331.266877 -44.166196) (xy 331.266292 -44.1198) (xy 331.266875 -44.073404) (xy 331.27652 -43.981116)
			(xy 331.295716 -43.890332) (xy 331.324254 -43.802039) (xy 331.342492 -43.759374) (xy 331.346298 -43.749432)
			(xy 331.346298 -43.728168) (xy 331.342492 -43.718226) (xy 331.324247 -43.675564) (xy 331.295703 -43.587271)
			(xy 331.27651 -43.496486) (xy 331.266877 -43.404196) (xy 331.266292 -43.3578) (xy 331.266875 -43.311404)
			(xy 331.27652 -43.219116) (xy 331.295716 -43.128332) (xy 331.324254 -43.040039) (xy 331.342492 -42.997374)
			(xy 331.346298 -42.987432) (xy 331.346298 -42.966168) (xy 331.342492 -42.956226) (xy 331.32427 -42.913623)
			(xy 331.295752 -42.825456) (xy 331.27656 -42.7348) (xy 331.2669 -42.64264) (xy 331.266292 -42.596308)
			(xy 331.266292 -42.5958) (xy 331.266767 -42.554698) (xy 331.274352 -42.472843) (xy 331.289457 -42.392038)
			(xy 331.311953 -42.312971) (xy 331.341649 -42.236317) (xy 331.378291 -42.16273) (xy 331.421566 -42.092838)
			(xy 331.471106 -42.027237) (xy 331.526487 -41.966487) (xy 331.587237 -41.911106) (xy 331.652838 -41.861566)
			(xy 331.72273 -41.818291) (xy 331.796317 -41.781649) (xy 331.872971 -41.751953) (xy 331.952038 -41.729457)
			(xy 332.032843 -41.714352) (xy 332.114698 -41.706767) (xy 332.1558 -41.706292) (xy 332.156308 -41.706292)
			(xy 332.20264 -41.706898) (xy 332.294798 -41.716569) (xy 332.385452 -41.735765) (xy 332.473621 -41.764277)
			(xy 332.516226 -41.782492) (xy 332.526168 -41.786298) (xy 332.547432 -41.786298) (xy 332.557374 -41.782492)
			(xy 332.600036 -41.764247) (xy 332.688329 -41.735703) (xy 332.779114 -41.71651) (xy 332.871404 -41.706877)
			(xy 332.9178 -41.706292) (xy 332.964196 -41.706875) (xy 333.056484 -41.71652) (xy 333.147268 -41.735716)
			(xy 333.235561 -41.764254) (xy 333.278226 -41.782492) (xy 333.288168 -41.786298) (xy 333.309432 -41.786298)
			(xy 333.319374 -41.782492) (xy 333.362036 -41.764247) (xy 333.450329 -41.735703) (xy 333.541114 -41.71651)
			(xy 333.633404 -41.706877) (xy 333.6798 -41.706292) (xy 333.726196 -41.706875) (xy 333.818484 -41.71652)
			(xy 333.909268 -41.735716) (xy 333.997561 -41.764254) (xy 334.040226 -41.782492) (xy 334.050168 -41.786298)
			(xy 334.071432 -41.786298) (xy 334.081374 -41.782492) (xy 334.124036 -41.764247) (xy 334.212329 -41.735703)
			(xy 334.303114 -41.71651) (xy 334.395404 -41.706877) (xy 334.4418 -41.706292) (xy 334.488196 -41.706875)
			(xy 334.580484 -41.71652) (xy 334.671268 -41.735716) (xy 334.759561 -41.764254) (xy 334.802226 -41.782492)
			(xy 334.812168 -41.786298) (xy 334.833432 -41.786298) (xy 334.843374 -41.782492) (xy 334.885977 -41.76427)
			(xy 334.974144 -41.735752) (xy 335.0648 -41.71656) (xy 335.15696 -41.7069) (xy 335.203292 -41.706292)
			(xy 335.2038 -41.706292) (xy 335.244902 -41.706767) (xy 335.326757 -41.714352) (xy 335.407562 -41.729457)
			(xy 335.486629 -41.751953) (xy 335.563283 -41.781649) (xy 335.63687 -41.818291) (xy 335.706762 -41.861566)
			(xy 335.772363 -41.911106) (xy 335.833113 -41.966487) (xy 335.888494 -42.027237) (xy 335.938034 -42.092838)
			(xy 335.981309 -42.16273) (xy 336.017951 -42.236317) (xy 336.047647 -42.312971) (xy 336.070143 -42.392038)
			(xy 336.085248 -42.472843) (xy 336.092833 -42.554698) (xy 336.093308 -42.5958) (xy 336.093308 -42.596308)
			(xy 336.092702 -42.64264) (xy 336.083031 -42.734798) (xy 336.063835 -42.825452) (xy 336.035323 -42.913621)
			(xy 336.017108 -42.956226) (xy 336.013302 -42.966168) (xy 336.013302 -42.987432) (xy 336.017108 -42.997374)
			(xy 336.035353 -43.040036) (xy 336.063897 -43.128329) (xy 336.08309 -43.219114) (xy 336.092723 -43.311404)
			(xy 336.093308 -43.3578) (xy 336.092725 -43.404196) (xy 336.08308 -43.496484) (xy 336.063884 -43.587268)
			(xy 336.035346 -43.675561) (xy 336.017108 -43.718226) (xy 336.013302 -43.728168) (xy 336.013302 -43.749432)
			(xy 336.017108 -43.759374) (xy 336.035353 -43.802036) (xy 336.063897 -43.890329) (xy 336.08309 -43.981114)
			(xy 336.092723 -44.073404) (xy 336.093308 -44.1198) (xy 336.092725 -44.166196) (xy 336.08308 -44.258484)
			(xy 336.063884 -44.349268) (xy 336.035346 -44.437561) (xy 336.017108 -44.480226) (xy 336.013302 -44.490168)
			(xy 336.013302 -44.511432) (xy 336.017108 -44.521374) (xy 336.03533 -44.563977) (xy 336.063848 -44.652144)
			(xy 336.08304 -44.7428) (xy 336.0927 -44.83496) (xy 336.093308 -44.881292) (xy 336.093308 -44.8818)
			(xy 336.092833 -44.922902) (xy 336.085248 -45.004757) (xy 336.070143 -45.085562) (xy 336.047647 -45.164629)
			(xy 336.017951 -45.241283) (xy 335.981309 -45.31487) (xy 335.938034 -45.384762) (xy 335.888494 -45.450363)
			(xy 335.833113 -45.511113) (xy 335.772363 -45.566494) (xy 335.706762 -45.616034) (xy 335.63687 -45.659309)
			(xy 335.563283 -45.695951) (xy 335.486629 -45.725647) (xy 335.407562 -45.748143) (xy 335.326757 -45.763248)
			(xy 335.244902 -45.770833) (xy 335.2038 -45.771308) (xy 335.203292 -45.771308) (xy 335.15696 -45.770702)
			(xy 335.064802 -45.761031) (xy 334.974148 -45.741835) (xy 334.885979 -45.713323) (xy 334.843374 -45.695108)
			(xy 334.833432 -45.691302) (xy 334.812168 -45.691302) (xy 334.802226 -45.695108) (xy 334.769307 -45.709337)
			(xy 334.701622 -45.733057) (xy 334.632242 -45.751237) (xy 334.596994 -45.757846) (xy 334.58687 -45.760144)
			(xy 334.569549 -45.771549) (xy 334.558144 -45.78887) (xy 334.555846 -45.798994) (xy 334.548139 -45.839659)
			(xy 334.526175 -45.919465) (xy 334.496893 -45.996885) (xy 334.460547 -46.071251) (xy 334.417451 -46.14192)
			(xy 334.367977 -46.20828) (xy 334.312554 -46.269759) (xy 334.251659 -46.325823) (xy 334.185821 -46.375989)
			(xy 334.115608 -46.419824) (xy 334.041627 -46.456947) (xy 333.964517 -46.487038) (xy 333.884946 -46.509837)
			(xy 333.803601 -46.525147) (xy 333.721186 -46.532835) (xy 333.6798 -46.533308) (xy 333.679292 -46.533308)
			(xy 333.63296 -46.532702) (xy 333.540802 -46.523031) (xy 333.450148 -46.503835) (xy 333.361979 -46.475323)
			(xy 333.319374 -46.457108) (xy 333.309432 -46.453302) (xy 333.288168 -46.453302) (xy 333.278226 -46.457108)
			(xy 333.235564 -46.475353) (xy 333.147271 -46.503897) (xy 333.056486 -46.52309) (xy 332.964196 -46.532723)
			(xy 332.9178 -46.533308) (xy 332.871404 -46.532725) (xy 332.779116 -46.52308) (xy 332.688332 -46.503884)
			(xy 332.600039 -46.475346) (xy 332.557374 -46.457108) (xy 332.547432 -46.453302) (xy 332.526168 -46.453302)
			(xy 332.516226 -46.457108) (xy 332.473623 -46.47533) (xy 332.385456 -46.503848) (xy 332.2948 -46.52304)
			(xy 332.20264 -46.5327) (xy 332.156308 -46.533308) (xy 332.1558 -46.533308) (xy 332.114698 -46.532833)
			(xy 332.032843 -46.525248) (xy 331.952038 -46.510143) (xy 331.872971 -46.487647) (xy 331.796317 -46.457951)
			(xy 331.72273 -46.421309) (xy 331.652838 -46.378034) (xy 331.587237 -46.328494) (xy 331.526487 -46.273113)
			(xy 331.471106 -46.212363) (xy 331.421566 -46.146762) (xy 331.378291 -46.07687) (xy 331.341649 -46.003283)
			(xy 331.311953 -45.926629) (xy 331.289457 -45.847562) (xy 331.274352 -45.766757) (xy 331.266767 -45.684902)
			(xy 331.266292 -45.6438) (xy 325.12 -45.6438) (xy 325.12 -48.465937) (xy 337.609176 -48.465937) (xy 337.609176 -48.381215)
			(xy 337.617229 -48.296878) (xy 337.633263 -48.213688) (xy 337.657131 -48.132398) (xy 337.688619 -48.053746)
			(xy 337.727441 -47.978443) (xy 337.773244 -47.907171) (xy 337.825615 -47.840575) (xy 337.88408 -47.77926)
			(xy 337.948108 -47.723779) (xy 338.01712 -47.674636) (xy 338.09049 -47.632276) (xy 338.167555 -47.597081)
			(xy 338.247617 -47.569372) (xy 338.32995 -47.549398) (xy 338.413809 -47.537341) (xy 338.498434 -47.53331)
			(xy 338.583059 -47.537341) (xy 338.666918 -47.549398) (xy 338.749251 -47.569372) (xy 338.829313 -47.597081)
			(xy 338.906378 -47.632276) (xy 338.979748 -47.674636) (xy 339.04876 -47.723779) (xy 339.112788 -47.77926)
			(xy 339.171253 -47.840575) (xy 339.223624 -47.907171) (xy 339.269427 -47.978443) (xy 339.308249 -48.053746)
			(xy 339.339737 -48.132398) (xy 339.363605 -48.213688) (xy 339.379639 -48.296878) (xy 339.387692 -48.381215)
			(xy 339.388196 -48.423576) (xy 339.387692 -48.465937) (xy 339.379639 -48.550274) (xy 339.363605 -48.633464)
			(xy 339.339737 -48.714754) (xy 339.308249 -48.793406) (xy 339.269427 -48.868709) (xy 339.223624 -48.939981)
			(xy 339.171253 -49.006577) (xy 339.112788 -49.067892) (xy 339.04876 -49.123373) (xy 338.979748 -49.172516)
			(xy 338.906378 -49.214876) (xy 338.829313 -49.250071) (xy 338.749251 -49.27778) (xy 338.666918 -49.297754)
			(xy 338.583059 -49.309811) (xy 338.498434 -49.313843) (xy 338.413809 -49.309811) (xy 338.32995 -49.297754)
			(xy 338.247617 -49.27778) (xy 338.167555 -49.250071) (xy 338.09049 -49.214876) (xy 338.01712 -49.172516)
			(xy 337.948108 -49.123373) (xy 337.88408 -49.067892) (xy 337.825615 -49.006577) (xy 337.773244 -48.939981)
			(xy 337.727441 -48.868709) (xy 337.688619 -48.793406) (xy 337.657131 -48.714754) (xy 337.633263 -48.633464)
			(xy 337.617229 -48.550274) (xy 337.609176 -48.465937) (xy 325.12 -48.465937) (xy 325.12 -51.065431)
			(xy 334.477997 -51.065431) (xy 334.483261 -50.981746) (xy 334.496377 -50.898928) (xy 334.517229 -50.817712)
			(xy 334.545631 -50.738818) (xy 334.581332 -50.662948) (xy 334.624014 -50.590773) (xy 334.673299 -50.522936)
			(xy 334.728749 -50.460038) (xy 334.789873 -50.402638) (xy 334.856127 -50.351245) (xy 334.926923 -50.306314)
			(xy 335.001634 -50.268246) (xy 335.079595 -50.237377) (xy 335.160116 -50.213982) (xy 335.242481 -50.198269)
			(xy 335.325959 -50.190376) (xy 335.367884 -50.189892) (xy 335.368392 -50.189892) (xy 335.404819 -50.190266)
			(xy 335.477428 -50.196241) (xy 335.513426 -50.20183) (xy 335.528472 -50.203765) (xy 335.558521 -50.199719)
			(xy 335.586063 -50.187041) (xy 335.608678 -50.166846) (xy 335.624379 -50.140908) (xy 335.631785 -50.111506)
			(xy 335.630246 -50.081226) (xy 335.619897 -50.052727) (xy 335.611216 -50.040286) (xy 335.586864 -50.007213)
			(xy 335.543671 -49.937352) (xy 335.507099 -49.863806) (xy 335.477461 -49.787204) (xy 335.455009 -49.708196)
			(xy 335.439934 -49.627455) (xy 335.432365 -49.545668) (xy 335.431892 -49.5046) (xy 335.432376 -49.462675)
			(xy 335.440267 -49.379196) (xy 335.455979 -49.296831) (xy 335.479372 -49.216309) (xy 335.51024 -49.138347)
			(xy 335.548307 -49.063636) (xy 335.593237 -48.992838) (xy 335.644629 -48.926583) (xy 335.702029 -48.865459)
			(xy 335.764926 -48.810007) (xy 335.832763 -48.760721) (xy 335.904937 -48.718038) (xy 335.980807 -48.682336)
			(xy 336.0597 -48.653932) (xy 336.140917 -48.633079) (xy 336.223735 -48.619962) (xy 336.30742 -48.614697)
			(xy 336.39123 -48.617331) (xy 336.474419 -48.62784) (xy 336.55625 -48.646132) (xy 336.635997 -48.672043)
			(xy 336.712951 -48.705344) (xy 336.78643 -48.74574) (xy 336.855782 -48.792871) (xy 336.92039 -48.846319)
			(xy 336.979681 -48.90561) (xy 337.033129 -48.970218) (xy 337.08026 -49.03957) (xy 337.120656 -49.113049)
			(xy 337.153957 -49.190003) (xy 337.179868 -49.26975) (xy 337.19816 -49.351581) (xy 337.208669 -49.43477)
			(xy 337.211303 -49.51858) (xy 337.206038 -49.602265) (xy 337.192921 -49.685083) (xy 337.172068 -49.7663)
			(xy 337.143664 -49.845193) (xy 337.107962 -49.921063) (xy 337.065279 -49.993237) (xy 337.015993 -50.061074)
			(xy 336.960541 -50.123971) (xy 336.899417 -50.181371) (xy 336.833162 -50.232763) (xy 336.762364 -50.277693)
			(xy 336.687653 -50.31576) (xy 336.609691 -50.346628) (xy 336.529169 -50.370021) (xy 336.446804 -50.385733)
			(xy 336.363325 -50.393624) (xy 336.3214 -50.394108) (xy 336.320892 -50.394108) (xy 336.284465 -50.393736)
			(xy 336.211856 -50.387759) (xy 336.175858 -50.38217) (xy 336.160814 -50.380222) (xy 336.130765 -50.384272)
			(xy 336.103223 -50.396952) (xy 336.080609 -50.417149) (xy 336.064909 -50.443089) (xy 336.057502 -50.472491)
			(xy 336.05904 -50.502772) (xy 336.069388 -50.531272) (xy 336.078068 -50.543714) (xy 336.102418 -50.576788)
			(xy 336.145612 -50.64665) (xy 336.182184 -50.720194) (xy 336.211822 -50.796797) (xy 336.234274 -50.875805)
			(xy 336.242505 -50.919888) (xy 377.061232 -50.919888) (xy 377.065214 -50.829938) (xy 377.077131 -50.740691)
			(xy 377.096889 -50.652847) (xy 377.124333 -50.567093) (xy 377.159249 -50.4841) (xy 377.201363 -50.404518)
			(xy 377.250346 -50.328969) (xy 377.305814 -50.258045) (xy 377.367334 -50.1923) (xy 377.434423 -50.13225)
			(xy 377.506557 -50.078365) (xy 377.583171 -50.031065) (xy 377.663665 -49.990722) (xy 377.74741 -49.95765)
			(xy 377.833751 -49.93211) (xy 377.92201 -49.9143) (xy 378.011499 -49.90436) (xy 378.101515 -49.902369)
			(xy 378.191356 -49.90834) (xy 378.280317 -49.922229) (xy 378.367702 -49.943925) (xy 378.452828 -49.97326)
			(xy 378.535028 -50.010003) (xy 378.613659 -50.053867) (xy 378.688106 -50.104509) (xy 378.757786 -50.161533)
			(xy 378.822153 -50.224492) (xy 378.880704 -50.292893) (xy 378.932981 -50.366201) (xy 378.978574 -50.443843)
			(xy 379.017127 -50.52521) (xy 379.048338 -50.609666) (xy 379.071962 -50.69655) (xy 379.087815 -50.785182)
			(xy 379.095772 -50.874869) (xy 379.09627 -50.919888) (xy 396.619232 -50.919888) (xy 396.623214 -50.829938)
			(xy 396.635131 -50.740691) (xy 396.654889 -50.652847) (xy 396.682333 -50.567093) (xy 396.717249 -50.4841)
			(xy 396.759363 -50.404518) (xy 396.808346 -50.328969) (xy 396.863814 -50.258045) (xy 396.925334 -50.1923)
			(xy 396.992423 -50.13225) (xy 397.064557 -50.078365) (xy 397.141171 -50.031065) (xy 397.221665 -49.990722)
			(xy 397.30541 -49.95765) (xy 397.391751 -49.93211) (xy 397.48001 -49.9143) (xy 397.569499 -49.90436)
			(xy 397.659515 -49.902369) (xy 397.749356 -49.90834) (xy 397.838317 -49.922229) (xy 397.925702 -49.943925)
			(xy 398.010828 -49.97326) (xy 398.093028 -50.010003) (xy 398.171659 -50.053867) (xy 398.246106 -50.104509)
			(xy 398.315786 -50.161533) (xy 398.380153 -50.224492) (xy 398.438704 -50.292893) (xy 398.490981 -50.366201)
			(xy 398.536574 -50.443843) (xy 398.575127 -50.52521) (xy 398.606338 -50.609666) (xy 398.629962 -50.69655)
			(xy 398.645815 -50.785182) (xy 398.653772 -50.874869) (xy 398.65427 -50.919888) (xy 398.653772 -50.964907)
			(xy 398.645815 -51.054594) (xy 398.629962 -51.143226) (xy 398.606338 -51.23011) (xy 398.575127 -51.314566)
			(xy 398.536574 -51.395933) (xy 398.490981 -51.473575) (xy 398.438704 -51.546883) (xy 398.380153 -51.615284)
			(xy 398.315786 -51.678243) (xy 398.246106 -51.735267) (xy 398.171659 -51.785909) (xy 398.093028 -51.829773)
			(xy 398.010828 -51.866516) (xy 397.925702 -51.895851) (xy 397.838317 -51.917547) (xy 397.749356 -51.931436)
			(xy 397.659515 -51.937407) (xy 397.569499 -51.935416) (xy 397.48001 -51.925476) (xy 397.391751 -51.907666)
			(xy 397.30541 -51.882126) (xy 397.221665 -51.849054) (xy 397.141171 -51.808711) (xy 397.064557 -51.761411)
			(xy 396.992423 -51.707526) (xy 396.925334 -51.647476) (xy 396.863814 -51.581731) (xy 396.808346 -51.510807)
			(xy 396.759363 -51.435258) (xy 396.717249 -51.355676) (xy 396.682333 -51.272683) (xy 396.654889 -51.186929)
			(xy 396.635131 -51.099085) (xy 396.623214 -51.009838) (xy 396.619232 -50.919888) (xy 379.09627 -50.919888)
			(xy 379.095772 -50.964907) (xy 379.087815 -51.054594) (xy 379.071962 -51.143226) (xy 379.048338 -51.23011)
			(xy 379.017127 -51.314566) (xy 378.978574 -51.395933) (xy 378.932981 -51.473575) (xy 378.880704 -51.546883)
			(xy 378.822153 -51.615284) (xy 378.757786 -51.678243) (xy 378.688106 -51.735267) (xy 378.613659 -51.785909)
			(xy 378.535028 -51.829773) (xy 378.452828 -51.866516) (xy 378.367702 -51.895851) (xy 378.280317 -51.917547)
			(xy 378.191356 -51.931436) (xy 378.101515 -51.937407) (xy 378.011499 -51.935416) (xy 377.92201 -51.925476)
			(xy 377.833751 -51.907666) (xy 377.74741 -51.882126) (xy 377.663665 -51.849054) (xy 377.583171 -51.808711)
			(xy 377.506557 -51.761411) (xy 377.434423 -51.707526) (xy 377.367334 -51.647476) (xy 377.305814 -51.581731)
			(xy 377.250346 -51.510807) (xy 377.201363 -51.435258) (xy 377.159249 -51.355676) (xy 377.124333 -51.272683)
			(xy 377.096889 -51.186929) (xy 377.077131 -51.099085) (xy 377.065214 -51.009838) (xy 377.061232 -50.919888)
			(xy 336.242505 -50.919888) (xy 336.249349 -50.956545) (xy 336.256919 -51.038332) (xy 336.257392 -51.0794)
			(xy 336.256924 -51.121325) (xy 336.249033 -51.204803) (xy 336.233322 -51.287169) (xy 336.209928 -51.367689)
			(xy 336.179061 -51.445652) (xy 336.140994 -51.520363) (xy 336.096065 -51.59116) (xy 336.044672 -51.657415)
			(xy 335.987273 -51.718539) (xy 335.924376 -51.773991) (xy 335.85654 -51.823277) (xy 335.784367 -51.865961)
			(xy 335.708497 -51.901663) (xy 335.629604 -51.930066) (xy 335.548388 -51.95092) (xy 335.46557 -51.964037)
			(xy 335.381885 -51.969303) (xy 335.298076 -51.966669) (xy 335.214887 -51.956161) (xy 335.133056 -51.93787)
			(xy 335.053309 -51.911959) (xy 334.976355 -51.878659) (xy 334.902876 -51.838264) (xy 334.833525 -51.791134)
			(xy 334.768916 -51.737686) (xy 334.709625 -51.678396) (xy 334.656176 -51.613788) (xy 334.609044 -51.544438)
			(xy 334.568648 -51.47096) (xy 334.535346 -51.394006) (xy 334.509434 -51.31426) (xy 334.491142 -51.232429)
			(xy 334.480632 -51.14924) (xy 334.477997 -51.065431) (xy 325.12 -51.065431) (xy 325.12 -56.9214)
			(xy 331.266292 -56.9214) (xy 331.266292 -56.920892) (xy 331.266898 -56.87456) (xy 331.276569 -56.782402)
			(xy 331.295765 -56.691748) (xy 331.324277 -56.603579) (xy 331.342492 -56.560974) (xy 331.346298 -56.551032)
			(xy 331.346298 -56.529768) (xy 331.342492 -56.519826) (xy 331.324247 -56.477164) (xy 331.295703 -56.388871)
			(xy 331.27651 -56.298086) (xy 331.266877 -56.205796) (xy 331.266292 -56.1594) (xy 331.266875 -56.113004)
			(xy 331.27652 -56.020716) (xy 331.295716 -55.929932) (xy 331.324254 -55.841639) (xy 331.342492 -55.798974)
			(xy 331.346298 -55.789032) (xy 331.346298 -55.767768) (xy 331.342492 -55.757826) (xy 331.324247 -55.715164)
			(xy 331.295703 -55.626871) (xy 331.27651 -55.536086) (xy 331.266877 -55.443796) (xy 331.266292 -55.3974)
			(xy 331.266875 -55.351004) (xy 331.27652 -55.258716) (xy 331.295716 -55.167932) (xy 331.324254 -55.079639)
			(xy 331.342492 -55.036974) (xy 331.346298 -55.027032) (xy 331.346298 -55.005768) (xy 331.342492 -54.995826)
			(xy 331.324247 -54.953164) (xy 331.295703 -54.864871) (xy 331.27651 -54.774086) (xy 331.266877 -54.681796)
			(xy 331.266292 -54.6354) (xy 331.266875 -54.589004) (xy 331.27652 -54.496716) (xy 331.295716 -54.405932)
			(xy 331.324254 -54.317639) (xy 331.342492 -54.274974) (xy 331.346298 -54.265032) (xy 331.346298 -54.243768)
			(xy 331.342492 -54.233826) (xy 331.32427 -54.191223) (xy 331.295752 -54.103056) (xy 331.27656 -54.0124)
			(xy 331.2669 -53.92024) (xy 331.266292 -53.873908) (xy 331.266292 -53.8734) (xy 331.266767 -53.832298)
			(xy 331.274352 -53.750443) (xy 331.289457 -53.669638) (xy 331.311953 -53.590571) (xy 331.341649 -53.513917)
			(xy 331.378291 -53.44033) (xy 331.421566 -53.370438) (xy 331.471106 -53.304837) (xy 331.526487 -53.244087)
			(xy 331.587237 -53.188706) (xy 331.652838 -53.139166) (xy 331.72273 -53.095891) (xy 331.796317 -53.059249)
			(xy 331.872971 -53.029553) (xy 331.952038 -53.007057) (xy 332.032843 -52.991952) (xy 332.114698 -52.984367)
			(xy 332.1558 -52.983892) (xy 332.156308 -52.983892) (xy 332.20264 -52.984498) (xy 332.294798 -52.994169)
			(xy 332.385452 -53.013365) (xy 332.473621 -53.041877) (xy 332.516226 -53.060092) (xy 332.526168 -53.063898)
			(xy 332.547432 -53.063898) (xy 332.557374 -53.060092) (xy 332.600036 -53.041847) (xy 332.688329 -53.013303)
			(xy 332.779114 -52.99411) (xy 332.871404 -52.984477) (xy 332.9178 -52.983892) (xy 332.964196 -52.984475)
			(xy 333.056484 -52.99412) (xy 333.147268 -53.013316) (xy 333.235561 -53.041854) (xy 333.278226 -53.060092)
			(xy 333.288168 -53.063898) (xy 333.309432 -53.063898) (xy 333.319374 -53.060092) (xy 333.362036 -53.041847)
			(xy 333.450329 -53.013303) (xy 333.541114 -52.99411) (xy 333.633404 -52.984477) (xy 333.6798 -52.983892)
			(xy 333.726196 -52.984475) (xy 333.818484 -52.99412) (xy 333.909268 -53.013316) (xy 333.997561 -53.041854)
			(xy 334.040226 -53.060092) (xy 334.050168 -53.063898) (xy 334.071432 -53.063898) (xy 334.081374 -53.060092)
			(xy 334.124036 -53.041847) (xy 334.212329 -53.013303) (xy 334.303114 -52.99411) (xy 334.395404 -52.984477)
			(xy 334.4418 -52.983892) (xy 334.488196 -52.984475) (xy 334.580484 -52.99412) (xy 334.671268 -53.013316)
			(xy 334.759561 -53.041854) (xy 334.802226 -53.060092) (xy 334.812168 -53.063898) (xy 334.833432 -53.063898)
			(xy 334.843374 -53.060092) (xy 334.885977 -53.04187) (xy 334.974144 -53.013352) (xy 335.0648 -52.99416)
			(xy 335.15696 -52.9845) (xy 335.203292 -52.983892) (xy 335.2038 -52.983892) (xy 335.244902 -52.984367)
			(xy 335.326757 -52.991952) (xy 335.407562 -53.007057) (xy 335.486629 -53.029553) (xy 335.563283 -53.059249)
			(xy 335.63687 -53.095891) (xy 335.706762 -53.139166) (xy 335.772363 -53.188706) (xy 335.833113 -53.244087)
			(xy 335.888494 -53.304837) (xy 335.938034 -53.370438) (xy 335.981309 -53.44033) (xy 336.017951 -53.513917)
			(xy 336.047647 -53.590571) (xy 336.070143 -53.669638) (xy 336.085248 -53.750443) (xy 336.092833 -53.832298)
			(xy 336.093308 -53.8734) (xy 336.093308 -53.873908) (xy 336.092702 -53.92024) (xy 336.083031 -54.012398)
			(xy 336.063835 -54.103052) (xy 336.035323 -54.191221) (xy 336.017108 -54.233826) (xy 336.013302 -54.243768)
			(xy 336.013302 -54.265032) (xy 336.017108 -54.274974) (xy 336.035353 -54.317636) (xy 336.063897 -54.405929)
			(xy 336.08309 -54.496714) (xy 336.092723 -54.589004) (xy 336.093308 -54.6354) (xy 336.092725 -54.681796)
			(xy 336.08308 -54.774084) (xy 336.063884 -54.864868) (xy 336.035346 -54.953161) (xy 336.017108 -54.995826)
			(xy 336.013302 -55.005768) (xy 336.013302 -55.027032) (xy 336.017108 -55.036974) (xy 336.035353 -55.079636)
			(xy 336.063897 -55.167929) (xy 336.08309 -55.258714) (xy 336.092723 -55.351004) (xy 336.093308 -55.3974)
			(xy 336.092725 -55.443796) (xy 336.08308 -55.536084) (xy 336.063884 -55.626868) (xy 336.035346 -55.715161)
			(xy 336.017108 -55.757826) (xy 336.013302 -55.767768) (xy 336.013302 -55.789032) (xy 336.017108 -55.798974)
			(xy 336.035353 -55.841636) (xy 336.063897 -55.929929) (xy 336.076593 -55.989982) (xy 468.668363 -55.989982)
			(xy 468.672353 -55.876999) (xy 468.684302 -55.764578) (xy 468.704152 -55.653281) (xy 468.731804 -55.543661)
			(xy 468.767118 -55.436264) (xy 468.809921 -55.331626) (xy 468.859998 -55.230268) (xy 468.9171 -55.132695)
			(xy 468.980942 -55.039393) (xy 469.051207 -54.950827) (xy 469.127544 -54.867437) (xy 469.209573 -54.78964)
			(xy 469.296886 -54.717823) (xy 469.389047 -54.652344) (xy 469.485597 -54.593529) (xy 469.586055 -54.541671)
			(xy 469.689922 -54.497029) (xy 469.796678 -54.459824) (xy 469.905793 -54.430242) (xy 470.016723 -54.408431)
			(xy 470.128915 -54.3945) (xy 470.24181 -54.388516) (xy 470.354846 -54.390512) (xy 470.46746 -54.400475)
			(xy 470.579091 -54.418358) (xy 470.689182 -54.44407) (xy 470.797185 -54.477484) (xy 470.902562 -54.518433)
			(xy 471.004788 -54.566714) (xy 471.103353 -54.622085) (xy 471.197768 -54.68427) (xy 471.28756 -54.752961)
			(xy 471.372284 -54.827815) (xy 471.451517 -54.908458) (xy 471.524863 -54.99449) (xy 471.591959 -55.085481)
			(xy 471.652468 -55.180978) (xy 471.706091 -55.280505) (xy 471.75256 -55.383568) (xy 471.791643 -55.489651)
			(xy 471.823146 -55.598227) (xy 471.846911 -55.708754) (xy 471.862821 -55.820683) (xy 471.870795 -55.933455)
			(xy 471.871294 -55.989982) (xy 471.870795 -56.046509) (xy 471.862821 -56.159281) (xy 471.846911 -56.27121)
			(xy 471.823146 -56.381737) (xy 471.791643 -56.490313) (xy 471.75256 -56.596396) (xy 471.706091 -56.699459)
			(xy 471.652468 -56.798986) (xy 471.591959 -56.894483) (xy 471.524863 -56.985474) (xy 471.451517 -57.071506)
			(xy 471.372284 -57.152149) (xy 471.28756 -57.227003) (xy 471.197768 -57.295694) (xy 471.103353 -57.357879)
			(xy 471.004788 -57.41325) (xy 470.902562 -57.461531) (xy 470.797185 -57.50248) (xy 470.689182 -57.535894)
			(xy 470.579091 -57.561606) (xy 470.46746 -57.579489) (xy 470.354846 -57.589452) (xy 470.24181 -57.591448)
			(xy 470.128915 -57.585464) (xy 470.016723 -57.571533) (xy 469.905793 -57.549722) (xy 469.796678 -57.52014)
			(xy 469.689922 -57.482935) (xy 469.586055 -57.438293) (xy 469.485597 -57.386435) (xy 469.389047 -57.32762)
			(xy 469.296886 -57.262141) (xy 469.209573 -57.190324) (xy 469.127544 -57.112527) (xy 469.051207 -57.029137)
			(xy 468.980942 -56.940571) (xy 468.9171 -56.847269) (xy 468.859998 -56.749696) (xy 468.809921 -56.648338)
			(xy 468.767118 -56.5437) (xy 468.731804 -56.436303) (xy 468.704152 -56.326683) (xy 468.684302 -56.215386)
			(xy 468.672353 -56.102965) (xy 468.668363 -55.989982) (xy 336.076593 -55.989982) (xy 336.08309 -56.020714)
			(xy 336.092723 -56.113004) (xy 336.093308 -56.1594) (xy 336.092725 -56.205796) (xy 336.08308 -56.298084)
			(xy 336.063884 -56.388868) (xy 336.035346 -56.477161) (xy 336.017108 -56.519826) (xy 336.013302 -56.529768)
			(xy 336.013302 -56.551032) (xy 336.017108 -56.560974) (xy 336.03533 -56.603577) (xy 336.063848 -56.691744)
			(xy 336.08304 -56.7824) (xy 336.0927 -56.87456) (xy 336.093308 -56.920892) (xy 336.093308 -56.9214)
			(xy 336.092833 -56.962502) (xy 336.085248 -57.044357) (xy 336.070143 -57.125162) (xy 336.047647 -57.204229)
			(xy 336.017951 -57.280883) (xy 335.981309 -57.35447) (xy 335.938034 -57.424362) (xy 335.888494 -57.489963)
			(xy 335.833113 -57.550713) (xy 335.772363 -57.606094) (xy 335.706762 -57.655634) (xy 335.63687 -57.698909)
			(xy 335.563283 -57.735551) (xy 335.486629 -57.765247) (xy 335.407562 -57.787743) (xy 335.326757 -57.802848)
			(xy 335.244902 -57.810433) (xy 335.2038 -57.810908) (xy 335.203292 -57.810908) (xy 335.15696 -57.810302)
			(xy 335.064802 -57.800631) (xy 334.974148 -57.781435) (xy 334.885979 -57.752923) (xy 334.843374 -57.734708)
			(xy 334.833432 -57.730902) (xy 334.812168 -57.730902) (xy 334.802226 -57.734708) (xy 334.759564 -57.752953)
			(xy 334.671271 -57.781497) (xy 334.580486 -57.80069) (xy 334.488196 -57.810323) (xy 334.4418 -57.810908)
			(xy 334.395404 -57.810325) (xy 334.303116 -57.80068) (xy 334.212332 -57.781484) (xy 334.124039 -57.752946)
			(xy 334.081374 -57.734708) (xy 334.071432 -57.730902) (xy 334.050168 -57.730902) (xy 334.040226 -57.734708)
			(xy 333.997564 -57.752953) (xy 333.909271 -57.781497) (xy 333.818486 -57.80069) (xy 333.726196 -57.810323)
			(xy 333.6798 -57.810908) (xy 333.633404 -57.810325) (xy 333.541116 -57.80068) (xy 333.450332 -57.781484)
			(xy 333.362039 -57.752946) (xy 333.319374 -57.734708) (xy 333.309432 -57.730902) (xy 333.288168 -57.730902)
			(xy 333.278226 -57.734708) (xy 333.235564 -57.752953) (xy 333.147271 -57.781497) (xy 333.056486 -57.80069)
			(xy 332.964196 -57.810323) (xy 332.9178 -57.810908) (xy 332.871404 -57.810325) (xy 332.779116 -57.80068)
			(xy 332.688332 -57.781484) (xy 332.600039 -57.752946) (xy 332.557374 -57.734708) (xy 332.547432 -57.730902)
			(xy 332.526168 -57.730902) (xy 332.516226 -57.734708) (xy 332.473623 -57.75293) (xy 332.385456 -57.781448)
			(xy 332.2948 -57.80064) (xy 332.20264 -57.8103) (xy 332.156308 -57.810908) (xy 332.1558 -57.810908)
			(xy 332.114698 -57.810433) (xy 332.032843 -57.802848) (xy 331.952038 -57.787743) (xy 331.872971 -57.765247)
			(xy 331.796317 -57.735551) (xy 331.72273 -57.698909) (xy 331.652838 -57.655634) (xy 331.587237 -57.606094)
			(xy 331.526487 -57.550713) (xy 331.471106 -57.489963) (xy 331.421566 -57.424362) (xy 331.378291 -57.35447)
			(xy 331.341649 -57.280883) (xy 331.311953 -57.204229) (xy 331.289457 -57.125162) (xy 331.274352 -57.044357)
			(xy 331.266767 -56.962502) (xy 331.266292 -56.9214) (xy 325.12 -56.9214) (xy 325.12 -58.42) (xy 376.553741 -58.42)
			(xy 376.557716 -58.309941) (xy 376.569624 -58.200455) (xy 376.5894 -58.092114) (xy 376.616943 -57.985483)
			(xy 376.652108 -57.881117) (xy 376.694712 -57.77956) (xy 376.744533 -57.681343) (xy 376.801312 -57.586976)
			(xy 376.864751 -57.496952) (xy 376.934522 -57.411741) (xy 377.010259 -57.331786) (xy 377.091568 -57.257505)
			(xy 377.178025 -57.189285) (xy 377.269179 -57.12748) (xy 377.364556 -57.072415) (xy 377.463657 -57.024375)
			(xy 377.565966 -56.983611) (xy 377.67095 -56.950336) (xy 377.778061 -56.924723) (xy 377.886741 -56.906906)
			(xy 377.996424 -56.896977) (xy 378.106537 -56.894989) (xy 378.216507 -56.900951) (xy 378.32576 -56.914833)
			(xy 378.433726 -56.936563) (xy 378.539843 -56.966026) (xy 378.643557 -57.003069) (xy 378.744328 -57.0475)
			(xy 378.84163 -57.099087) (xy 378.934956 -57.157559) (xy 379.023819 -57.222614) (xy 379.107757 -57.293912)
			(xy 379.186332 -57.37108) (xy 379.259133 -57.453717) (xy 379.325781 -57.541391) (xy 379.38593 -57.633647)
			(xy 379.439264 -57.730002) (xy 379.485507 -57.829954) (xy 379.524417 -57.932982) (xy 379.555791 -58.03855)
			(xy 379.579466 -58.146106) (xy 379.595318 -58.25509) (xy 379.603265 -58.364934) (xy 379.603762 -58.42)
			(xy 396.111741 -58.42) (xy 396.115716 -58.309941) (xy 396.127624 -58.200455) (xy 396.1474 -58.092114)
			(xy 396.174943 -57.985483) (xy 396.210108 -57.881117) (xy 396.252712 -57.77956) (xy 396.302533 -57.681343)
			(xy 396.359312 -57.586976) (xy 396.422751 -57.496952) (xy 396.492522 -57.411741) (xy 396.568259 -57.331786)
			(xy 396.649568 -57.257505) (xy 396.736025 -57.189285) (xy 396.827179 -57.12748) (xy 396.922556 -57.072415)
			(xy 397.021657 -57.024375) (xy 397.123966 -56.983611) (xy 397.22895 -56.950336) (xy 397.336061 -56.924723)
			(xy 397.444741 -56.906906) (xy 397.554424 -56.896977) (xy 397.664537 -56.894989) (xy 397.774507 -56.900951)
			(xy 397.88376 -56.914833) (xy 397.991726 -56.936563) (xy 398.097843 -56.966026) (xy 398.201557 -57.003069)
			(xy 398.302328 -57.0475) (xy 398.39963 -57.099087) (xy 398.492956 -57.157559) (xy 398.581819 -57.222614)
			(xy 398.665757 -57.293912) (xy 398.744332 -57.37108) (xy 398.817133 -57.453717) (xy 398.883781 -57.541391)
			(xy 398.94393 -57.633647) (xy 398.997264 -57.730002) (xy 399.043507 -57.829954) (xy 399.082417 -57.932982)
			(xy 399.113791 -58.03855) (xy 399.137466 -58.146106) (xy 399.153318 -58.25509) (xy 399.161265 -58.364934)
			(xy 399.161762 -58.42) (xy 399.161265 -58.475066) (xy 399.153318 -58.58491) (xy 399.137466 -58.693894)
			(xy 399.113791 -58.80145) (xy 399.082417 -58.907018) (xy 399.043507 -59.010046) (xy 398.997264 -59.109998)
			(xy 398.94393 -59.206353) (xy 398.883781 -59.298609) (xy 398.817133 -59.386283) (xy 398.744332 -59.46892)
			(xy 398.665757 -59.546088) (xy 398.581819 -59.617386) (xy 398.492956 -59.682441) (xy 398.39963 -59.740913)
			(xy 398.302328 -59.7925) (xy 398.201557 -59.836931) (xy 398.097843 -59.873974) (xy 397.991726 -59.903437)
			(xy 397.88376 -59.925167) (xy 397.774507 -59.939049) (xy 397.664537 -59.945011) (xy 397.554424 -59.943023)
			(xy 397.444741 -59.933094) (xy 397.336061 -59.915277) (xy 397.22895 -59.889664) (xy 397.123966 -59.856389)
			(xy 397.021657 -59.815625) (xy 396.922556 -59.767585) (xy 396.827179 -59.71252) (xy 396.736025 -59.650715)
			(xy 396.649568 -59.582495) (xy 396.568259 -59.508214) (xy 396.492522 -59.428259) (xy 396.422751 -59.343048)
			(xy 396.359312 -59.253024) (xy 396.302533 -59.158657) (xy 396.252712 -59.06044) (xy 396.210108 -58.958883)
			(xy 396.174943 -58.854517) (xy 396.1474 -58.747886) (xy 396.127624 -58.639545) (xy 396.115716 -58.530059)
			(xy 396.111741 -58.42) (xy 379.603762 -58.42) (xy 379.603265 -58.475066) (xy 379.595318 -58.58491)
			(xy 379.579466 -58.693894) (xy 379.555791 -58.80145) (xy 379.524417 -58.907018) (xy 379.485507 -59.010046)
			(xy 379.439264 -59.109998) (xy 379.38593 -59.206353) (xy 379.325781 -59.298609) (xy 379.259133 -59.386283)
			(xy 379.186332 -59.46892) (xy 379.107757 -59.546088) (xy 379.023819 -59.617386) (xy 378.934956 -59.682441)
			(xy 378.84163 -59.740913) (xy 378.744328 -59.7925) (xy 378.643557 -59.836931) (xy 378.539843 -59.873974)
			(xy 378.433726 -59.903437) (xy 378.32576 -59.925167) (xy 378.216507 -59.939049) (xy 378.106537 -59.945011)
			(xy 377.996424 -59.943023) (xy 377.886741 -59.933094) (xy 377.778061 -59.915277) (xy 377.67095 -59.889664)
			(xy 377.565966 -59.856389) (xy 377.463657 -59.815625) (xy 377.364556 -59.767585) (xy 377.269179 -59.71252)
			(xy 377.178025 -59.650715) (xy 377.091568 -59.582495) (xy 377.010259 -59.508214) (xy 376.934522 -59.428259)
			(xy 376.864751 -59.343048) (xy 376.801312 -59.253024) (xy 376.744533 -59.158657) (xy 376.694712 -59.06044)
			(xy 376.652108 -58.958883) (xy 376.616943 -58.854517) (xy 376.5894 -58.747886) (xy 376.569624 -58.639545)
			(xy 376.557716 -58.530059) (xy 376.553741 -58.42) (xy 325.12 -58.42) (xy 325.12 -60.099956) (xy 422.484046 -60.099956)
			(xy 422.488076 -59.957621) (xy 422.500151 -59.815741) (xy 422.520234 -59.674773) (xy 422.548261 -59.535166)
			(xy 422.584141 -59.397368) (xy 422.627759 -59.261821) (xy 422.678976 -59.128959) (xy 422.737627 -58.999207)
			(xy 422.803525 -58.872981) (xy 422.876459 -58.750685) (xy 422.956196 -58.632712) (xy 423.042478 -58.519439)
			(xy 423.135031 -58.411228) (xy 423.233558 -58.308427) (xy 423.337743 -58.211365) (xy 423.447252 -58.120353)
			(xy 423.561735 -58.035681) (xy 423.680825 -57.957623) (xy 423.80414 -57.886427) (xy 423.931286 -57.822321)
			(xy 424.061855 -57.765512) (xy 424.195429 -57.71618) (xy 424.33158 -57.674484) (xy 424.469871 -57.640558)
			(xy 424.609861 -57.61451) (xy 424.7511 -57.596424) (xy 424.893136 -57.586357) (xy 425.035514 -57.584342)
			(xy 425.177778 -57.590385) (xy 425.319472 -57.604467) (xy 425.460142 -57.626543) (xy 425.599339 -57.656543)
			(xy 425.736615 -57.694369) (xy 425.871531 -57.739901) (xy 426.003655 -57.792992) (xy 426.132564 -57.853474)
			(xy 426.257845 -57.921152) (xy 426.379096 -57.995809) (xy 426.495929 -58.077207) (xy 426.60797 -58.165084)
			(xy 426.71486 -58.259159) (xy 426.816257 -58.359131) (xy 426.911835 -58.464679) (xy 427.001289 -58.575465)
			(xy 427.084331 -58.691134) (xy 427.160697 -58.811317) (xy 427.230141 -58.935627) (xy 427.292441 -59.063668)
			(xy 427.347397 -59.195027) (xy 427.394834 -59.329286) (xy 427.434598 -59.466013) (xy 427.466564 -59.604771)
			(xy 427.490629 -59.745115) (xy 427.506715 -59.886596) (xy 427.51477 -60.02876) (xy 427.515274 -60.099956)
			(xy 427.51477 -60.171152) (xy 427.506715 -60.313316) (xy 427.490629 -60.454797) (xy 427.466564 -60.595141)
			(xy 427.434598 -60.733899) (xy 427.394834 -60.870626) (xy 427.347397 -61.004885) (xy 427.292441 -61.136244)
			(xy 427.230141 -61.264285) (xy 427.160697 -61.388595) (xy 427.084331 -61.508778) (xy 427.001289 -61.624447)
			(xy 426.911835 -61.735233) (xy 426.816257 -61.840781) (xy 426.71486 -61.940753) (xy 426.60797 -62.034828)
			(xy 426.495929 -62.122705) (xy 426.379096 -62.204103) (xy 426.257845 -62.27876) (xy 426.132564 -62.346438)
			(xy 426.003655 -62.40692) (xy 425.871531 -62.460011) (xy 425.736615 -62.505543) (xy 425.599339 -62.543369)
			(xy 425.460142 -62.573369) (xy 425.319472 -62.595445) (xy 425.177778 -62.609527) (xy 425.035514 -62.61557)
			(xy 424.893136 -62.613555) (xy 424.7511 -62.603488) (xy 424.609861 -62.585402) (xy 424.469871 -62.559354)
			(xy 424.33158 -62.525428) (xy 424.195429 -62.483732) (xy 424.061855 -62.4344) (xy 423.931286 -62.377591)
			(xy 423.80414 -62.313485) (xy 423.680825 -62.242289) (xy 423.561735 -62.164231) (xy 423.447252 -62.079559)
			(xy 423.337743 -61.988547) (xy 423.233558 -61.891485) (xy 423.135031 -61.788684) (xy 423.042478 -61.680473)
			(xy 422.956196 -61.5672) (xy 422.876459 -61.449227) (xy 422.803525 -61.326931) (xy 422.737627 -61.200705)
			(xy 422.678976 -61.070953) (xy 422.627759 -60.938091) (xy 422.584141 -60.802544) (xy 422.548261 -60.664746)
			(xy 422.520234 -60.525139) (xy 422.500151 -60.384171) (xy 422.488076 -60.242291) (xy 422.484046 -60.099956)
			(xy 325.12 -60.099956) (xy 325.12 -62.399361) (xy 334.478626 -62.399361) (xy 334.478626 -62.314639)
			(xy 334.486679 -62.230302) (xy 334.502713 -62.147112) (xy 334.526581 -62.065822) (xy 334.558069 -61.98717)
			(xy 334.596891 -61.911867) (xy 334.642694 -61.840595) (xy 334.695065 -61.773999) (xy 334.75353 -61.712684)
			(xy 334.817558 -61.657203) (xy 334.88657 -61.60806) (xy 334.95994 -61.5657) (xy 335.037005 -61.530505)
			(xy 335.117067 -61.502796) (xy 335.1994 -61.482822) (xy 335.283259 -61.470765) (xy 335.367884 -61.466734)
			(xy 335.452509 -61.470765) (xy 335.536368 -61.482822) (xy 335.618701 -61.502796) (xy 335.698763 -61.530505)
			(xy 335.775828 -61.5657) (xy 335.849198 -61.60806) (xy 335.91821 -61.657203) (xy 335.982238 -61.712684)
			(xy 336.040703 -61.773999) (xy 336.093074 -61.840595) (xy 336.138877 -61.911867) (xy 336.177699 -61.98717)
			(xy 336.209187 -62.065822) (xy 336.233055 -62.147112) (xy 336.249089 -62.230302) (xy 336.257142 -62.314639)
			(xy 336.257646 -62.357) (xy 336.257142 -62.399361) (xy 336.249089 -62.483698) (xy 336.233055 -62.566888)
			(xy 336.209187 -62.648178) (xy 336.177699 -62.72683) (xy 336.138877 -62.802133) (xy 336.093074 -62.873405)
			(xy 336.040703 -62.940001) (xy 335.982238 -63.001316) (xy 335.91821 -63.056797) (xy 335.849198 -63.10594)
			(xy 335.775828 -63.1483) (xy 335.698763 -63.183495) (xy 335.618701 -63.211204) (xy 335.536368 -63.231178)
			(xy 335.452509 -63.243235) (xy 335.367884 -63.247267) (xy 335.283259 -63.243235) (xy 335.1994 -63.231178)
			(xy 335.117067 -63.211204) (xy 335.037005 -63.183495) (xy 334.95994 -63.1483) (xy 334.88657 -63.10594)
			(xy 334.817558 -63.056797) (xy 334.75353 -63.001316) (xy 334.695065 -62.940001) (xy 334.642694 -62.873405)
			(xy 334.596891 -62.802133) (xy 334.558069 -62.72683) (xy 334.526581 -62.648178) (xy 334.502713 -62.566888)
			(xy 334.486679 -62.483698) (xy 334.478626 -62.399361) (xy 325.12 -62.399361) (xy 325.12 -68.199)
			(xy 331.266292 -68.199) (xy 331.266292 -68.198492) (xy 331.266898 -68.15216) (xy 331.276569 -68.060002)
			(xy 331.295765 -67.969348) (xy 331.324277 -67.881179) (xy 331.342492 -67.838574) (xy 331.346298 -67.828632)
			(xy 331.346298 -67.807368) (xy 331.342492 -67.797426) (xy 331.324247 -67.754764) (xy 331.295703 -67.666471)
			(xy 331.27651 -67.575686) (xy 331.266877 -67.483396) (xy 331.266292 -67.437) (xy 331.266875 -67.390604)
			(xy 331.27652 -67.298316) (xy 331.295716 -67.207532) (xy 331.324254 -67.119239) (xy 331.342492 -67.076574)
			(xy 331.346298 -67.066632) (xy 331.346298 -67.045368) (xy 331.342492 -67.035426) (xy 331.324247 -66.992764)
			(xy 331.295703 -66.904471) (xy 331.27651 -66.813686) (xy 331.266877 -66.721396) (xy 331.266292 -66.675)
			(xy 331.266875 -66.628604) (xy 331.27652 -66.536316) (xy 331.295716 -66.445532) (xy 331.324254 -66.357239)
			(xy 331.342492 -66.314574) (xy 331.346298 -66.304632) (xy 331.346298 -66.283368) (xy 331.342492 -66.273426)
			(xy 331.324247 -66.230764) (xy 331.295703 -66.142471) (xy 331.27651 -66.051686) (xy 331.266877 -65.959396)
			(xy 331.266292 -65.913) (xy 331.266875 -65.866604) (xy 331.27652 -65.774316) (xy 331.295716 -65.683532)
			(xy 331.324254 -65.595239) (xy 331.342492 -65.552574) (xy 331.346298 -65.542632) (xy 331.346298 -65.521368)
			(xy 331.342492 -65.511426) (xy 331.32427 -65.468823) (xy 331.295752 -65.380656) (xy 331.27656 -65.29)
			(xy 331.2669 -65.19784) (xy 331.266292 -65.151508) (xy 331.266292 -65.151) (xy 331.266767 -65.109898)
			(xy 331.274352 -65.028043) (xy 331.289457 -64.947238) (xy 331.311953 -64.868171) (xy 331.341649 -64.791517)
			(xy 331.378291 -64.71793) (xy 331.421566 -64.648038) (xy 331.471106 -64.582437) (xy 331.526487 -64.521687)
			(xy 331.587237 -64.466306) (xy 331.652838 -64.416766) (xy 331.72273 -64.373491) (xy 331.796317 -64.336849)
			(xy 331.872971 -64.307153) (xy 331.952038 -64.284657) (xy 332.032843 -64.269552) (xy 332.114698 -64.261967)
			(xy 332.1558 -64.261492) (xy 332.156308 -64.261492) (xy 332.20264 -64.262098) (xy 332.294798 -64.271769)
			(xy 332.385452 -64.290965) (xy 332.473621 -64.319477) (xy 332.516226 -64.337692) (xy 332.526168 -64.341498)
			(xy 332.547432 -64.341498) (xy 332.557374 -64.337692) (xy 332.600036 -64.319447) (xy 332.688329 -64.290903)
			(xy 332.779114 -64.27171) (xy 332.871404 -64.262077) (xy 332.9178 -64.261492) (xy 332.964196 -64.262075)
			(xy 333.056484 -64.27172) (xy 333.147268 -64.290916) (xy 333.235561 -64.319454) (xy 333.278226 -64.337692)
			(xy 333.288168 -64.341498) (xy 333.309432 -64.341498) (xy 333.319374 -64.337692) (xy 333.362036 -64.319447)
			(xy 333.450329 -64.290903) (xy 333.541114 -64.27171) (xy 333.633404 -64.262077) (xy 333.6798 -64.261492)
			(xy 333.726196 -64.262075) (xy 333.818484 -64.27172) (xy 333.909268 -64.290916) (xy 333.997561 -64.319454)
			(xy 334.040226 -64.337692) (xy 334.050168 -64.341498) (xy 334.071432 -64.341498) (xy 334.081374 -64.337692)
			(xy 334.124036 -64.319447) (xy 334.212329 -64.290903) (xy 334.303114 -64.27171) (xy 334.395404 -64.262077)
			(xy 334.4418 -64.261492) (xy 334.488196 -64.262075) (xy 334.580484 -64.27172) (xy 334.671268 -64.290916)
			(xy 334.759561 -64.319454) (xy 334.802226 -64.337692) (xy 334.812168 -64.341498) (xy 334.833432 -64.341498)
			(xy 334.843374 -64.337692) (xy 334.885977 -64.31947) (xy 334.974144 -64.290952) (xy 335.0648 -64.27176)
			(xy 335.15696 -64.2621) (xy 335.203292 -64.261492) (xy 335.2038 -64.261492) (xy 335.244902 -64.261967)
			(xy 335.326757 -64.269552) (xy 335.407562 -64.284657) (xy 335.486629 -64.307153) (xy 335.563283 -64.336849)
			(xy 335.63687 -64.373491) (xy 335.706762 -64.416766) (xy 335.772363 -64.466306) (xy 335.833113 -64.521687)
			(xy 335.888494 -64.582437) (xy 335.938034 -64.648038) (xy 335.981309 -64.71793) (xy 336.017951 -64.791517)
			(xy 336.047647 -64.868171) (xy 336.070143 -64.947238) (xy 336.085248 -65.028043) (xy 336.092833 -65.109898)
			(xy 336.093308 -65.151) (xy 336.093308 -65.151508) (xy 336.092702 -65.19784) (xy 336.083031 -65.289998)
			(xy 336.063835 -65.380652) (xy 336.035323 -65.468821) (xy 336.017108 -65.511426) (xy 336.013302 -65.521368)
			(xy 336.013302 -65.542632) (xy 336.017108 -65.552574) (xy 336.035353 -65.595236) (xy 336.063897 -65.683529)
			(xy 336.08309 -65.774314) (xy 336.092723 -65.866604) (xy 336.093308 -65.913) (xy 336.092725 -65.959396)
			(xy 336.08308 -66.051684) (xy 336.063884 -66.142468) (xy 336.035346 -66.230761) (xy 336.017108 -66.273426)
			(xy 336.013302 -66.283368) (xy 336.013302 -66.304632) (xy 336.017108 -66.314574) (xy 336.035353 -66.357236)
			(xy 336.063897 -66.445529) (xy 336.08309 -66.536314) (xy 336.092723 -66.628604) (xy 336.093308 -66.675)
			(xy 336.092725 -66.721396) (xy 336.08308 -66.813684) (xy 336.063884 -66.904468) (xy 336.035346 -66.992761)
			(xy 336.017108 -67.035426) (xy 336.013302 -67.045368) (xy 336.013302 -67.066632) (xy 336.017108 -67.076574)
			(xy 336.035353 -67.119236) (xy 336.063897 -67.207529) (xy 336.08309 -67.298314) (xy 336.092723 -67.390604)
			(xy 336.093308 -67.437) (xy 336.092725 -67.483396) (xy 336.08308 -67.575684) (xy 336.063884 -67.666468)
			(xy 336.035346 -67.754761) (xy 336.017108 -67.797426) (xy 336.013302 -67.807368) (xy 336.013302 -67.828632)
			(xy 336.017108 -67.838574) (xy 336.03533 -67.881177) (xy 336.063848 -67.969344) (xy 336.08304 -68.06)
			(xy 336.0927 -68.15216) (xy 336.093308 -68.198492) (xy 336.093308 -68.199) (xy 336.092833 -68.240102)
			(xy 336.085248 -68.321957) (xy 336.070143 -68.402762) (xy 336.047647 -68.481829) (xy 336.017951 -68.558483)
			(xy 335.981309 -68.63207) (xy 335.938034 -68.701962) (xy 335.888494 -68.767563) (xy 335.833113 -68.828313)
			(xy 335.772363 -68.883694) (xy 335.706762 -68.933234) (xy 335.63687 -68.976509) (xy 335.563283 -69.013151)
			(xy 335.486629 -69.042847) (xy 335.407562 -69.065343) (xy 335.326757 -69.080448) (xy 335.244902 -69.088033)
			(xy 335.2038 -69.088508) (xy 335.203292 -69.088508) (xy 335.15696 -69.087902) (xy 335.064802 -69.078231)
			(xy 334.974148 -69.059035) (xy 334.885979 -69.030523) (xy 334.843374 -69.012308) (xy 334.833432 -69.008502)
			(xy 334.812168 -69.008502) (xy 334.802226 -69.012308) (xy 334.759564 -69.030553) (xy 334.671271 -69.059097)
			(xy 334.580486 -69.07829) (xy 334.488196 -69.087923) (xy 334.4418 -69.088508) (xy 334.395404 -69.087925)
			(xy 334.303116 -69.07828) (xy 334.212332 -69.059084) (xy 334.124039 -69.030546) (xy 334.081374 -69.012308)
			(xy 334.071432 -69.008502) (xy 334.050168 -69.008502) (xy 334.040226 -69.012308) (xy 333.997564 -69.030553)
			(xy 333.909271 -69.059097) (xy 333.818486 -69.07829) (xy 333.726196 -69.087923) (xy 333.6798 -69.088508)
			(xy 333.633404 -69.087925) (xy 333.541116 -69.07828) (xy 333.450332 -69.059084) (xy 333.362039 -69.030546)
			(xy 333.319374 -69.012308) (xy 333.309432 -69.008502) (xy 333.288168 -69.008502) (xy 333.278226 -69.012308)
			(xy 333.235564 -69.030553) (xy 333.147271 -69.059097) (xy 333.056486 -69.07829) (xy 332.964196 -69.087923)
			(xy 332.9178 -69.088508) (xy 332.871404 -69.087925) (xy 332.779116 -69.07828) (xy 332.688332 -69.059084)
			(xy 332.600039 -69.030546) (xy 332.557374 -69.012308) (xy 332.547432 -69.008502) (xy 332.526168 -69.008502)
			(xy 332.516226 -69.012308) (xy 332.473623 -69.03053) (xy 332.385456 -69.059048) (xy 332.2948 -69.07824)
			(xy 332.20264 -69.0879) (xy 332.156308 -69.088508) (xy 332.1558 -69.088508) (xy 332.114698 -69.088033)
			(xy 332.032843 -69.080448) (xy 331.952038 -69.065343) (xy 331.872971 -69.042847) (xy 331.796317 -69.013151)
			(xy 331.72273 -68.976509) (xy 331.652838 -68.933234) (xy 331.587237 -68.883694) (xy 331.526487 -68.828313)
			(xy 331.471106 -68.767563) (xy 331.421566 -68.701962) (xy 331.378291 -68.63207) (xy 331.341649 -68.558483)
			(xy 331.311953 -68.481829) (xy 331.289457 -68.402762) (xy 331.274352 -68.321957) (xy 331.266767 -68.240102)
			(xy 331.266292 -68.199) (xy 325.12 -68.199) (xy 325.12 -71.239888) (xy 377.061232 -71.239888) (xy 377.065214 -71.149938)
			(xy 377.077131 -71.060691) (xy 377.096889 -70.972847) (xy 377.124333 -70.887093) (xy 377.159249 -70.8041)
			(xy 377.201363 -70.724518) (xy 377.250346 -70.648969) (xy 377.305814 -70.578045) (xy 377.367334 -70.5123)
			(xy 377.434423 -70.45225) (xy 377.506557 -70.398365) (xy 377.583171 -70.351065) (xy 377.663665 -70.310722)
			(xy 377.74741 -70.27765) (xy 377.833751 -70.25211) (xy 377.92201 -70.2343) (xy 378.011499 -70.22436)
			(xy 378.101515 -70.222369) (xy 378.191356 -70.22834) (xy 378.280317 -70.242229) (xy 378.367702 -70.263925)
			(xy 378.452828 -70.29326) (xy 378.535028 -70.330003) (xy 378.613659 -70.373867) (xy 378.688106 -70.424509)
			(xy 378.757786 -70.481533) (xy 378.822153 -70.544492) (xy 378.880704 -70.612893) (xy 378.932981 -70.686201)
			(xy 378.978574 -70.763843) (xy 379.017127 -70.84521) (xy 379.048338 -70.929666) (xy 379.071962 -71.01655)
			(xy 379.087815 -71.105182) (xy 379.095772 -71.194869) (xy 379.09627 -71.239888) (xy 396.619232 -71.239888)
			(xy 396.623214 -71.149938) (xy 396.635131 -71.060691) (xy 396.654889 -70.972847) (xy 396.682333 -70.887093)
			(xy 396.717249 -70.8041) (xy 396.759363 -70.724518) (xy 396.808346 -70.648969) (xy 396.863814 -70.578045)
			(xy 396.925334 -70.5123) (xy 396.992423 -70.45225) (xy 397.064557 -70.398365) (xy 397.141171 -70.351065)
			(xy 397.221665 -70.310722) (xy 397.30541 -70.27765) (xy 397.391751 -70.25211) (xy 397.48001 -70.2343)
			(xy 397.569499 -70.22436) (xy 397.659515 -70.222369) (xy 397.749356 -70.22834) (xy 397.838317 -70.242229)
			(xy 397.925702 -70.263925) (xy 398.010828 -70.29326) (xy 398.093028 -70.330003) (xy 398.171659 -70.373867)
			(xy 398.246106 -70.424509) (xy 398.315786 -70.481533) (xy 398.380153 -70.544492) (xy 398.438704 -70.612893)
			(xy 398.490981 -70.686201) (xy 398.536574 -70.763843) (xy 398.575127 -70.84521) (xy 398.606338 -70.929666)
			(xy 398.629962 -71.01655) (xy 398.645815 -71.105182) (xy 398.653772 -71.194869) (xy 398.65427 -71.239888)
			(xy 398.653772 -71.284907) (xy 398.645815 -71.374594) (xy 398.629962 -71.463226) (xy 398.606338 -71.55011)
			(xy 398.575127 -71.634566) (xy 398.536574 -71.715933) (xy 398.490981 -71.793575) (xy 398.438704 -71.866883)
			(xy 398.380153 -71.935284) (xy 398.315786 -71.998243) (xy 398.246106 -72.055267) (xy 398.171659 -72.105909)
			(xy 398.093028 -72.149773) (xy 398.010828 -72.186516) (xy 397.925702 -72.215851) (xy 397.838317 -72.237547)
			(xy 397.749356 -72.251436) (xy 397.659515 -72.257407) (xy 397.569499 -72.255416) (xy 397.48001 -72.245476)
			(xy 397.391751 -72.227666) (xy 397.30541 -72.202126) (xy 397.221665 -72.169054) (xy 397.141171 -72.128711)
			(xy 397.064557 -72.081411) (xy 396.992423 -72.027526) (xy 396.925334 -71.967476) (xy 396.863814 -71.901731)
			(xy 396.808346 -71.830807) (xy 396.759363 -71.755258) (xy 396.717249 -71.675676) (xy 396.682333 -71.592683)
			(xy 396.654889 -71.506929) (xy 396.635131 -71.419085) (xy 396.623214 -71.329838) (xy 396.619232 -71.239888)
			(xy 379.09627 -71.239888) (xy 379.095772 -71.284907) (xy 379.087815 -71.374594) (xy 379.071962 -71.463226)
			(xy 379.048338 -71.55011) (xy 379.017127 -71.634566) (xy 378.978574 -71.715933) (xy 378.932981 -71.793575)
			(xy 378.880704 -71.866883) (xy 378.822153 -71.935284) (xy 378.757786 -71.998243) (xy 378.688106 -72.055267)
			(xy 378.613659 -72.105909) (xy 378.535028 -72.149773) (xy 378.452828 -72.186516) (xy 378.367702 -72.215851)
			(xy 378.280317 -72.237547) (xy 378.191356 -72.251436) (xy 378.101515 -72.257407) (xy 378.011499 -72.255416)
			(xy 377.92201 -72.245476) (xy 377.833751 -72.227666) (xy 377.74741 -72.202126) (xy 377.663665 -72.169054)
			(xy 377.583171 -72.128711) (xy 377.506557 -72.081411) (xy 377.434423 -72.027526) (xy 377.367334 -71.967476)
			(xy 377.305814 -71.901731) (xy 377.250346 -71.830807) (xy 377.201363 -71.755258) (xy 377.159249 -71.675676)
			(xy 377.124333 -71.592683) (xy 377.096889 -71.506929) (xy 377.077131 -71.419085) (xy 377.065214 -71.329838)
			(xy 377.061232 -71.239888) (xy 325.12 -71.239888) (xy 325.12 -73.676961) (xy 334.478626 -73.676961)
			(xy 334.478626 -73.592239) (xy 334.486679 -73.507902) (xy 334.502713 -73.424712) (xy 334.526581 -73.343422)
			(xy 334.558069 -73.26477) (xy 334.596891 -73.189467) (xy 334.642694 -73.118195) (xy 334.695065 -73.051599)
			(xy 334.75353 -72.990284) (xy 334.817558 -72.934803) (xy 334.88657 -72.88566) (xy 334.95994 -72.8433)
			(xy 335.037005 -72.808105) (xy 335.117067 -72.780396) (xy 335.1994 -72.760422) (xy 335.283259 -72.748365)
			(xy 335.367884 -72.744334) (xy 335.452509 -72.748365) (xy 335.536368 -72.760422) (xy 335.618701 -72.780396)
			(xy 335.698763 -72.808105) (xy 335.775828 -72.8433) (xy 335.849198 -72.88566) (xy 335.91821 -72.934803)
			(xy 335.982238 -72.990284) (xy 336.040703 -73.051599) (xy 336.093074 -73.118195) (xy 336.138877 -73.189467)
			(xy 336.177699 -73.26477) (xy 336.209187 -73.343422) (xy 336.233055 -73.424712) (xy 336.249089 -73.507902)
			(xy 336.257142 -73.592239) (xy 336.257646 -73.6346) (xy 336.257142 -73.676961) (xy 336.249089 -73.761298)
			(xy 336.233055 -73.844488) (xy 336.209187 -73.925778) (xy 336.177699 -74.00443) (xy 336.138877 -74.079733)
			(xy 336.093074 -74.151005) (xy 336.040703 -74.217601) (xy 335.982238 -74.278916) (xy 335.91821 -74.334397)
			(xy 335.849198 -74.38354) (xy 335.775828 -74.4259) (xy 335.698763 -74.461095) (xy 335.618701 -74.488804)
			(xy 335.536368 -74.508778) (xy 335.452509 -74.520835) (xy 335.367884 -74.524867) (xy 335.283259 -74.520835)
			(xy 335.1994 -74.508778) (xy 335.117067 -74.488804) (xy 335.037005 -74.461095) (xy 334.95994 -74.4259)
			(xy 334.88657 -74.38354) (xy 334.817558 -74.334397) (xy 334.75353 -74.278916) (xy 334.695065 -74.217601)
			(xy 334.642694 -74.151005) (xy 334.596891 -74.079733) (xy 334.558069 -74.00443) (xy 334.526581 -73.925778)
			(xy 334.502713 -73.844488) (xy 334.486679 -73.761298) (xy 334.478626 -73.676961) (xy 325.12 -73.676961)
			(xy 325.12 -79.4766) (xy 331.266292 -79.4766) (xy 331.266292 -79.476092) (xy 331.266898 -79.42976)
			(xy 331.276569 -79.337602) (xy 331.295765 -79.246948) (xy 331.324277 -79.158779) (xy 331.342492 -79.116174)
			(xy 331.346298 -79.106232) (xy 331.346298 -79.084968) (xy 331.342492 -79.075026) (xy 331.324247 -79.032364)
			(xy 331.295703 -78.944071) (xy 331.27651 -78.853286) (xy 331.266877 -78.760996) (xy 331.266292 -78.7146)
			(xy 331.266875 -78.668204) (xy 331.27652 -78.575916) (xy 331.295716 -78.485132) (xy 331.324254 -78.396839)
			(xy 331.342492 -78.354174) (xy 331.346298 -78.344232) (xy 331.346298 -78.322968) (xy 331.342492 -78.313026)
			(xy 331.324247 -78.270364) (xy 331.295703 -78.182071) (xy 331.27651 -78.091286) (xy 331.266877 -77.998996)
			(xy 331.266292 -77.9526) (xy 331.266875 -77.906204) (xy 331.27652 -77.813916) (xy 331.295716 -77.723132)
			(xy 331.324254 -77.634839) (xy 331.342492 -77.592174) (xy 331.346298 -77.582232) (xy 331.346298 -77.560968)
			(xy 331.342492 -77.551026) (xy 331.324247 -77.508364) (xy 331.295703 -77.420071) (xy 331.27651 -77.329286)
			(xy 331.266877 -77.236996) (xy 331.266292 -77.1906) (xy 331.266875 -77.144204) (xy 331.27652 -77.051916)
			(xy 331.295716 -76.961132) (xy 331.324254 -76.872839) (xy 331.342492 -76.830174) (xy 331.346298 -76.820232)
			(xy 331.346298 -76.798968) (xy 331.342492 -76.789026) (xy 331.32427 -76.746423) (xy 331.295752 -76.658256)
			(xy 331.27656 -76.5676) (xy 331.2669 -76.47544) (xy 331.266292 -76.429108) (xy 331.266292 -76.4286)
			(xy 331.266767 -76.387498) (xy 331.274352 -76.305643) (xy 331.289457 -76.224838) (xy 331.311953 -76.145771)
			(xy 331.341649 -76.069117) (xy 331.378291 -75.99553) (xy 331.421566 -75.925638) (xy 331.471106 -75.860037)
			(xy 331.526487 -75.799287) (xy 331.587237 -75.743906) (xy 331.652838 -75.694366) (xy 331.72273 -75.651091)
			(xy 331.796317 -75.614449) (xy 331.872971 -75.584753) (xy 331.952038 -75.562257) (xy 332.032843 -75.547152)
			(xy 332.114698 -75.539567) (xy 332.1558 -75.539092) (xy 332.156308 -75.539092) (xy 332.20264 -75.539698)
			(xy 332.294798 -75.549369) (xy 332.385452 -75.568565) (xy 332.473621 -75.597077) (xy 332.516226 -75.615292)
			(xy 332.526168 -75.619098) (xy 332.547432 -75.619098) (xy 332.557374 -75.615292) (xy 332.600036 -75.597047)
			(xy 332.688329 -75.568503) (xy 332.779114 -75.54931) (xy 332.871404 -75.539677) (xy 332.9178 -75.539092)
			(xy 332.964196 -75.539675) (xy 333.056484 -75.54932) (xy 333.147268 -75.568516) (xy 333.235561 -75.597054)
			(xy 333.278226 -75.615292) (xy 333.288168 -75.619098) (xy 333.309432 -75.619098) (xy 333.319374 -75.615292)
			(xy 333.362036 -75.597047) (xy 333.450329 -75.568503) (xy 333.541114 -75.54931) (xy 333.633404 -75.539677)
			(xy 333.6798 -75.539092) (xy 333.726196 -75.539675) (xy 333.818484 -75.54932) (xy 333.909268 -75.568516)
			(xy 333.997561 -75.597054) (xy 334.040226 -75.615292) (xy 334.050168 -75.619098) (xy 334.071432 -75.619098)
			(xy 334.081374 -75.615292) (xy 334.124036 -75.597047) (xy 334.212329 -75.568503) (xy 334.303114 -75.54931)
			(xy 334.395404 -75.539677) (xy 334.4418 -75.539092) (xy 334.488196 -75.539675) (xy 334.580484 -75.54932)
			(xy 334.671268 -75.568516) (xy 334.759561 -75.597054) (xy 334.802226 -75.615292) (xy 334.812168 -75.619098)
			(xy 334.833432 -75.619098) (xy 334.843374 -75.615292) (xy 334.885977 -75.59707) (xy 334.974144 -75.568552)
			(xy 335.0648 -75.54936) (xy 335.15696 -75.5397) (xy 335.203292 -75.539092) (xy 335.2038 -75.539092)
			(xy 335.244902 -75.539567) (xy 335.326757 -75.547152) (xy 335.407562 -75.562257) (xy 335.486629 -75.584753)
			(xy 335.563283 -75.614449) (xy 335.63687 -75.651091) (xy 335.706762 -75.694366) (xy 335.772363 -75.743906)
			(xy 335.833113 -75.799287) (xy 335.888494 -75.860037) (xy 335.938034 -75.925638) (xy 335.981309 -75.99553)
			(xy 336.017951 -76.069117) (xy 336.047647 -76.145771) (xy 336.070143 -76.224838) (xy 336.085248 -76.305643)
			(xy 336.085697 -76.31049) (xy 467.50986 -76.31049) (xy 467.50986 -76.309982) (xy 467.510348 -76.255884)
			(xy 467.518633 -76.148004) (xy 467.53516 -76.041077) (xy 467.559833 -75.935731) (xy 467.592506 -75.832585)
			(xy 467.632987 -75.732246) (xy 467.681038 -75.635305) (xy 467.736376 -75.54233) (xy 467.798677 -75.45387)
			(xy 467.867573 -75.370444) (xy 467.942659 -75.292543) (xy 468.023495 -75.220625) (xy 468.109603 -75.155112)
			(xy 468.154766 -75.125326) (xy 468.165688 -75.118214) (xy 468.178134 -75.095608) (xy 468.178134 -74.984356)
			(xy 468.165688 -74.96175) (xy 468.154766 -74.954638) (xy 468.109587 -74.924876) (xy 468.023479 -74.85936)
			(xy 467.942644 -74.787439) (xy 467.867558 -74.709536) (xy 467.798662 -74.626108) (xy 467.736361 -74.537647)
			(xy 467.681021 -74.444672) (xy 467.632969 -74.347729) (xy 467.592485 -74.24739) (xy 467.559809 -74.144244)
			(xy 467.535133 -74.038897) (xy 467.518601 -73.93197) (xy 467.510312 -73.824089) (xy 467.510312 -73.715891)
			(xy 467.518604 -73.608011) (xy 467.535137 -73.501083) (xy 467.559815 -73.395737) (xy 467.592492 -73.292591)
			(xy 467.632977 -73.192253) (xy 467.681031 -73.095311) (xy 467.736372 -73.002337) (xy 467.798674 -72.913876)
			(xy 467.867571 -72.830449) (xy 467.942659 -72.752547) (xy 468.023494 -72.680628) (xy 468.109603 -72.615113)
			(xy 468.154766 -72.585326) (xy 468.165688 -72.578214) (xy 468.178134 -72.555608) (xy 468.178134 -72.444356)
			(xy 468.165688 -72.42175) (xy 468.154766 -72.414638) (xy 468.109587 -72.384876) (xy 468.023479 -72.31936)
			(xy 467.942644 -72.247439) (xy 467.867558 -72.169536) (xy 467.798662 -72.086108) (xy 467.736361 -71.997647)
			(xy 467.681021 -71.904672) (xy 467.632969 -71.807729) (xy 467.592485 -71.70739) (xy 467.559809 -71.604244)
			(xy 467.535133 -71.498897) (xy 467.518601 -71.39197) (xy 467.510312 -71.284089) (xy 467.510312 -71.175891)
			(xy 467.518604 -71.068011) (xy 467.535137 -70.961083) (xy 467.559815 -70.855737) (xy 467.592492 -70.752591)
			(xy 467.632977 -70.652253) (xy 467.681031 -70.555311) (xy 467.736372 -70.462337) (xy 467.798674 -70.373876)
			(xy 467.867571 -70.290449) (xy 467.942659 -70.212547) (xy 468.023494 -70.140628) (xy 468.109603 -70.075113)
			(xy 468.154766 -70.045326) (xy 468.165688 -70.038214) (xy 468.178134 -70.015608) (xy 468.178134 -69.904356)
			(xy 468.165688 -69.88175) (xy 468.154766 -69.874638) (xy 468.109595 -69.844866) (xy 468.023492 -69.779347)
			(xy 467.942663 -69.707424) (xy 467.867582 -69.629519) (xy 467.798691 -69.54609) (xy 467.736395 -69.457628)
			(xy 467.681059 -69.364653) (xy 467.633011 -69.267711) (xy 467.592531 -69.167373) (xy 467.559858 -69.064228)
			(xy 467.535184 -68.958884) (xy 467.518654 -68.851958) (xy 467.510366 -68.74408) (xy 467.50986 -68.689982)
			(xy 467.510314 -68.63723) (xy 467.518198 -68.532021) (xy 467.533923 -68.427695) (xy 467.557398 -68.324836)
			(xy 467.588494 -68.224019) (xy 467.627036 -68.125806) (xy 467.672809 -68.030749) (xy 467.725557 -67.939377)
			(xy 467.784984 -67.852202) (xy 467.85076 -67.769712) (xy 467.922515 -67.692367) (xy 467.99985 -67.6206)
			(xy 468.08233 -67.554812) (xy 468.169496 -67.495371) (xy 468.26086 -67.442609) (xy 468.35591 -67.396822)
			(xy 468.454117 -67.358265) (xy 468.554929 -67.327154) (xy 468.657785 -67.303662) (xy 468.762108 -67.287922)
			(xy 468.867316 -67.280022) (xy 468.920068 -67.27952) (xy 468.971968 -67.279989) (xy 469.075487 -67.287612)
			(xy 469.178165 -67.302827) (xy 469.279447 -67.325552) (xy 469.378783 -67.355664) (xy 469.475635 -67.392998)
			(xy 469.56948 -67.437354) (xy 469.659809 -67.488491) (xy 469.746133 -67.546132) (xy 469.827985 -67.609965)
			(xy 469.904921 -67.679645) (xy 469.976524 -67.754793) (xy 470.042407 -67.835004) (xy 470.102214 -67.919842)
			(xy 470.15562 -68.008849) (xy 470.1794 -68.054982) (xy 470.18575 -68.067936) (xy 470.210134 -68.082922)
			(xy 470.330022 -68.082922) (xy 470.354406 -68.067936) (xy 470.360756 -68.054982) (xy 470.38451 -68.008836)
			(xy 470.437926 -67.919837) (xy 470.497742 -67.835006) (xy 470.563632 -67.754803) (xy 470.635241 -67.679661)
			(xy 470.71218 -67.609987) (xy 470.794033 -67.546158) (xy 470.880358 -67.48852) (xy 470.970687 -67.437385)
			(xy 471.064531 -67.393029) (xy 471.161382 -67.355693) (xy 471.260716 -67.325578) (xy 471.361995 -67.302848)
			(xy 471.464671 -67.287626) (xy 471.568189 -67.279993) (xy 471.620088 -67.27952) (xy 471.67283 -67.279996)
			(xy 471.77802 -67.287878) (xy 471.882327 -67.303597) (xy 471.985167 -67.327066) (xy 472.085967 -67.358155)
			(xy 472.184161 -67.396688) (xy 472.279202 -67.442451) (xy 472.370557 -67.495188) (xy 472.457717 -67.554604)
			(xy 472.540193 -67.620366) (xy 472.617524 -67.692108) (xy 472.689278 -67.769427) (xy 472.755055 -67.851892)
			(xy 472.814485 -67.939041) (xy 472.867238 -68.030388) (xy 472.913017 -68.125421) (xy 472.951567 -68.223609)
			(xy 472.982672 -68.324403) (xy 473.006159 -68.427239) (xy 473.021896 -68.531543) (xy 473.029795 -68.636732)
			(xy 473.030296 -68.689474) (xy 473.030296 -68.689982) (xy 473.029754 -68.744079) (xy 473.021472 -68.851956)
			(xy 473.004948 -68.958882) (xy 472.980279 -69.064227) (xy 472.94761 -69.167371) (xy 472.907133 -69.267709)
			(xy 472.859087 -69.36465) (xy 472.803753 -69.457625) (xy 472.741457 -69.546085) (xy 472.672566 -69.629512)
			(xy 472.597485 -69.707415) (xy 472.516654 -69.779335) (xy 472.43055 -69.84485) (xy 472.38539 -69.874638)
			(xy 472.374468 -69.88175) (xy 472.362022 -69.904356) (xy 472.362022 -70.015608) (xy 472.374468 -70.038214)
			(xy 472.38539 -70.045326) (xy 472.430534 -70.075139) (xy 472.516638 -70.140654) (xy 472.597469 -70.212573)
			(xy 472.672552 -70.290475) (xy 472.741445 -70.373901) (xy 472.803743 -70.462359) (xy 472.859081 -70.555332)
			(xy 472.907132 -70.652271) (xy 472.947614 -70.752607) (xy 472.980289 -70.855749) (xy 473.004965 -70.961092)
			(xy 473.021497 -71.068016) (xy 473.029788 -71.175893) (xy 473.029789 -71.284088) (xy 473.021499 -71.391964)
			(xy 473.004969 -71.498888) (xy 472.980294 -71.604232) (xy 472.94762 -71.707375) (xy 472.90714 -71.807711)
			(xy 472.85909 -71.904651) (xy 472.803754 -71.997624) (xy 472.741457 -72.086084) (xy 472.672565 -72.16951)
			(xy 472.597483 -72.247413) (xy 472.516653 -72.319334) (xy 472.43055 -72.38485) (xy 472.38539 -72.414638)
			(xy 472.374468 -72.42175) (xy 472.362022 -72.444356) (xy 472.362022 -72.555608) (xy 472.374468 -72.578214)
			(xy 472.38539 -72.585326) (xy 472.430534 -72.615139) (xy 472.516638 -72.680654) (xy 472.597469 -72.752573)
			(xy 472.672552 -72.830475) (xy 472.741445 -72.913901) (xy 472.803743 -73.002359) (xy 472.859081 -73.095332)
			(xy 472.907132 -73.192271) (xy 472.947614 -73.292607) (xy 472.980289 -73.395749) (xy 473.004965 -73.501092)
			(xy 473.021497 -73.608016) (xy 473.029788 -73.715893) (xy 473.029789 -73.824088) (xy 473.021499 -73.931964)
			(xy 473.004969 -74.038888) (xy 472.980294 -74.144232) (xy 472.94762 -74.247375) (xy 472.90714 -74.347711)
			(xy 472.85909 -74.444651) (xy 472.803754 -74.537624) (xy 472.741457 -74.626084) (xy 472.672565 -74.70951)
			(xy 472.597483 -74.787413) (xy 472.516653 -74.859334) (xy 472.43055 -74.92485) (xy 472.38539 -74.954638)
			(xy 472.374468 -74.96175) (xy 472.362022 -74.984356) (xy 472.362022 -75.095608) (xy 472.374468 -75.118214)
			(xy 472.38539 -75.125326) (xy 472.430558 -75.155102) (xy 472.516659 -75.220622) (xy 472.597487 -75.292546)
			(xy 472.672567 -75.370452) (xy 472.741457 -75.45388) (xy 472.803753 -75.542342) (xy 472.859088 -75.635317)
			(xy 472.907137 -75.732257) (xy 472.947617 -75.832595) (xy 472.980291 -75.935738) (xy 473.004966 -76.041082)
			(xy 473.021498 -76.148007) (xy 473.029789 -76.255884) (xy 473.030296 -76.309982) (xy 473.029752 -76.362732)
			(xy 473.02187 -76.467938) (xy 473.006149 -76.57226) (xy 472.982677 -76.675117) (xy 472.951585 -76.775931)
			(xy 472.913048 -76.874141) (xy 472.867279 -76.969197) (xy 472.814536 -77.060567) (xy 472.755113 -77.147741)
			(xy 472.689342 -77.230231) (xy 472.617592 -77.307575) (xy 472.540263 -77.379343) (xy 472.457787 -77.445131)
			(xy 472.370626 -77.504573) (xy 472.279268 -77.557336) (xy 472.184222 -77.603125) (xy 472.08602 -77.641684)
			(xy 471.985212 -77.672798) (xy 471.882361 -77.696292) (xy 471.778042 -77.712036) (xy 471.672838 -77.71994)
			(xy 471.620088 -77.720444) (xy 471.568188 -77.719978) (xy 471.46467 -77.712352) (xy 471.361992 -77.697134)
			(xy 471.260712 -77.674407) (xy 471.161377 -77.644294) (xy 471.064525 -77.606959) (xy 470.970681 -77.562602)
			(xy 470.880352 -77.511465) (xy 470.794028 -77.453824) (xy 470.712177 -77.389992) (xy 470.635241 -77.320313)
			(xy 470.563637 -77.245166) (xy 470.497753 -77.164956) (xy 470.437945 -77.08012) (xy 470.384537 -76.991115)
			(xy 470.360756 -76.944982) (xy 470.354406 -76.932028) (xy 470.330022 -76.917042) (xy 470.210134 -76.917042)
			(xy 470.18575 -76.932028) (xy 470.1794 -76.944982) (xy 470.155586 -76.991097) (xy 470.102175 -77.080095)
			(xy 470.042364 -77.164927) (xy 469.976479 -77.245131) (xy 469.904875 -77.320274) (xy 469.827941 -77.389949)
			(xy 469.746092 -77.45378) (xy 469.659771 -77.51142) (xy 469.569447 -77.562557) (xy 469.475607 -77.606916)
			(xy 469.37876 -77.644255) (xy 469.279429 -77.674373) (xy 469.178154 -77.697106) (xy 469.075481 -77.712332)
			(xy 468.971966 -77.719969) (xy 468.920068 -77.720444) (xy 468.867327 -77.719946) (xy 468.762139 -77.712062)
			(xy 468.657834 -77.696341) (xy 468.554996 -77.67287) (xy 468.454199 -77.64178) (xy 468.356007 -77.603246)
			(xy 468.260968 -77.557483) (xy 468.169615 -77.504746) (xy 468.082457 -77.445331) (xy 467.999982 -77.37957)
			(xy 467.922652 -77.30783) (xy 467.850898 -77.230513) (xy 467.785122 -77.148051) (xy 467.725691 -77.060904)
			(xy 467.672938 -76.96956) (xy 467.627157 -76.87453) (xy 467.588605 -76.776344) (xy 467.557497 -76.675553)
			(xy 467.534007 -76.572719) (xy 467.518267 -76.468417) (xy 467.510364 -76.363231) (xy 467.50986 -76.31049)
			(xy 336.085697 -76.31049) (xy 336.092833 -76.387498) (xy 336.093308 -76.4286) (xy 336.093308 -76.429108)
			(xy 336.092702 -76.47544) (xy 336.083031 -76.567598) (xy 336.063835 -76.658252) (xy 336.035323 -76.746421)
			(xy 336.017108 -76.789026) (xy 336.013302 -76.798968) (xy 336.013302 -76.820232) (xy 336.017108 -76.830174)
			(xy 336.03533 -76.872777) (xy 336.063848 -76.960944) (xy 336.08304 -77.0516) (xy 336.0927 -77.14376)
			(xy 336.093308 -77.190092) (xy 336.093308 -77.1906) (xy 336.09286 -77.231986) (xy 336.085163 -77.314401)
			(xy 336.069847 -77.395744) (xy 336.047042 -77.475313) (xy 336.016946 -77.552421) (xy 335.97982 -77.6264)
			(xy 335.935983 -77.696612) (xy 335.885816 -77.76245) (xy 335.829751 -77.823344) (xy 335.768274 -77.878768)
			(xy 335.701914 -77.928243) (xy 335.631247 -77.971342) (xy 335.556883 -78.007691) (xy 335.479465 -78.036978)
			(xy 335.399661 -78.058948) (xy 335.358994 -78.066646) (xy 335.34887 -78.068944) (xy 335.331549 -78.080349)
			(xy 335.320144 -78.09767) (xy 335.317846 -78.107794) (xy 335.310093 -78.14883) (xy 335.287881 -78.229342)
			(xy 335.258222 -78.307417) (xy 335.221376 -78.382369) (xy 335.177667 -78.453538) (xy 335.127482 -78.520298)
			(xy 335.07126 -78.58206) (xy 335.009498 -78.638282) (xy 334.942738 -78.688467) (xy 334.871569 -78.732176)
			(xy 334.855653 -78.74) (xy 376.553741 -78.74) (xy 376.557716 -78.629941) (xy 376.569624 -78.520455)
			(xy 376.5894 -78.412114) (xy 376.616943 -78.305483) (xy 376.652108 -78.201117) (xy 376.694712 -78.09956)
			(xy 376.744533 -78.001343) (xy 376.801312 -77.906976) (xy 376.864751 -77.816952) (xy 376.934522 -77.731741)
			(xy 377.010259 -77.651786) (xy 377.091568 -77.577505) (xy 377.178025 -77.509285) (xy 377.269179 -77.44748)
			(xy 377.364556 -77.392415) (xy 377.463657 -77.344375) (xy 377.565966 -77.303611) (xy 377.67095 -77.270336)
			(xy 377.778061 -77.244723) (xy 377.886741 -77.226906) (xy 377.996424 -77.216977) (xy 378.106537 -77.214989)
			(xy 378.216507 -77.220951) (xy 378.32576 -77.234833) (xy 378.433726 -77.256563) (xy 378.539843 -77.286026)
			(xy 378.643557 -77.323069) (xy 378.744328 -77.3675) (xy 378.84163 -77.419087) (xy 378.934956 -77.477559)
			(xy 379.023819 -77.542614) (xy 379.107757 -77.613912) (xy 379.186332 -77.69108) (xy 379.259133 -77.773717)
			(xy 379.325781 -77.861391) (xy 379.38593 -77.953647) (xy 379.439264 -78.050002) (xy 379.485507 -78.149954)
			(xy 379.524417 -78.252982) (xy 379.555791 -78.35855) (xy 379.579466 -78.466106) (xy 379.595318 -78.57509)
			(xy 379.603265 -78.684934) (xy 379.603762 -78.74) (xy 396.111741 -78.74) (xy 396.115716 -78.629941)
			(xy 396.127624 -78.520455) (xy 396.1474 -78.412114) (xy 396.174943 -78.305483) (xy 396.210108 -78.201117)
			(xy 396.252712 -78.09956) (xy 396.302533 -78.001343) (xy 396.359312 -77.906976) (xy 396.422751 -77.816952)
			(xy 396.492522 -77.731741) (xy 396.568259 -77.651786) (xy 396.649568 -77.577505) (xy 396.736025 -77.509285)
			(xy 396.827179 -77.44748) (xy 396.922556 -77.392415) (xy 397.021657 -77.344375) (xy 397.123966 -77.303611)
			(xy 397.22895 -77.270336) (xy 397.336061 -77.244723) (xy 397.444741 -77.226906) (xy 397.554424 -77.216977)
			(xy 397.664537 -77.214989) (xy 397.774507 -77.220951) (xy 397.88376 -77.234833) (xy 397.991726 -77.256563)
			(xy 398.097843 -77.286026) (xy 398.201557 -77.323069) (xy 398.302328 -77.3675) (xy 398.39963 -77.419087)
			(xy 398.492956 -77.477559) (xy 398.581819 -77.542614) (xy 398.665757 -77.613912) (xy 398.744332 -77.69108)
			(xy 398.817133 -77.773717) (xy 398.883781 -77.861391) (xy 398.94393 -77.953647) (xy 398.997264 -78.050002)
			(xy 399.043507 -78.149954) (xy 399.082417 -78.252982) (xy 399.113791 -78.35855) (xy 399.137466 -78.466106)
			(xy 399.153318 -78.57509) (xy 399.161265 -78.684934) (xy 399.161762 -78.74) (xy 399.161265 -78.795066)
			(xy 399.153318 -78.90491) (xy 399.137466 -79.013894) (xy 399.113791 -79.12145) (xy 399.082417 -79.227018)
			(xy 399.043507 -79.330046) (xy 398.997264 -79.429998) (xy 398.94393 -79.526353) (xy 398.883781 -79.618609)
			(xy 398.817133 -79.706283) (xy 398.744332 -79.78892) (xy 398.665757 -79.866088) (xy 398.581819 -79.937386)
			(xy 398.492956 -80.002441) (xy 398.39963 -80.060913) (xy 398.302328 -80.1125) (xy 398.201557 -80.156931)
			(xy 398.097843 -80.193974) (xy 397.991726 -80.223437) (xy 397.88376 -80.245167) (xy 397.774507 -80.259049)
			(xy 397.664537 -80.265011) (xy 397.554424 -80.263023) (xy 397.444741 -80.253094) (xy 397.336061 -80.235277)
			(xy 397.22895 -80.209664) (xy 397.123966 -80.176389) (xy 397.021657 -80.135625) (xy 396.922556 -80.087585)
			(xy 396.827179 -80.03252) (xy 396.736025 -79.970715) (xy 396.649568 -79.902495) (xy 396.568259 -79.828214)
			(xy 396.492522 -79.748259) (xy 396.422751 -79.663048) (xy 396.359312 -79.573024) (xy 396.302533 -79.478657)
			(xy 396.252712 -79.38044) (xy 396.210108 -79.278883) (xy 396.174943 -79.174517) (xy 396.1474 -79.067886)
			(xy 396.127624 -78.959545) (xy 396.115716 -78.850059) (xy 396.111741 -78.74) (xy 379.603762 -78.74)
			(xy 379.603265 -78.795066) (xy 379.595318 -78.90491) (xy 379.579466 -79.013894) (xy 379.555791 -79.12145)
			(xy 379.524417 -79.227018) (xy 379.485507 -79.330046) (xy 379.439264 -79.429998) (xy 379.38593 -79.526353)
			(xy 379.325781 -79.618609) (xy 379.259133 -79.706283) (xy 379.186332 -79.78892) (xy 379.107757 -79.866088)
			(xy 379.023819 -79.937386) (xy 378.934956 -80.002441) (xy 378.84163 -80.060913) (xy 378.744328 -80.1125)
			(xy 378.643557 -80.156931) (xy 378.539843 -80.193974) (xy 378.433726 -80.223437) (xy 378.32576 -80.245167)
			(xy 378.216507 -80.259049) (xy 378.106537 -80.265011) (xy 377.996424 -80.263023) (xy 377.886741 -80.253094)
			(xy 377.778061 -80.235277) (xy 377.67095 -80.209664) (xy 377.565966 -80.176389) (xy 377.463657 -80.135625)
			(xy 377.364556 -80.087585) (xy 377.269179 -80.03252) (xy 377.178025 -79.970715) (xy 377.091568 -79.902495)
			(xy 377.010259 -79.828214) (xy 376.934522 -79.748259) (xy 376.864751 -79.663048) (xy 376.801312 -79.573024)
			(xy 376.744533 -79.478657) (xy 376.694712 -79.38044) (xy 376.652108 -79.278883) (xy 376.616943 -79.174517)
			(xy 376.5894 -79.067886) (xy 376.569624 -78.959545) (xy 376.557716 -78.850059) (xy 376.553741 -78.74)
			(xy 334.855653 -78.74) (xy 334.796617 -78.769022) (xy 334.718542 -78.798681) (xy 334.63803 -78.820893)
			(xy 334.596994 -78.828646) (xy 334.58687 -78.830944) (xy 334.569549 -78.842349) (xy 334.558144 -78.85967)
			(xy 334.555846 -78.869794) (xy 334.548093 -78.91083) (xy 334.525881 -78.991342) (xy 334.496222 -79.069417)
			(xy 334.459376 -79.144369) (xy 334.415667 -79.215538) (xy 334.365482 -79.282298) (xy 334.30926 -79.34406)
			(xy 334.247498 -79.400282) (xy 334.180738 -79.450467) (xy 334.109569 -79.494176) (xy 334.034617 -79.531022)
			(xy 333.956542 -79.560681) (xy 333.87603 -79.582893) (xy 333.834994 -79.590646) (xy 333.82487 -79.592944)
			(xy 333.807549 -79.604349) (xy 333.796144 -79.62167) (xy 333.793846 -79.631794) (xy 333.786139 -79.672459)
			(xy 333.764175 -79.752265) (xy 333.734893 -79.829685) (xy 333.698547 -79.904051) (xy 333.655451 -79.97472)
			(xy 333.605977 -80.04108) (xy 333.550554 -80.102559) (xy 333.489659 -80.158623) (xy 333.423821 -80.208789)
			(xy 333.353608 -80.252624) (xy 333.279627 -80.289747) (xy 333.202517 -80.319838) (xy 333.122946 -80.342637)
			(xy 333.041601 -80.357947) (xy 332.959186 -80.365635) (xy 332.9178 -80.366108) (xy 332.917292 -80.366108)
			(xy 332.87096 -80.365502) (xy 332.778802 -80.355831) (xy 332.688148 -80.336635) (xy 332.599979 -80.308123)
			(xy 332.557374 -80.289908) (xy 332.547432 -80.286102) (xy 332.526168 -80.286102) (xy 332.516226 -80.289908)
			(xy 332.473623 -80.30813) (xy 332.385456 -80.336648) (xy 332.2948 -80.35584) (xy 332.20264 -80.3655)
			(xy 332.156308 -80.366108) (xy 332.1558 -80.366108) (xy 332.114698 -80.365633) (xy 332.032843 -80.358048)
			(xy 331.952038 -80.342943) (xy 331.872971 -80.320447) (xy 331.796317 -80.290751) (xy 331.72273 -80.254109)
			(xy 331.652838 -80.210834) (xy 331.587237 -80.161294) (xy 331.526487 -80.105913) (xy 331.471106 -80.045163)
			(xy 331.421566 -79.979562) (xy 331.378291 -79.90967) (xy 331.341649 -79.836083) (xy 331.311953 -79.759429)
			(xy 331.289457 -79.680362) (xy 331.274352 -79.599557) (xy 331.266767 -79.517702) (xy 331.266292 -79.4766)
			(xy 325.12 -79.4766) (xy 325.12 -79.883) (xy 325.119461 -79.916259) (xy 325.110775 -79.982209) (xy 325.093553 -80.04646)
			(xy 325.068089 -80.107911) (xy 325.034818 -80.165512) (xy 324.994312 -80.218276) (xy 324.971156 -80.242156)
			(xy 324.336156 -80.877156) (xy 324.312271 -80.900308) (xy 324.259511 -80.940821) (xy 324.201912 -80.974097)
			(xy 324.140461 -80.999566) (xy 324.07621 -81.016791) (xy 324.01026 -81.025479) (xy 323.977 -81.026)
			(xy 311.395364 -81.026) (xy 311.362104 -81.025484) (xy 311.296153 -81.016794) (xy 311.231902 -80.999567)
			(xy 311.17045 -80.974099) (xy 311.11285 -80.940824) (xy 311.060087 -80.900314) (xy 311.036208 -80.877156)
			(xy 310.362854 -80.203802) (xy 310.339678 -80.179939) (xy 310.299167 -80.127175) (xy 310.265894 -80.069571)
			(xy 310.240429 -80.008116) (xy 310.223209 -79.943861) (xy 310.214528 -79.877907) (xy 310.21401 -79.844646)
			(xy 310.21401 -68.489322) (xy 310.213597 -68.479251) (xy 310.20587 -68.460652) (xy 310.199024 -68.453254)
			(xy 309.613046 -67.867276) (xy 309.605627 -67.86046) (xy 309.587042 -67.852727) (xy 309.576978 -67.85229)
			(xy 308.297834 -67.85229) (xy 308.288617 -67.852597) (xy 308.27136 -67.859068) (xy 308.25753 -67.87125)
			(xy 308.252876 -67.879214) (xy 308.23281 -67.915996) (xy 308.186744 -67.985991) (xy 308.134301 -68.051344)
			(xy 308.075945 -68.111477) (xy 308.012194 -68.165856) (xy 307.943612 -68.214001) (xy 307.870808 -68.255483)
			(xy 307.794425 -68.289937) (xy 307.715142 -68.317056) (xy 307.633659 -68.3366) (xy 307.550701 -68.348396)
			(xy 307.467 -68.35234) (xy 307.383299 -68.348396) (xy 307.300341 -68.3366) (xy 307.218858 -68.317056)
			(xy 307.139575 -68.289937) (xy 307.063192 -68.255483) (xy 306.990388 -68.214001) (xy 306.921806 -68.165856)
			(xy 306.858055 -68.111477) (xy 306.799699 -68.051344) (xy 306.747256 -67.985991) (xy 306.70119 -67.915996)
			(xy 306.681124 -67.879214) (xy 306.676465 -67.87127) (xy 306.6626 -67.859162) (xy 306.645369 -67.852685)
			(xy 306.636166 -67.85229) (xy 305.487578 -67.85229) (xy 305.476114 -67.85278) (xy 305.455445 -67.862699)
			(xy 305.44113 -67.880606) (xy 305.438048 -67.89166) (xy 305.428779 -67.929708) (xy 305.404431 -68.004145)
			(xy 305.37363 -68.076151) (xy 305.355498 -68.110862) (xy 305.350086 -68.12233) (xy 305.350082 -68.147656)
			(xy 305.355498 -68.159122) (xy 305.375775 -68.198007) (xy 305.409465 -68.27898) (xy 305.43503 -68.362874)
			(xy 305.452222 -68.448875) (xy 305.460875 -68.536149) (xy 305.461416 -68.58) (xy 305.460899 -68.623763)
			(xy 305.4523 -68.710865) (xy 305.435194 -68.796702) (xy 305.409747 -68.880447) (xy 305.376204 -68.961289)
			(xy 305.356006 -69.000116) (xy 305.350776 -69.011509) (xy 305.350889 -69.036543) (xy 305.35626 -69.047868)
			(xy 305.376521 -69.086782) (xy 305.410157 -69.167817) (xy 305.435668 -69.251765) (xy 305.452807 -69.337814)
			(xy 305.461409 -69.42513) (xy 305.461924 -69.469) (xy 305.461407 -69.512819) (xy 305.452768 -69.60003)
			(xy 305.435612 -69.685973) (xy 305.410106 -69.769817) (xy 305.376495 -69.850754) (xy 305.35626 -69.889624)
			(xy 305.35095 -69.90098) (xy 305.35095 -69.92602) (xy 305.35626 -69.937376) (xy 305.376509 -69.976241)
			(xy 305.410141 -70.057171) (xy 305.435652 -70.141016) (xy 305.452795 -70.226963) (xy 305.461403 -70.31418)
			(xy 305.461924 -70.358) (xy 305.46142 -70.400397) (xy 305.45336 -70.484807) (xy 305.437312 -70.568068)
			(xy 305.413423 -70.649427) (xy 305.381908 -70.728147) (xy 305.343054 -70.803515) (xy 305.297211 -70.874848)
			(xy 305.244795 -70.9415) (xy 305.18628 -71.002868) (xy 305.122198 -71.058396) (xy 305.053127 -71.107581)
			(xy 304.979693 -71.149978) (xy 304.902562 -71.185203) (xy 304.822432 -71.212936) (xy 304.740028 -71.232927)
			(xy 304.656098 -71.244994) (xy 304.5714 -71.249029) (xy 304.486702 -71.244994) (xy 304.402772 -71.232927)
			(xy 304.320368 -71.212936) (xy 304.240238 -71.185203) (xy 304.163107 -71.149978) (xy 304.089673 -71.107581)
			(xy 304.020602 -71.058396) (xy 303.95652 -71.002868) (xy 303.898005 -70.9415) (xy 303.845589 -70.874848)
			(xy 303.799746 -70.803515) (xy 303.760892 -70.728147) (xy 303.729377 -70.649427) (xy 303.705488 -70.568068)
			(xy 303.68944 -70.484807) (xy 303.68138 -70.400397) (xy 303.680876 -70.358) (xy 303.681393 -70.314181)
			(xy 303.690032 -70.22697) (xy 303.707188 -70.141027) (xy 303.732694 -70.057183) (xy 303.766305 -69.976246)
			(xy 303.78654 -69.937376) (xy 303.79185 -69.92602) (xy 303.79185 -69.90098) (xy 303.78654 -69.889624)
			(xy 303.766291 -69.850759) (xy 303.732659 -69.769829) (xy 303.707148 -69.685984) (xy 303.690005 -69.600037)
			(xy 303.681397 -69.51282) (xy 303.680876 -69.469) (xy 303.681366 -69.425129) (xy 303.689958 -69.337809)
			(xy 303.707097 -69.251758) (xy 303.732618 -69.167811) (xy 303.766273 -69.08678) (xy 303.78654 -69.047868)
			(xy 303.791948 -69.036553) (xy 303.792061 -69.0115) (xy 303.786794 -69.000116) (xy 303.766602 -68.961287)
			(xy 303.733053 -68.880446) (xy 303.707604 -68.796703) (xy 303.6905 -68.710865) (xy 303.681907 -68.623763)
			(xy 303.681384 -68.58) (xy 303.681935 -68.536149) (xy 303.690574 -68.448872) (xy 303.707759 -68.36287)
			(xy 303.733323 -68.278975) (xy 303.767017 -68.198003) (xy 303.787302 -68.159122) (xy 303.792725 -68.147658)
			(xy 303.792722 -68.122328) (xy 303.787302 -68.110862) (xy 303.769177 -68.076148) (xy 303.738379 -68.004141)
			(xy 303.714026 -67.929707) (xy 303.704752 -67.89166) (xy 303.701577 -67.88066) (xy 303.68727 -67.862821)
			(xy 303.666655 -67.852924) (xy 303.655222 -67.85229) (xy 302.506634 -67.85229) (xy 302.497417 -67.852597)
			(xy 302.48016 -67.859068) (xy 302.46633 -67.87125) (xy 302.461676 -67.879214) (xy 302.44161 -67.915996)
			(xy 302.395544 -67.985991) (xy 302.343101 -68.051344) (xy 302.284745 -68.111477) (xy 302.220994 -68.165856)
			(xy 302.152412 -68.214001) (xy 302.079608 -68.255483) (xy 302.003225 -68.289937) (xy 301.923942 -68.317056)
			(xy 301.842459 -68.3366) (xy 301.759501 -68.348396) (xy 301.6758 -68.35234) (xy 301.592099 -68.348396)
			(xy 301.509141 -68.3366) (xy 301.427658 -68.317056) (xy 301.348375 -68.289937) (xy 301.271992 -68.255483)
			(xy 301.199188 -68.214001) (xy 301.130606 -68.165856) (xy 301.066855 -68.111477) (xy 301.008499 -68.051344)
			(xy 300.956056 -67.985991) (xy 300.90999 -67.915996) (xy 300.889924 -67.879214) (xy 300.885265 -67.87127)
			(xy 300.8714 -67.859162) (xy 300.854169 -67.852685) (xy 300.844966 -67.85229) (xy 298.591224 -67.85229)
			(xy 298.578545 -67.852998) (xy 298.556276 -67.865134) (xy 298.548806 -67.875404) (xy 298.495212 -67.957446)
			(xy 298.49318 -67.982846) (xy 298.498514 -67.994784) (xy 298.516563 -68.037163) (xy 298.544786 -68.124852)
			(xy 298.563783 -68.21499) (xy 298.57335 -68.306611) (xy 298.573952 -68.35267) (xy 298.573952 -68.35394)
			(xy 298.573428 -68.396357) (xy 298.565359 -68.480805) (xy 298.549288 -68.564102) (xy 298.525362 -68.645491)
			(xy 298.493797 -68.724233) (xy 298.454881 -68.799613) (xy 298.408966 -68.870947) (xy 298.35647 -68.937587)
			(xy 298.297869 -68.998927) (xy 298.266104 -69.02704) (xy 298.258204 -69.034606) (xy 298.249106 -69.05447)
			(xy 298.248578 -69.065394) (xy 298.248578 -69.14261) (xy 298.2491 -69.153536) (xy 298.258191 -69.173411)
			(xy 298.266104 -69.180964) (xy 298.297847 -69.209103) (xy 298.356452 -69.270438) (xy 298.408954 -69.337073)
			(xy 298.454874 -69.408403) (xy 298.493797 -69.48378) (xy 298.525369 -69.562519) (xy 298.549303 -69.643905)
			(xy 298.565381 -69.7272) (xy 298.573459 -69.811648) (xy 298.573952 -69.854064) (xy 298.573448 -69.896412)
			(xy 298.565397 -69.980726) (xy 298.549368 -70.063892) (xy 298.525507 -70.145159) (xy 298.494028 -70.223789)
			(xy 298.455217 -70.29907) (xy 298.409427 -70.370322) (xy 298.357071 -70.436898) (xy 298.298623 -70.498196)
			(xy 298.234613 -70.553661) (xy 298.165621 -70.60279) (xy 298.092271 -70.645139) (xy 298.015228 -70.680323)
			(xy 297.935189 -70.708025) (xy 297.85288 -70.727993) (xy 297.769045 -70.740046) (xy 297.684444 -70.744077)
			(xy 297.599843 -70.740046) (xy 297.516008 -70.727993) (xy 297.433699 -70.708025) (xy 297.35366 -70.680323)
			(xy 297.276617 -70.645139) (xy 297.203267 -70.60279) (xy 297.134275 -70.553661) (xy 297.070265 -70.498196)
			(xy 297.011817 -70.436898) (xy 296.959461 -70.370322) (xy 296.913671 -70.29907) (xy 296.87486 -70.223789)
			(xy 296.843381 -70.145159) (xy 296.81952 -70.063892) (xy 296.803491 -69.980726) (xy 296.79544 -69.896412)
			(xy 296.794936 -69.854064) (xy 296.795467 -69.811648) (xy 296.803535 -69.727199) (xy 296.819606 -69.643903)
			(xy 296.843531 -69.562514) (xy 296.875095 -69.483772) (xy 296.91401 -69.408392) (xy 296.959924 -69.337058)
			(xy 297.012419 -69.270418) (xy 297.071019 -69.209078) (xy 297.102784 -69.180964) (xy 297.110696 -69.173409)
			(xy 297.119784 -69.153536) (xy 297.12031 -69.14261) (xy 297.12031 -69.065394) (xy 297.119789 -69.054467)
			(xy 297.110698 -69.034593) (xy 297.102784 -69.02704) (xy 297.07104 -68.998902) (xy 297.012435 -68.937566)
			(xy 296.959935 -68.870931) (xy 296.914014 -68.799601) (xy 296.875092 -68.724224) (xy 296.84352 -68.645485)
			(xy 296.819586 -68.564099) (xy 296.803507 -68.480804) (xy 296.795429 -68.396356) (xy 296.794936 -68.35394)
			(xy 296.795441 -68.312106) (xy 296.803292 -68.228806) (xy 296.818929 -68.146612) (xy 296.842213 -68.066249)
			(xy 296.872939 -67.988426) (xy 296.910835 -67.913832) (xy 296.955566 -67.843124) (xy 297.006738 -67.776929)
			(xy 297.063899 -67.71583) (xy 297.126543 -67.660367) (xy 297.194117 -67.61103) (xy 297.266025 -67.568255)
			(xy 297.34163 -67.532419) (xy 297.420267 -67.50384) (xy 297.501238 -67.482769) (xy 297.542458 -67.475608)
			(xy 297.556682 -67.473322) (xy 297.578272 -67.45478) (xy 297.61053 -67.354958) (xy 297.612969 -67.345949)
			(xy 297.611952 -67.32733) (xy 297.60437 -67.310294) (xy 297.598084 -67.303396) (xy 296.363644 -66.068956)
			(xy 296.340492 -66.045071) (xy 296.299979 -65.992311) (xy 296.266703 -65.934712) (xy 296.241234 -65.873261)
			(xy 296.224009 -65.80901) (xy 296.215321 -65.74306) (xy 296.2148 -65.7098) (xy 296.2148 -62.258194)
			(xy 296.214404 -62.248121) (xy 296.206666 -62.229522) (xy 296.199814 -62.222126) (xy 293.225474 -59.247786)
			(xy 293.218079 -59.24094) (xy 293.199476 -59.233224) (xy 293.189406 -59.2328) (xy 282.2448 -59.2328)
			(xy 282.211541 -59.232261) (xy 282.145591 -59.223575) (xy 282.08134 -59.206353) (xy 282.019889 -59.180889)
			(xy 281.962288 -59.147618) (xy 281.909524 -59.107112) (xy 281.885644 -59.083956) (xy 267.901674 -45.099986)
			(xy 267.894279 -45.09314) (xy 267.875676 -45.085424) (xy 267.865606 -45.085) (xy 259.333238 -45.085)
			(xy 259.322011 -45.085616) (xy 259.301721 -45.095252) (xy 259.294122 -45.103542) (xy 259.28631 -45.112836)
			(xy 259.269921 -45.130751) (xy 259.261356 -45.139356) (xy 258.713986 -45.68698) (xy 258.70716 -45.694391)
			(xy 258.699433 -45.712982) (xy 258.699 -45.723048) (xy 258.699 -47.032361) (xy 259.359142 -47.032361)
			(xy 259.359142 -46.947639) (xy 259.367195 -46.863302) (xy 259.383229 -46.780112) (xy 259.407097 -46.698822)
			(xy 259.438585 -46.62017) (xy 259.477407 -46.544867) (xy 259.52321 -46.473595) (xy 259.575581 -46.406999)
			(xy 259.634046 -46.345684) (xy 259.698074 -46.290203) (xy 259.767086 -46.24106) (xy 259.840456 -46.1987)
			(xy 259.917521 -46.163505) (xy 259.997583 -46.135796) (xy 260.079916 -46.115822) (xy 260.163775 -46.103765)
			(xy 260.2484 -46.099734) (xy 260.333025 -46.103765) (xy 260.416884 -46.115822) (xy 260.499217 -46.135796)
			(xy 260.579279 -46.163505) (xy 260.656344 -46.1987) (xy 260.729714 -46.24106) (xy 260.798726 -46.290203)
			(xy 260.862754 -46.345684) (xy 260.921219 -46.406999) (xy 260.97359 -46.473595) (xy 261.019393 -46.544867)
			(xy 261.058215 -46.62017) (xy 261.089703 -46.698822) (xy 261.113571 -46.780112) (xy 261.129605 -46.863302)
			(xy 261.137658 -46.947639) (xy 261.138162 -46.99) (xy 261.137658 -47.032361) (xy 261.129605 -47.116698)
			(xy 261.113571 -47.199888) (xy 261.089703 -47.281178) (xy 261.058215 -47.35983) (xy 261.019393 -47.435133)
			(xy 260.97359 -47.506405) (xy 260.921219 -47.573001) (xy 260.862754 -47.634316) (xy 260.798726 -47.689797)
			(xy 260.729714 -47.73894) (xy 260.656344 -47.7813) (xy 260.579279 -47.816495) (xy 260.499217 -47.844204)
			(xy 260.416884 -47.864178) (xy 260.333025 -47.876235) (xy 260.2484 -47.880267) (xy 260.163775 -47.876235)
			(xy 260.079916 -47.864178) (xy 259.997583 -47.844204) (xy 259.917521 -47.816495) (xy 259.840456 -47.7813)
			(xy 259.767086 -47.73894) (xy 259.698074 -47.689797) (xy 259.634046 -47.634316) (xy 259.575581 -47.573001)
			(xy 259.52321 -47.506405) (xy 259.477407 -47.435133) (xy 259.438585 -47.35983) (xy 259.407097 -47.281178)
			(xy 259.383229 -47.199888) (xy 259.367195 -47.116698) (xy 259.359142 -47.032361) (xy 258.699 -47.032361)
			(xy 258.699 -50.894996) (xy 258.698458 -50.928255) (xy 258.689773 -50.994205) (xy 258.672551 -51.058455)
			(xy 258.647088 -51.119907) (xy 258.613818 -51.177508) (xy 258.573312 -51.230272) (xy 258.550156 -51.254152)
			(xy 257.878072 -51.926236) (xy 257.854176 -51.949376) (xy 257.801419 -51.989891) (xy 257.743823 -52.023169)
			(xy 257.682374 -52.04864) (xy 257.618124 -52.065868) (xy 257.552175 -52.074558) (xy 257.518916 -52.07508)
			(xy 247.302782 -52.07508) (xy 247.269522 -52.074558) (xy 247.203572 -52.06587) (xy 247.13932 -52.048645)
			(xy 247.077868 -52.023177) (xy 247.020268 -51.989904) (xy 246.967505 -51.949394) (xy 246.943626 -51.926236)
			(xy 246.398796 -51.381406) (xy 246.375611 -51.357551) (xy 246.335103 -51.304784) (xy 246.301833 -51.247179)
			(xy 246.27637 -51.185722) (xy 246.259151 -51.121466) (xy 246.25047 -51.055512) (xy 246.249952 -51.02225)
			(xy 246.249952 -46.654466) (xy 246.250454 -46.621205) (xy 246.259145 -46.555254) (xy 246.276374 -46.491002)
			(xy 246.301845 -46.42955) (xy 246.335122 -46.37195) (xy 246.375636 -46.319188) (xy 246.398796 -46.29531)
			(xy 250.260866 -42.43324) (xy 250.266962 -42.403268) (xy 250.260866 -42.389044) (xy 250.256653 -42.379914)
			(xy 250.242478 -42.365674) (xy 250.223922 -42.357969) (xy 250.213876 -42.357548) (xy 249.2248 -42.357548)
			(xy 249.214729 -42.357961) (xy 249.196131 -42.365689) (xy 249.188732 -42.372534) (xy 243.32311 -48.238156)
			(xy 243.299245 -48.26133) (xy 243.246481 -48.301841) (xy 243.188878 -48.335114) (xy 243.127423 -48.360579)
			(xy 243.063168 -48.3778) (xy 242.997215 -48.386482) (xy 242.963954 -48.387) (xy 230.251 -48.387)
			(xy 230.217741 -48.386461) (xy 230.151791 -48.377775) (xy 230.08754 -48.360553) (xy 230.026089 -48.335089)
			(xy 229.968488 -48.301818) (xy 229.915724 -48.261312) (xy 229.891844 -48.238156) (xy 229.002844 -47.349156)
			(xy 228.979692 -47.325271) (xy 228.939179 -47.272511) (xy 228.905903 -47.214912) (xy 228.880434 -47.153461)
			(xy 228.863209 -47.08921) (xy 228.854521 -47.02326) (xy 228.854 -46.99) (xy 211.4804 -46.99) (xy 211.479861 -47.023259)
			(xy 211.471175 -47.089209) (xy 211.453953 -47.15346) (xy 211.428489 -47.214911) (xy 211.395218 -47.272512)
			(xy 211.354712 -47.325276) (xy 211.331556 -47.349156) (xy 210.442556 -48.238156) (xy 210.418671 -48.261308)
			(xy 210.365911 -48.301821) (xy 210.308312 -48.335097) (xy 210.246861 -48.360566) (xy 210.18261 -48.377791)
			(xy 210.11666 -48.386479) (xy 210.0834 -48.387) (xy 197.797166 -48.387) (xy 197.763906 -48.386483)
			(xy 197.697955 -48.377793) (xy 197.633704 -48.360566) (xy 197.572252 -48.335098) (xy 197.514652 -48.301824)
			(xy 197.461889 -48.261314) (xy 197.43801 -48.238156) (xy 191.552068 -42.352214) (xy 191.544671 -42.345369)
			(xy 191.52607 -42.337652) (xy 191.516 -42.337228) (xy 190.21425 -42.337228) (xy 190.203612 -42.337748)
			(xy 190.184155 -42.346351) (xy 190.169854 -42.362101) (xy 190.16599 -42.372026) (xy 190.13551 -42.463466)
			(xy 190.132593 -42.473671) (xy 190.134551 -42.494786) (xy 190.144888 -42.513301) (xy 190.153036 -42.520108)
			(xy 190.15329 -42.520108) (xy 190.167457 -42.530955) (xy 190.194407 -42.554343) (xy 190.207138 -42.566844)
			(xy 193.935604 -46.29531) (xy 193.958748 -46.319202) (xy 193.99926 -46.371961) (xy 194.032536 -46.429559)
			(xy 194.058006 -46.491009) (xy 194.075234 -46.555258) (xy 194.083925 -46.621207) (xy 194.084448 -46.654466)
			(xy 194.084448 -51.02225) (xy 194.084038 -51.049936) (xy 207.409803 -51.049936) (xy 207.413813 -50.944033)
			(xy 207.425821 -50.838737) (xy 207.445758 -50.734651) (xy 207.47351 -50.632371) (xy 207.508918 -50.532482)
			(xy 207.551779 -50.435558) (xy 207.601847 -50.342152) (xy 207.658837 -50.252801) (xy 207.72242 -50.168015)
			(xy 207.792234 -50.088281) (xy 207.867878 -50.014056) (xy 207.948918 -49.945763) (xy 208.034892 -49.883796)
			(xy 208.125306 -49.828508) (xy 208.219642 -49.780216) (xy 208.317361 -49.739197) (xy 208.417901 -49.705686)
			(xy 208.520689 -49.679874) (xy 208.625133 -49.66191) (xy 208.730638 -49.651897) (xy 208.836597 -49.649891)
			(xy 208.942405 -49.655905) (xy 209.047455 -49.669904) (xy 209.151145 -49.691807) (xy 209.252882 -49.72149)
			(xy 209.352083 -49.758781) (xy 209.448179 -49.803469) (xy 209.54062 -49.855296) (xy 209.628877 -49.913966)
			(xy 209.712444 -49.979143) (xy 209.790843 -50.050453) (xy 209.863624 -50.127487) (xy 209.93037 -50.209806)
			(xy 209.9907 -50.296937) (xy 210.044267 -50.388381) (xy 210.090765 -50.483614) (xy 210.129927 -50.582091)
			(xy 210.16153 -50.683248) (xy 210.185391 -50.786506) (xy 210.201376 -50.891272) (xy 210.209391 -50.996947)
			(xy 210.209892 -51.049936) (xy 237.409743 -51.049936) (xy 237.413753 -50.944033) (xy 237.425761 -50.838737)
			(xy 237.445698 -50.734651) (xy 237.47345 -50.632371) (xy 237.508858 -50.532482) (xy 237.551719 -50.435558)
			(xy 237.601787 -50.342152) (xy 237.658777 -50.252801) (xy 237.72236 -50.168015) (xy 237.792174 -50.088281)
			(xy 237.867818 -50.014056) (xy 237.948858 -49.945763) (xy 238.034832 -49.883796) (xy 238.125246 -49.828508)
			(xy 238.219582 -49.780216) (xy 238.317301 -49.739197) (xy 238.417841 -49.705686) (xy 238.520629 -49.679874)
			(xy 238.625073 -49.66191) (xy 238.730578 -49.651897) (xy 238.836537 -49.649891) (xy 238.942345 -49.655905)
			(xy 239.047395 -49.669904) (xy 239.151085 -49.691807) (xy 239.252822 -49.72149) (xy 239.352023 -49.758781)
			(xy 239.448119 -49.803469) (xy 239.54056 -49.855296) (xy 239.628817 -49.913966) (xy 239.712384 -49.979143)
			(xy 239.790783 -50.050453) (xy 239.863564 -50.127487) (xy 239.93031 -50.209806) (xy 239.99064 -50.296937)
			(xy 240.044207 -50.388381) (xy 240.090705 -50.483614) (xy 240.129867 -50.582091) (xy 240.16147 -50.683248)
			(xy 240.185331 -50.786506) (xy 240.201316 -50.891272) (xy 240.209331 -50.996947) (xy 240.209832 -51.049936)
			(xy 240.209331 -51.102925) (xy 240.201316 -51.2086) (xy 240.185331 -51.313366) (xy 240.16147 -51.416624)
			(xy 240.129867 -51.517781) (xy 240.090705 -51.616258) (xy 240.044207 -51.711491) (xy 239.99064 -51.802935)
			(xy 239.93031 -51.890066) (xy 239.863564 -51.972385) (xy 239.790783 -52.049419) (xy 239.712384 -52.120729)
			(xy 239.628817 -52.185906) (xy 239.54056 -52.244576) (xy 239.448119 -52.296403) (xy 239.352023 -52.341091)
			(xy 239.252822 -52.378382) (xy 239.151085 -52.408065) (xy 239.047395 -52.429968) (xy 238.942345 -52.443967)
			(xy 238.836537 -52.449981) (xy 238.730578 -52.447975) (xy 238.625073 -52.437962) (xy 238.520629 -52.419998)
			(xy 238.417841 -52.394186) (xy 238.317301 -52.360675) (xy 238.219582 -52.319656) (xy 238.125246 -52.271364)
			(xy 238.034832 -52.216076) (xy 237.948858 -52.154109) (xy 237.867818 -52.085816) (xy 237.792174 -52.011591)
			(xy 237.72236 -51.931857) (xy 237.658777 -51.847071) (xy 237.601787 -51.75772) (xy 237.551719 -51.664314)
			(xy 237.508858 -51.56739) (xy 237.47345 -51.467501) (xy 237.445698 -51.365221) (xy 237.425761 -51.261135)
			(xy 237.413753 -51.155839) (xy 237.409743 -51.049936) (xy 210.209892 -51.049936) (xy 210.209391 -51.102925)
			(xy 210.201376 -51.2086) (xy 210.185391 -51.313366) (xy 210.16153 -51.416624) (xy 210.129927 -51.517781)
			(xy 210.090765 -51.616258) (xy 210.044267 -51.711491) (xy 209.9907 -51.802935) (xy 209.93037 -51.890066)
			(xy 209.863624 -51.972385) (xy 209.790843 -52.049419) (xy 209.712444 -52.120729) (xy 209.628877 -52.185906)
			(xy 209.54062 -52.244576) (xy 209.448179 -52.296403) (xy 209.352083 -52.341091) (xy 209.252882 -52.378382)
			(xy 209.151145 -52.408065) (xy 209.047455 -52.429968) (xy 208.942405 -52.443967) (xy 208.836597 -52.449981)
			(xy 208.730638 -52.447975) (xy 208.625133 -52.437962) (xy 208.520689 -52.419998) (xy 208.417901 -52.394186)
			(xy 208.317361 -52.360675) (xy 208.219642 -52.319656) (xy 208.125306 -52.271364) (xy 208.034892 -52.216076)
			(xy 207.948918 -52.154109) (xy 207.867878 -52.085816) (xy 207.792234 -52.011591) (xy 207.72242 -51.931857)
			(xy 207.658837 -51.847071) (xy 207.601847 -51.75772) (xy 207.551779 -51.664314) (xy 207.508918 -51.56739)
			(xy 207.47351 -51.467501) (xy 207.445758 -51.365221) (xy 207.425821 -51.261135) (xy 207.413813 -51.155839)
			(xy 207.409803 -51.049936) (xy 194.084038 -51.049936) (xy 194.083956 -51.055511) (xy 194.075263 -51.121463)
			(xy 194.058032 -51.185715) (xy 194.03256 -51.247167) (xy 193.99928 -51.304767) (xy 193.958765 -51.357528)
			(xy 193.935604 -51.381406) (xy 193.390774 -51.926236) (xy 193.366877 -51.949375) (xy 193.31412 -51.989891)
			(xy 193.256524 -52.023169) (xy 193.195075 -52.04864) (xy 193.130826 -52.065868) (xy 193.064877 -52.074557)
			(xy 193.031618 -52.07508) (xy 182.815484 -52.07508) (xy 182.782224 -52.074557) (xy 182.716274 -52.065869)
			(xy 182.652022 -52.048644) (xy 182.59057 -52.023177) (xy 182.53297 -51.989903) (xy 182.480207 -51.949394)
			(xy 182.456328 -51.926236) (xy 181.784244 -51.254152) (xy 181.76109 -51.230269) (xy 181.720577 -51.177508)
			(xy 181.687302 -51.119909) (xy 181.661833 -51.058458) (xy 181.644608 -50.994207) (xy 181.635921 -50.928256)
			(xy 181.6354 -50.894996) (xy 181.6354 -46.609) (xy 181.635939 -46.575741) (xy 181.644625 -46.509791)
			(xy 181.661847 -46.44554) (xy 181.687311 -46.384089) (xy 181.720582 -46.326488) (xy 181.761088 -46.273724)
			(xy 181.784244 -46.249844) (xy 185.467244 -42.566844) (xy 185.479973 -42.554341) (xy 185.506922 -42.530951)
			(xy 185.521092 -42.520108) (xy 185.521346 -42.520108) (xy 185.529459 -42.513289) (xy 185.539717 -42.494765)
			(xy 185.541693 -42.473684) (xy 185.538872 -42.463466) (xy 185.508392 -42.372026) (xy 185.504497 -42.362119)
			(xy 185.4902 -42.346385) (xy 185.470761 -42.337776) (xy 185.460132 -42.337228) (xy 174.147226 -42.337228)
			(xy 174.137157 -42.337659) (xy 174.118559 -42.345375) (xy 174.111158 -42.352214) (xy 172.697648 -43.765724)
			(xy 172.690812 -43.773127) (xy 172.683088 -43.791724) (xy 172.682662 -43.801792) (xy 172.682662 -47.032361)
			(xy 177.987702 -47.032361) (xy 177.987702 -46.947639) (xy 177.995755 -46.863302) (xy 178.011789 -46.780112)
			(xy 178.035657 -46.698822) (xy 178.067145 -46.62017) (xy 178.105967 -46.544867) (xy 178.15177 -46.473595)
			(xy 178.204141 -46.406999) (xy 178.262606 -46.345684) (xy 178.326634 -46.290203) (xy 178.395646 -46.24106)
			(xy 178.469016 -46.1987) (xy 178.546081 -46.163505) (xy 178.626143 -46.135796) (xy 178.708476 -46.115822)
			(xy 178.792335 -46.103765) (xy 178.87696 -46.099734) (xy 178.961585 -46.103765) (xy 179.045444 -46.115822)
			(xy 179.127777 -46.135796) (xy 179.207839 -46.163505) (xy 179.284904 -46.1987) (xy 179.358274 -46.24106)
			(xy 179.427286 -46.290203) (xy 179.491314 -46.345684) (xy 179.549779 -46.406999) (xy 179.60215 -46.473595)
			(xy 179.647953 -46.544867) (xy 179.686775 -46.62017) (xy 179.718263 -46.698822) (xy 179.742131 -46.780112)
			(xy 179.758165 -46.863302) (xy 179.766218 -46.947639) (xy 179.766722 -46.99) (xy 179.766218 -47.032361)
			(xy 179.758165 -47.116698) (xy 179.742131 -47.199888) (xy 179.718263 -47.281178) (xy 179.686775 -47.35983)
			(xy 179.647953 -47.435133) (xy 179.60215 -47.506405) (xy 179.549779 -47.573001) (xy 179.491314 -47.634316)
			(xy 179.427286 -47.689797) (xy 179.358274 -47.73894) (xy 179.284904 -47.7813) (xy 179.207839 -47.816495)
			(xy 179.127777 -47.844204) (xy 179.045444 -47.864178) (xy 178.961585 -47.876235) (xy 178.87696 -47.880267)
			(xy 178.792335 -47.876235) (xy 178.708476 -47.864178) (xy 178.626143 -47.844204) (xy 178.546081 -47.816495)
			(xy 178.469016 -47.7813) (xy 178.395646 -47.73894) (xy 178.326634 -47.689797) (xy 178.262606 -47.634316)
			(xy 178.204141 -47.573001) (xy 178.15177 -47.506405) (xy 178.105967 -47.435133) (xy 178.067145 -47.35983)
			(xy 178.035657 -47.281178) (xy 178.011789 -47.199888) (xy 177.995755 -47.116698) (xy 177.987702 -47.032361)
			(xy 172.682662 -47.032361) (xy 172.682662 -50.465228) (xy 172.683056 -50.475301) (xy 172.690797 -50.4939)
			(xy 172.697648 -50.501296) (xy 172.778674 -50.582322) (xy 172.786086 -50.589146) (xy 172.804676 -50.596875)
			(xy 172.814742 -50.597308) (xy 173.980348 -50.597308) (xy 174.013609 -50.597814) (xy 174.07956 -50.606506)
			(xy 174.143811 -50.623734) (xy 174.205263 -50.649205) (xy 174.262863 -50.682481) (xy 174.315625 -50.722993)
			(xy 174.339504 -50.746152) (xy 176.661318 -53.067966) (xy 176.684492 -53.091831) (xy 176.725 -53.144596)
			(xy 176.758272 -53.2022) (xy 176.783737 -53.263655) (xy 176.800958 -53.327908) (xy 176.809642 -53.393861)
			(xy 176.810162 -53.427122) (xy 176.810162 -54.679088) (xy 176.809626 -54.712348) (xy 176.800941 -54.778298)
			(xy 176.783719 -54.842549) (xy 176.758254 -54.904001) (xy 176.724983 -54.961602) (xy 176.684475 -55.014365)
			(xy 176.661318 -55.038244) (xy 175.970438 -55.729124) (xy 175.946572 -55.752297) (xy 175.893807 -55.792805)
			(xy 175.836204 -55.826077) (xy 175.774749 -55.851542) (xy 175.710495 -55.868764) (xy 175.644543 -55.877448)
			(xy 175.611282 -55.877968) (xy 160.844484 -55.877968) (xy 160.834411 -55.878367) (xy 160.815813 -55.886104)
			(xy 160.808416 -55.892954) (xy 158.78937 -57.912) (xy 268.756388 -57.912) (xy 268.760418 -57.827399)
			(xy 268.772471 -57.743564) (xy 268.792439 -57.661255) (xy 268.820141 -57.581216) (xy 268.855325 -57.504173)
			(xy 268.897674 -57.430823) (xy 268.946803 -57.361831) (xy 269.002268 -57.297821) (xy 269.063566 -57.239373)
			(xy 269.130142 -57.187017) (xy 269.201394 -57.141227) (xy 269.276675 -57.102416) (xy 269.355305 -57.070937)
			(xy 269.436572 -57.047076) (xy 269.519738 -57.031047) (xy 269.604052 -57.022996) (xy 269.6464 -57.022492)
			(xy 269.646908 -57.022492) (xy 269.69324 -57.023098) (xy 269.785398 -57.032769) (xy 269.876052 -57.051965)
			(xy 269.964221 -57.080477) (xy 270.006826 -57.098692) (xy 270.016768 -57.102498) (xy 270.038032 -57.102498)
			(xy 270.047974 -57.098692) (xy 270.090636 -57.080447) (xy 270.178929 -57.051903) (xy 270.269714 -57.03271)
			(xy 270.362004 -57.023077) (xy 270.4084 -57.022492) (xy 270.451753 -57.02298) (xy 270.538049 -57.031388)
			(xy 270.623118 -57.048154) (xy 270.706152 -57.073118) (xy 270.786362 -57.106044) (xy 270.862988 -57.146619)
			(xy 270.935302 -57.194458) (xy 271.002617 -57.249107) (xy 271.064295 -57.310046) (xy 271.092422 -57.34304)
			(xy 271.099534 -57.351676) (xy 271.119854 -57.361328) (xy 271.220946 -57.361328) (xy 271.241266 -57.351676)
			(xy 271.248378 -57.34304) (xy 271.276524 -57.310064) (xy 271.338205 -57.249132) (xy 271.40552 -57.194489)
			(xy 271.477833 -57.146654) (xy 271.554455 -57.106081) (xy 271.634662 -57.073155) (xy 271.717692 -57.048188)
			(xy 271.802756 -57.031418) (xy 271.889049 -57.023002) (xy 271.9324 -57.022492) (xy 271.978796 -57.023075)
			(xy 272.071084 -57.03272) (xy 272.161868 -57.051916) (xy 272.250161 -57.080454) (xy 272.292826 -57.098692)
			(xy 272.302768 -57.102498) (xy 272.324032 -57.102498) (xy 272.333974 -57.098692) (xy 272.376577 -57.08047)
			(xy 272.464744 -57.051952) (xy 272.5554 -57.03276) (xy 272.64756 -57.0231) (xy 272.693892 -57.022492)
			(xy 272.6944 -57.022492) (xy 272.736748 -57.022996) (xy 272.821062 -57.031047) (xy 272.904228 -57.047076)
			(xy 272.985495 -57.070937) (xy 273.064125 -57.102416) (xy 273.139406 -57.141227) (xy 273.210658 -57.187017)
			(xy 273.277234 -57.239373) (xy 273.338532 -57.297821) (xy 273.393997 -57.361831) (xy 273.443126 -57.430823)
			(xy 273.485475 -57.504173) (xy 273.520659 -57.581216) (xy 273.548361 -57.661255) (xy 273.568329 -57.743564)
			(xy 273.580382 -57.827399) (xy 273.584413 -57.912) (xy 273.580382 -57.996601) (xy 273.568329 -58.080436)
			(xy 273.548361 -58.162745) (xy 273.520659 -58.242784) (xy 273.485475 -58.319827) (xy 273.443126 -58.393177)
			(xy 273.393997 -58.462169) (xy 273.338532 -58.526179) (xy 273.277234 -58.584627) (xy 273.210658 -58.636983)
			(xy 273.139406 -58.682773) (xy 273.064125 -58.721584) (xy 272.985495 -58.753063) (xy 272.904228 -58.776924)
			(xy 272.821062 -58.792953) (xy 272.736748 -58.801004) (xy 272.6944 -58.801508) (xy 272.693892 -58.801508)
			(xy 272.64756 -58.800902) (xy 272.555402 -58.791231) (xy 272.464748 -58.772035) (xy 272.376579 -58.743523)
			(xy 272.333974 -58.725308) (xy 272.324032 -58.721502) (xy 272.302768 -58.721502) (xy 272.292826 -58.725308)
			(xy 272.250164 -58.743553) (xy 272.161871 -58.772097) (xy 272.071086 -58.79129) (xy 271.978796 -58.800923)
			(xy 271.9324 -58.801508) (xy 271.889047 -58.80102) (xy 271.802751 -58.792612) (xy 271.717682 -58.775846)
			(xy 271.634648 -58.750882) (xy 271.554438 -58.717956) (xy 271.477812 -58.677381) (xy 271.405498 -58.629542)
			(xy 271.338183 -58.574893) (xy 271.276505 -58.513954) (xy 271.248378 -58.48096) (xy 271.241266 -58.472324)
			(xy 271.220946 -58.462672) (xy 271.119854 -58.462672) (xy 271.099534 -58.472324) (xy 271.092422 -58.48096)
			(xy 271.064276 -58.513936) (xy 271.002595 -58.574868) (xy 270.93528 -58.629511) (xy 270.862967 -58.677346)
			(xy 270.786345 -58.717919) (xy 270.706138 -58.750845) (xy 270.623108 -58.775812) (xy 270.538044 -58.792582)
			(xy 270.451751 -58.800998) (xy 270.4084 -58.801508) (xy 270.362004 -58.800925) (xy 270.269716 -58.79128)
			(xy 270.178932 -58.772084) (xy 270.090639 -58.743546) (xy 270.047974 -58.725308) (xy 270.038032 -58.721502)
			(xy 270.016768 -58.721502) (xy 270.006826 -58.725308) (xy 269.964223 -58.74353) (xy 269.876056 -58.772048)
			(xy 269.7854 -58.79124) (xy 269.69324 -58.8009) (xy 269.646908 -58.801508) (xy 269.6464 -58.801508)
			(xy 269.604052 -58.801004) (xy 269.519738 -58.792953) (xy 269.436572 -58.776924) (xy 269.355305 -58.753063)
			(xy 269.276675 -58.721584) (xy 269.201394 -58.682773) (xy 269.130142 -58.636983) (xy 269.063566 -58.584627)
			(xy 269.002268 -58.526179) (xy 268.946803 -58.462169) (xy 268.897674 -58.393177) (xy 268.855325 -58.319827)
			(xy 268.820141 -58.242784) (xy 268.792439 -58.162745) (xy 268.772471 -58.080436) (xy 268.760418 -57.996601)
			(xy 268.756388 -57.912) (xy 158.78937 -57.912) (xy 156.32557 -60.3758) (xy 165.632388 -60.3758) (xy 165.636418 -60.291199)
			(xy 165.648471 -60.207364) (xy 165.668439 -60.125055) (xy 165.696141 -60.045016) (xy 165.731325 -59.967973)
			(xy 165.773674 -59.894623) (xy 165.822803 -59.825631) (xy 165.878268 -59.761621) (xy 165.939566 -59.703173)
			(xy 166.006142 -59.650817) (xy 166.077394 -59.605027) (xy 166.152675 -59.566216) (xy 166.231305 -59.534737)
			(xy 166.312572 -59.510876) (xy 166.395738 -59.494847) (xy 166.480052 -59.486796) (xy 166.5224 -59.486292)
			(xy 166.522908 -59.486292) (xy 166.56924 -59.486898) (xy 166.661398 -59.496569) (xy 166.752052 -59.515765)
			(xy 166.840221 -59.544277) (xy 166.882826 -59.562492) (xy 166.892768 -59.566298) (xy 166.914032 -59.566298)
			(xy 166.923974 -59.562492) (xy 166.966577 -59.54427) (xy 167.054744 -59.515752) (xy 167.1454 -59.49656)
			(xy 167.23756 -59.4869) (xy 167.283892 -59.486292) (xy 167.2844 -59.486292) (xy 167.326748 -59.486796)
			(xy 167.411062 -59.494847) (xy 167.494228 -59.510876) (xy 167.575495 -59.534737) (xy 167.654125 -59.566216)
			(xy 167.729406 -59.605027) (xy 167.800658 -59.650817) (xy 167.867234 -59.703173) (xy 167.928532 -59.761621)
			(xy 167.983997 -59.825631) (xy 168.033126 -59.894623) (xy 168.075475 -59.967973) (xy 168.110659 -60.045016)
			(xy 168.138361 -60.125055) (xy 168.158329 -60.207364) (xy 168.170382 -60.291199) (xy 168.174413 -60.3758)
			(xy 168.170382 -60.460401) (xy 168.158329 -60.544236) (xy 168.138361 -60.626545) (xy 168.110659 -60.706584)
			(xy 168.075475 -60.783627) (xy 168.033126 -60.856977) (xy 167.983997 -60.925969) (xy 167.928532 -60.989979)
			(xy 167.867234 -61.048427) (xy 167.800658 -61.100783) (xy 167.729406 -61.146573) (xy 167.654125 -61.185384)
			(xy 167.575495 -61.216863) (xy 167.494228 -61.240724) (xy 167.411062 -61.256753) (xy 167.326748 -61.264804)
			(xy 167.2844 -61.265308) (xy 167.283892 -61.265308) (xy 167.23756 -61.264702) (xy 167.145402 -61.255031)
			(xy 167.054748 -61.235835) (xy 166.966579 -61.207323) (xy 166.923974 -61.189108) (xy 166.914032 -61.185302)
			(xy 166.892768 -61.185302) (xy 166.882826 -61.189108) (xy 166.840223 -61.20733) (xy 166.752056 -61.235848)
			(xy 166.6614 -61.25504) (xy 166.56924 -61.2647) (xy 166.522908 -61.265308) (xy 166.5224 -61.265308)
			(xy 166.480052 -61.264804) (xy 166.395738 -61.256753) (xy 166.312572 -61.240724) (xy 166.231305 -61.216863)
			(xy 166.152675 -61.185384) (xy 166.077394 -61.146573) (xy 166.006142 -61.100783) (xy 165.939566 -61.048427)
			(xy 165.878268 -60.989979) (xy 165.822803 -60.925969) (xy 165.773674 -60.856977) (xy 165.731325 -60.783627)
			(xy 165.696141 -60.706584) (xy 165.668439 -60.626545) (xy 165.648471 -60.544236) (xy 165.636418 -60.460401)
			(xy 165.632388 -60.3758) (xy 156.32557 -60.3758) (xy 152.143009 -64.558361) (xy 261.838182 -64.558361)
			(xy 261.838182 -64.473639) (xy 261.846235 -64.389302) (xy 261.862269 -64.306112) (xy 261.886137 -64.224822)
			(xy 261.917625 -64.14617) (xy 261.956447 -64.070867) (xy 262.00225 -63.999595) (xy 262.054621 -63.932999)
			(xy 262.113086 -63.871684) (xy 262.177114 -63.816203) (xy 262.246126 -63.76706) (xy 262.319496 -63.7247)
			(xy 262.396561 -63.689505) (xy 262.476623 -63.661796) (xy 262.558956 -63.641822) (xy 262.642815 -63.629765)
			(xy 262.72744 -63.625734) (xy 262.812065 -63.629765) (xy 262.895924 -63.641822) (xy 262.978257 -63.661796)
			(xy 263.058319 -63.689505) (xy 263.135384 -63.7247) (xy 263.208754 -63.76706) (xy 263.277766 -63.816203)
			(xy 263.341794 -63.871684) (xy 263.400259 -63.932999) (xy 263.45263 -63.999595) (xy 263.498433 -64.070867)
			(xy 263.537255 -64.14617) (xy 263.568743 -64.224822) (xy 263.592611 -64.306112) (xy 263.608645 -64.389302)
			(xy 263.616698 -64.473639) (xy 263.617202 -64.516) (xy 263.616698 -64.558361) (xy 263.608645 -64.642698)
			(xy 263.592611 -64.725888) (xy 263.568743 -64.807178) (xy 263.537255 -64.88583) (xy 263.498433 -64.961133)
			(xy 263.45263 -65.032405) (xy 263.400259 -65.099001) (xy 263.341794 -65.160316) (xy 263.277766 -65.215797)
			(xy 263.208754 -65.26494) (xy 263.135384 -65.3073) (xy 263.058319 -65.342495) (xy 262.978257 -65.370204)
			(xy 262.895924 -65.390178) (xy 262.812065 -65.402235) (xy 262.72744 -65.406267) (xy 262.642815 -65.402235)
			(xy 262.558956 -65.390178) (xy 262.476623 -65.370204) (xy 262.396561 -65.342495) (xy 262.319496 -65.3073)
			(xy 262.246126 -65.26494) (xy 262.177114 -65.215797) (xy 262.113086 -65.160316) (xy 262.054621 -65.099001)
			(xy 262.00225 -65.032405) (xy 261.956447 -64.961133) (xy 261.917625 -64.88583) (xy 261.886137 -64.807178)
			(xy 261.862269 -64.725888) (xy 261.846235 -64.642698) (xy 261.838182 -64.558361) (xy 152.143009 -64.558361)
			(xy 150.38197 -66.3194) (xy 178.683872 -66.3194) (xy 178.687902 -66.234795) (xy 178.699957 -66.150957)
			(xy 178.719926 -66.068644) (xy 178.74763 -65.988602) (xy 178.782817 -65.911556) (xy 178.825168 -65.838204)
			(xy 178.8743 -65.769209) (xy 178.929768 -65.705198) (xy 178.99107 -65.646749) (xy 179.057651 -65.594392)
			(xy 179.128907 -65.548601) (xy 179.204193 -65.509791) (xy 179.282827 -65.478314) (xy 179.364098 -65.454453)
			(xy 179.447268 -65.438427) (xy 179.531586 -65.430378) (xy 179.573936 -65.429892) (xy 179.574698 -65.429892)
			(xy 179.613046 -65.430288) (xy 179.689453 -65.436923) (xy 179.765005 -65.450117) (xy 179.839139 -65.469774)
			(xy 179.911302 -65.495746) (xy 179.9463 -65.511426) (xy 179.956573 -65.515566) (xy 179.978699 -65.515566)
			(xy 179.988972 -65.511426) (xy 180.023978 -65.49577) (xy 180.096146 -65.469818) (xy 180.170278 -65.45017)
			(xy 180.245826 -65.436971) (xy 180.322228 -65.430321) (xy 180.360574 -65.429892) (xy 180.361336 -65.429892)
			(xy 180.403683 -65.430397) (xy 180.487994 -65.438451) (xy 180.571158 -65.454483) (xy 180.652421 -65.478347)
			(xy 180.731048 -65.509827) (xy 180.806327 -65.548639) (xy 180.877576 -65.59443) (xy 180.944149 -65.646786)
			(xy 181.005444 -65.705234) (xy 181.060907 -65.769243) (xy 181.110033 -65.838234) (xy 181.15238 -65.911582)
			(xy 181.187562 -65.988624) (xy 181.215263 -66.068661) (xy 181.23523 -66.150968) (xy 181.247283 -66.234801)
			(xy 181.251313 -66.3194) (xy 181.247283 -66.403999) (xy 181.23523 -66.487832) (xy 181.215263 -66.570139)
			(xy 181.187562 -66.650176) (xy 181.15238 -66.727218) (xy 181.110033 -66.800566) (xy 181.060907 -66.869557)
			(xy 181.005444 -66.933566) (xy 180.944149 -66.992014) (xy 180.877576 -67.04437) (xy 180.806327 -67.090161)
			(xy 180.731048 -67.128973) (xy 180.652421 -67.160453) (xy 180.571158 -67.184317) (xy 180.487994 -67.200349)
			(xy 180.403683 -67.208403) (xy 180.361336 -67.208908) (xy 180.360574 -67.208908) (xy 180.322227 -67.208485)
			(xy 180.24582 -67.201857) (xy 180.170269 -67.188668) (xy 180.096135 -67.169018) (xy 180.02397 -67.143051)
			(xy 179.988972 -67.127374) (xy 179.978699 -67.123234) (xy 179.956573 -67.123234) (xy 179.9463 -67.127374)
			(xy 179.911298 -67.14304) (xy 179.839129 -67.16899) (xy 179.764996 -67.188636) (xy 179.689447 -67.201832)
			(xy 179.613044 -67.20848) (xy 179.574698 -67.208908) (xy 179.573936 -67.208908) (xy 179.531586 -67.208422)
			(xy 179.447268 -67.200373) (xy 179.364098 -67.184347) (xy 179.282827 -67.160486) (xy 179.204193 -67.129009)
			(xy 179.128907 -67.090199) (xy 179.057651 -67.044408) (xy 178.99107 -66.992051) (xy 178.929768 -66.933602)
			(xy 178.8743 -66.869591) (xy 178.825168 -66.800596) (xy 178.782817 -66.727244) (xy 178.74763 -66.650198)
			(xy 178.719926 -66.570156) (xy 178.699957 -66.487843) (xy 178.687902 -66.404005) (xy 178.683872 -66.3194)
			(xy 150.38197 -66.3194) (xy 149.027388 -67.673982) (xy 149.003493 -67.697123) (xy 148.950735 -67.737636)
			(xy 148.893138 -67.770913) (xy 148.831689 -67.796384) (xy 148.76744 -67.813612) (xy 148.701491 -67.822303)
			(xy 148.668232 -67.822826) (xy 147.268438 -67.822826) (xy 147.258918 -67.823235) (xy 147.241193 -67.830193)
			(xy 147.22722 -67.84313) (xy 147.222718 -67.851528) (xy 147.20415 -67.888594) (xy 147.161092 -67.959444)
			(xy 147.111631 -68.025982) (xy 147.056195 -68.08763) (xy 146.995265 -68.143854) (xy 146.929368 -68.194166)
			(xy 146.859078 -68.238131) (xy 146.785002 -68.275367) (xy 146.707784 -68.30555) (xy 146.628093 -68.32842)
			(xy 146.54662 -68.343777) (xy 146.464072 -68.351489) (xy 146.381164 -68.351489) (xy 146.298616 -68.343777)
			(xy 146.217143 -68.32842) (xy 146.137452 -68.30555) (xy 146.060234 -68.275367) (xy 145.986158 -68.238131)
			(xy 145.915868 -68.194166) (xy 145.849971 -68.143854) (xy 145.789041 -68.08763) (xy 145.733605 -68.025982)
			(xy 145.684144 -67.959444) (xy 145.641086 -67.888594) (xy 145.622518 -67.851528) (xy 145.618028 -67.84312)
			(xy 145.604056 -67.830173) (xy 145.586322 -67.82322) (xy 145.576798 -67.822826) (xy 143.862806 -67.822826)
			(xy 143.834866 -67.845686) (xy 143.83131 -67.86372) (xy 143.822279 -67.9067) (xy 143.796815 -67.99076)
			(xy 143.763184 -68.071898) (xy 143.742918 -68.110862) (xy 143.737504 -68.12233) (xy 143.737501 -68.147656)
			(xy 143.742918 -68.159122) (xy 143.763197 -68.198006) (xy 143.796886 -68.27898) (xy 143.822451 -68.362874)
			(xy 143.839643 -68.448874) (xy 143.848295 -68.536149) (xy 143.848836 -68.58) (xy 143.848317 -68.623763)
			(xy 143.839718 -68.710864) (xy 143.822612 -68.796702) (xy 143.797165 -68.880446) (xy 143.763623 -68.961289)
			(xy 143.743426 -69.000116) (xy 143.738194 -69.011509) (xy 143.738307 -69.036544) (xy 143.74368 -69.047868)
			(xy 143.763943 -69.086781) (xy 143.797578 -69.167817) (xy 143.804198 -69.1896) (xy 177.667872 -69.1896)
			(xy 177.671902 -69.104995) (xy 177.683957 -69.021157) (xy 177.703926 -68.938844) (xy 177.73163 -68.858802)
			(xy 177.766817 -68.781756) (xy 177.809168 -68.708404) (xy 177.8583 -68.639409) (xy 177.913768 -68.575398)
			(xy 177.97507 -68.516949) (xy 178.041651 -68.464592) (xy 178.112907 -68.418801) (xy 178.188193 -68.379991)
			(xy 178.266827 -68.348514) (xy 178.348098 -68.324653) (xy 178.431268 -68.308627) (xy 178.515586 -68.300578)
			(xy 178.557936 -68.300092) (xy 178.558444 -68.300092) (xy 178.597192 -68.300509) (xy 178.674394 -68.307273)
			(xy 178.750714 -68.320729) (xy 178.825573 -68.340774) (xy 178.898405 -68.367256) (xy 178.968657 -68.399975)
			(xy 179.002436 -68.418964) (xy 179.01031 -68.423123) (xy 179.027836 -68.426217) (xy 179.045362 -68.423123)
			(xy 179.053236 -68.418964) (xy 179.087017 -68.399978) (xy 179.157269 -68.367265) (xy 179.230101 -68.340786)
			(xy 179.304961 -68.320743) (xy 179.38128 -68.307289) (xy 179.45848 -68.300524) (xy 179.497228 -68.300092)
			(xy 179.497736 -68.300092) (xy 179.540083 -68.300597) (xy 179.624394 -68.308651) (xy 179.707558 -68.324683)
			(xy 179.788821 -68.348547) (xy 179.867448 -68.380027) (xy 179.942727 -68.418839) (xy 180.013976 -68.46463)
			(xy 180.080549 -68.516986) (xy 180.141844 -68.575434) (xy 180.197307 -68.639443) (xy 180.246433 -68.708434)
			(xy 180.28878 -68.781782) (xy 180.323962 -68.858824) (xy 180.351663 -68.938861) (xy 180.37163 -69.021168)
			(xy 180.383683 -69.105001) (xy 180.387713 -69.1896) (xy 180.383683 -69.274199) (xy 180.37163 -69.358032)
			(xy 180.351663 -69.440339) (xy 180.350534 -69.4436) (xy 181.326028 -69.4436) (xy 181.326532 -69.401252)
			(xy 181.334583 -69.316938) (xy 181.350612 -69.233772) (xy 181.374473 -69.152505) (xy 181.405952 -69.073875)
			(xy 181.444763 -68.998594) (xy 181.490553 -68.927342) (xy 181.542909 -68.860766) (xy 181.601357 -68.799468)
			(xy 181.665367 -68.744003) (xy 181.734359 -68.694874) (xy 181.807709 -68.652525) (xy 181.884752 -68.617341)
			(xy 181.964791 -68.589639) (xy 182.0471 -68.569671) (xy 182.130935 -68.557618) (xy 182.215536 -68.553588)
			(xy 182.300137 -68.557618) (xy 182.383972 -68.569671) (xy 182.426549 -68.58) (xy 183.920388 -68.58)
			(xy 183.924418 -68.495399) (xy 183.936471 -68.411564) (xy 183.956439 -68.329255) (xy 183.984141 -68.249216)
			(xy 184.019325 -68.172173) (xy 184.061674 -68.098823) (xy 184.110803 -68.029831) (xy 184.166268 -67.965821)
			(xy 184.227566 -67.907373) (xy 184.294142 -67.855017) (xy 184.365394 -67.809227) (xy 184.440675 -67.770416)
			(xy 184.519305 -67.738937) (xy 184.600572 -67.715076) (xy 184.683738 -67.699047) (xy 184.768052 -67.690996)
			(xy 184.8104 -67.690492) (xy 184.810908 -67.690492) (xy 184.85724 -67.691098) (xy 184.949398 -67.700769)
			(xy 185.040052 -67.719965) (xy 185.128221 -67.748477) (xy 185.170826 -67.766692) (xy 185.180768 -67.770498)
			(xy 185.202032 -67.770498) (xy 185.211974 -67.766692) (xy 185.254577 -67.74847) (xy 185.342744 -67.719952)
			(xy 185.4334 -67.70076) (xy 185.52556 -67.6911) (xy 185.571892 -67.690492) (xy 185.5724 -67.690492)
			(xy 185.614748 -67.690996) (xy 185.699062 -67.699047) (xy 185.782228 -67.715076) (xy 185.863495 -67.738937)
			(xy 185.942125 -67.770416) (xy 186.017406 -67.809227) (xy 186.088658 -67.855017) (xy 186.155234 -67.907373)
			(xy 186.216532 -67.965821) (xy 186.271997 -68.029831) (xy 186.321126 -68.098823) (xy 186.363475 -68.172173)
			(xy 186.375726 -68.199) (xy 267.232388 -68.199) (xy 267.236418 -68.114399) (xy 267.248471 -68.030564)
			(xy 267.268439 -67.948255) (xy 267.296141 -67.868216) (xy 267.331325 -67.791173) (xy 267.373674 -67.717823)
			(xy 267.422803 -67.648831) (xy 267.478268 -67.584821) (xy 267.539566 -67.526373) (xy 267.606142 -67.474017)
			(xy 267.677394 -67.428227) (xy 267.752675 -67.389416) (xy 267.831305 -67.357937) (xy 267.912572 -67.334076)
			(xy 267.995738 -67.318047) (xy 268.080052 -67.309996) (xy 268.1224 -67.309492) (xy 268.122908 -67.309492)
			(xy 268.161656 -67.309926) (xy 268.238857 -67.316687) (xy 268.315177 -67.330139) (xy 268.390036 -67.350181)
			(xy 268.462869 -67.37666) (xy 268.53312 -67.409376) (xy 268.5669 -67.428364) (xy 268.574774 -67.432523)
			(xy 268.5923 -67.435617) (xy 268.609826 -67.432523) (xy 268.6177 -67.428364) (xy 268.651489 -67.409393)
			(xy 268.721739 -67.376677) (xy 268.79457 -67.350196) (xy 268.869428 -67.330151) (xy 268.945745 -67.316693)
			(xy 269.022945 -67.309925) (xy 269.061692 -67.309492) (xy 269.0622 -67.309492) (xy 269.104548 -67.309996)
			(xy 269.188862 -67.318047) (xy 269.272028 -67.334076) (xy 269.353295 -67.357937) (xy 269.431925 -67.389416)
			(xy 269.507206 -67.428227) (xy 269.578458 -67.474017) (xy 269.645034 -67.526373) (xy 269.706332 -67.584821)
			(xy 269.761797 -67.648831) (xy 269.810926 -67.717823) (xy 269.853275 -67.791173) (xy 269.888459 -67.868216)
			(xy 269.916161 -67.948255) (xy 269.936129 -68.030564) (xy 269.948182 -68.114399) (xy 269.952213 -68.199)
			(xy 269.948182 -68.283601) (xy 269.936129 -68.367436) (xy 269.916161 -68.449745) (xy 269.888459 -68.529784)
			(xy 269.853275 -68.606827) (xy 269.810926 -68.680177) (xy 269.761797 -68.749169) (xy 269.706332 -68.813179)
			(xy 269.645034 -68.871627) (xy 269.578458 -68.923983) (xy 269.507206 -68.969773) (xy 269.431925 -69.008584)
			(xy 269.353295 -69.040063) (xy 269.272028 -69.063924) (xy 269.188862 -69.079953) (xy 269.104548 -69.088004)
			(xy 269.0622 -69.088508) (xy 269.061692 -69.088508) (xy 269.022944 -69.088074) (xy 268.945743 -69.081313)
			(xy 268.869423 -69.067861) (xy 268.794564 -69.047819) (xy 268.721731 -69.02134) (xy 268.65148 -68.988624)
			(xy 268.6177 -68.969636) (xy 268.609826 -68.965477) (xy 268.5923 -68.962383) (xy 268.574774 -68.965477)
			(xy 268.5669 -68.969636) (xy 268.533111 -68.988607) (xy 268.462861 -69.021323) (xy 268.39003 -69.047804)
			(xy 268.315172 -69.067849) (xy 268.238855 -69.081307) (xy 268.161655 -69.088075) (xy 268.122908 -69.088508)
			(xy 268.1224 -69.088508) (xy 268.080052 -69.088004) (xy 267.995738 -69.079953) (xy 267.912572 -69.063924)
			(xy 267.831305 -69.040063) (xy 267.752675 -69.008584) (xy 267.677394 -68.969773) (xy 267.606142 -68.923983)
			(xy 267.539566 -68.871627) (xy 267.478268 -68.813179) (xy 267.422803 -68.749169) (xy 267.373674 -68.680177)
			(xy 267.331325 -68.606827) (xy 267.296141 -68.529784) (xy 267.268439 -68.449745) (xy 267.248471 -68.367436)
			(xy 267.236418 -68.283601) (xy 267.232388 -68.199) (xy 186.375726 -68.199) (xy 186.398659 -68.249216)
			(xy 186.426361 -68.329255) (xy 186.446329 -68.411564) (xy 186.458382 -68.495399) (xy 186.462413 -68.58)
			(xy 186.458382 -68.664601) (xy 186.446329 -68.748436) (xy 186.426361 -68.830745) (xy 186.398659 -68.910784)
			(xy 186.363475 -68.987827) (xy 186.321126 -69.061177) (xy 186.271997 -69.130169) (xy 186.216532 -69.194179)
			(xy 186.155234 -69.252627) (xy 186.088658 -69.304983) (xy 186.023153 -69.34708) (xy 263.981692 -69.34708)
			(xy 263.982196 -69.304732) (xy 263.990247 -69.220418) (xy 264.006276 -69.137252) (xy 264.030137 -69.055985)
			(xy 264.061616 -68.977355) (xy 264.100427 -68.902074) (xy 264.146217 -68.830822) (xy 264.198573 -68.764246)
			(xy 264.257021 -68.702948) (xy 264.321031 -68.647483) (xy 264.390023 -68.598354) (xy 264.463373 -68.556005)
			(xy 264.540416 -68.520821) (xy 264.620455 -68.493119) (xy 264.702764 -68.473151) (xy 264.786599 -68.461098)
			(xy 264.8712 -68.457068) (xy 264.955801 -68.461098) (xy 265.039636 -68.473151) (xy 265.121945 -68.493119)
			(xy 265.201984 -68.520821) (xy 265.279027 -68.556005) (xy 265.352377 -68.598354) (xy 265.421369 -68.647483)
			(xy 265.485379 -68.702948) (xy 265.543827 -68.764246) (xy 265.596183 -68.830822) (xy 265.641973 -68.902074)
			(xy 265.680784 -68.977355) (xy 265.712263 -69.055985) (xy 265.736124 -69.137252) (xy 265.752153 -69.220418)
			(xy 265.760204 -69.304732) (xy 265.760708 -69.34708) (xy 265.760708 -69.347842) (xy 265.760124 -69.39309)
			(xy 265.750905 -69.483115) (xy 265.732585 -69.571738) (xy 265.705356 -69.658041) (xy 265.669499 -69.74113)
			(xy 265.647932 -69.780912) (xy 265.643026 -69.790878) (xy 265.641461 -69.813015) (xy 265.644884 -69.823584)
			(xy 265.676126 -69.906896) (xy 265.691874 -69.92239) (xy 265.702542 -69.9262) (xy 265.741999 -69.940786)
			(xy 265.818247 -69.976332) (xy 265.8908 -70.018917) (xy 265.959008 -70.068161) (xy 266.022264 -70.123623)
			(xy 266.080001 -70.184809) (xy 266.131705 -70.251172) (xy 266.176914 -70.322119) (xy 266.215223 -70.397017)
			(xy 266.246292 -70.475197) (xy 266.269842 -70.55596) (xy 266.285663 -70.638586) (xy 266.293613 -70.722337)
			(xy 266.294108 -70.7644) (xy 266.293604 -70.806748) (xy 266.285553 -70.891062) (xy 266.269524 -70.974228)
			(xy 266.256555 -71.0184) (xy 267.232388 -71.0184) (xy 267.236418 -70.933799) (xy 267.248471 -70.849964)
			(xy 267.268439 -70.767655) (xy 267.296141 -70.687616) (xy 267.331325 -70.610573) (xy 267.373674 -70.537223)
			(xy 267.422803 -70.468231) (xy 267.478268 -70.404221) (xy 267.539566 -70.345773) (xy 267.606142 -70.293417)
			(xy 267.677394 -70.247627) (xy 267.752675 -70.208816) (xy 267.831305 -70.177337) (xy 267.912572 -70.153476)
			(xy 267.995738 -70.137447) (xy 268.080052 -70.129396) (xy 268.1224 -70.128892) (xy 268.122908 -70.128892)
			(xy 268.161656 -70.129326) (xy 268.238857 -70.136087) (xy 268.315177 -70.149539) (xy 268.390036 -70.169581)
			(xy 268.462869 -70.19606) (xy 268.53312 -70.228776) (xy 268.5669 -70.247764) (xy 268.574774 -70.251923)
			(xy 268.5923 -70.255017) (xy 268.609826 -70.251923) (xy 268.6177 -70.247764) (xy 268.651489 -70.228793)
			(xy 268.721739 -70.196077) (xy 268.79457 -70.169596) (xy 268.869428 -70.149551) (xy 268.945745 -70.136093)
			(xy 269.022945 -70.129325) (xy 269.061692 -70.128892) (xy 269.0622 -70.128892) (xy 269.104548 -70.129396)
			(xy 269.188862 -70.137447) (xy 269.272028 -70.153476) (xy 269.353295 -70.177337) (xy 269.431925 -70.208816)
			(xy 269.507206 -70.247627) (xy 269.578458 -70.293417) (xy 269.645034 -70.345773) (xy 269.706332 -70.404221)
			(xy 269.761797 -70.468231) (xy 269.810926 -70.537223) (xy 269.853275 -70.610573) (xy 269.888459 -70.687616)
			(xy 269.916161 -70.767655) (xy 269.936129 -70.849964) (xy 269.948182 -70.933799) (xy 269.952213 -71.0184)
			(xy 269.948182 -71.103001) (xy 269.936129 -71.186836) (xy 269.916161 -71.269145) (xy 269.888459 -71.349184)
			(xy 269.853275 -71.426227) (xy 269.810926 -71.499577) (xy 269.761797 -71.568569) (xy 269.706332 -71.632579)
			(xy 269.645034 -71.691027) (xy 269.578458 -71.743383) (xy 269.507206 -71.789173) (xy 269.431925 -71.827984)
			(xy 269.353295 -71.859463) (xy 269.272028 -71.883324) (xy 269.188862 -71.899353) (xy 269.104548 -71.907404)
			(xy 269.0622 -71.907908) (xy 269.061692 -71.907908) (xy 269.022944 -71.907474) (xy 268.945743 -71.900713)
			(xy 268.869423 -71.887261) (xy 268.794564 -71.867219) (xy 268.721731 -71.84074) (xy 268.65148 -71.808024)
			(xy 268.6177 -71.789036) (xy 268.609826 -71.784877) (xy 268.5923 -71.781783) (xy 268.574774 -71.784877)
			(xy 268.5669 -71.789036) (xy 268.533111 -71.808007) (xy 268.462861 -71.840723) (xy 268.39003 -71.867204)
			(xy 268.315172 -71.887249) (xy 268.238855 -71.900707) (xy 268.161655 -71.907475) (xy 268.122908 -71.907908)
			(xy 268.1224 -71.907908) (xy 268.080052 -71.907404) (xy 267.995738 -71.899353) (xy 267.912572 -71.883324)
			(xy 267.831305 -71.859463) (xy 267.752675 -71.827984) (xy 267.677394 -71.789173) (xy 267.606142 -71.743383)
			(xy 267.539566 -71.691027) (xy 267.478268 -71.632579) (xy 267.422803 -71.568569) (xy 267.373674 -71.499577)
			(xy 267.331325 -71.426227) (xy 267.296141 -71.349184) (xy 267.268439 -71.269145) (xy 267.248471 -71.186836)
			(xy 267.236418 -71.103001) (xy 267.232388 -71.0184) (xy 266.256555 -71.0184) (xy 266.245663 -71.055495)
			(xy 266.214184 -71.134125) (xy 266.175373 -71.209406) (xy 266.129583 -71.280658) (xy 266.077227 -71.347234)
			(xy 266.018779 -71.408532) (xy 265.954769 -71.463997) (xy 265.885777 -71.513126) (xy 265.812427 -71.555475)
			(xy 265.735384 -71.590659) (xy 265.655345 -71.618361) (xy 265.573036 -71.638329) (xy 265.489201 -71.650382)
			(xy 265.4046 -71.654413) (xy 265.319999 -71.650382) (xy 265.236164 -71.638329) (xy 265.153855 -71.618361)
			(xy 265.073816 -71.590659) (xy 264.996773 -71.555475) (xy 264.923423 -71.513126) (xy 264.854431 -71.463997)
			(xy 264.790421 -71.408532) (xy 264.731973 -71.347234) (xy 264.679617 -71.280658) (xy 264.633827 -71.209406)
			(xy 264.595016 -71.134125) (xy 264.563537 -71.055495) (xy 264.539676 -70.974228) (xy 264.523647 -70.891062)
			(xy 264.515596 -70.806748) (xy 264.515092 -70.7644) (xy 264.515092 -70.763638) (xy 264.515667 -70.71839)
			(xy 264.524889 -70.628364) (xy 264.54321 -70.539741) (xy 264.570441 -70.453439) (xy 264.6063 -70.37035)
			(xy 264.627868 -70.330568) (xy 264.632726 -70.320583) (xy 264.634321 -70.298463) (xy 264.630916 -70.287896)
			(xy 264.599674 -70.204584) (xy 264.583926 -70.18909) (xy 264.573258 -70.18528) (xy 264.533794 -70.170712)
			(xy 264.457545 -70.135164) (xy 264.384993 -70.092578) (xy 264.316784 -70.043333) (xy 264.253528 -69.987869)
			(xy 264.195791 -69.926681) (xy 264.144087 -69.860317) (xy 264.098879 -69.789368) (xy 264.06057 -69.714469)
			(xy 264.029503 -69.636288) (xy 264.005954 -69.555523) (xy 263.990135 -69.472895) (xy 263.982186 -69.389144)
			(xy 263.981692 -69.34708) (xy 186.023153 -69.34708) (xy 186.017406 -69.350773) (xy 185.942125 -69.389584)
			(xy 185.863495 -69.421063) (xy 185.782228 -69.444924) (xy 185.699062 -69.460953) (xy 185.614748 -69.469004)
			(xy 185.5724 -69.469508) (xy 185.571892 -69.469508) (xy 185.52556 -69.468902) (xy 185.433402 -69.459231)
			(xy 185.342748 -69.440035) (xy 185.254579 -69.411523) (xy 185.211974 -69.393308) (xy 185.202032 -69.389502)
			(xy 185.180768 -69.389502) (xy 185.170826 -69.393308) (xy 185.128223 -69.41153) (xy 185.040056 -69.440048)
			(xy 184.9494 -69.45924) (xy 184.85724 -69.4689) (xy 184.810908 -69.469508) (xy 184.8104 -69.469508)
			(xy 184.768052 -69.469004) (xy 184.683738 -69.460953) (xy 184.600572 -69.444924) (xy 184.519305 -69.421063)
			(xy 184.440675 -69.389584) (xy 184.365394 -69.350773) (xy 184.294142 -69.304983) (xy 184.227566 -69.252627)
			(xy 184.166268 -69.194179) (xy 184.110803 -69.130169) (xy 184.061674 -69.061177) (xy 184.019325 -68.987827)
			(xy 183.984141 -68.910784) (xy 183.956439 -68.830745) (xy 183.936471 -68.748436) (xy 183.924418 -68.664601)
			(xy 183.920388 -68.58) (xy 182.426549 -68.58) (xy 182.466281 -68.589639) (xy 182.54632 -68.617341)
			(xy 182.623363 -68.652525) (xy 182.696713 -68.694874) (xy 182.765705 -68.744003) (xy 182.829715 -68.799468)
			(xy 182.888163 -68.860766) (xy 182.940519 -68.927342) (xy 182.986309 -68.998594) (xy 183.02512 -69.073875)
			(xy 183.056599 -69.152505) (xy 183.08046 -69.233772) (xy 183.096489 -69.316938) (xy 183.10454 -69.401252)
			(xy 183.105044 -69.4436) (xy 183.105044 -69.444362) (xy 183.104477 -69.489611) (xy 183.095255 -69.579637)
			(xy 183.076932 -69.66826) (xy 183.049699 -69.754562) (xy 183.013837 -69.837651) (xy 182.992268 -69.877432)
			(xy 182.98741 -69.887417) (xy 182.985813 -69.909537) (xy 182.98922 -69.920104) (xy 183.020462 -70.003416)
			(xy 183.03621 -70.01891) (xy 183.046878 -70.02272) (xy 183.08635 -70.037268) (xy 183.162598 -70.072818)
			(xy 183.23515 -70.115407) (xy 183.303358 -70.164655) (xy 183.366613 -70.220121) (xy 183.424349 -70.28131)
			(xy 183.476052 -70.347676) (xy 183.521259 -70.418626) (xy 183.559567 -70.493527) (xy 183.590634 -70.571709)
			(xy 183.614182 -70.652475) (xy 183.630002 -70.735103) (xy 183.63795 -70.818856) (xy 183.638444 -70.86092)
			(xy 183.63794 -70.903268) (xy 183.629889 -70.987582) (xy 183.61386 -71.070748) (xy 183.589999 -71.152015)
			(xy 183.55852 -71.230645) (xy 183.519709 -71.305926) (xy 183.473919 -71.377178) (xy 183.421563 -71.443754)
			(xy 183.363115 -71.505052) (xy 183.299105 -71.560517) (xy 183.275677 -71.5772) (xy 260.602988 -71.5772)
			(xy 260.607018 -71.492599) (xy 260.619071 -71.408764) (xy 260.639039 -71.326455) (xy 260.666741 -71.246416)
			(xy 260.701925 -71.169373) (xy 260.744274 -71.096023) (xy 260.793403 -71.027031) (xy 260.848868 -70.963021)
			(xy 260.910166 -70.904573) (xy 260.976742 -70.852217) (xy 261.047994 -70.806427) (xy 261.123275 -70.767616)
			(xy 261.201905 -70.736137) (xy 261.283172 -70.712276) (xy 261.366338 -70.696247) (xy 261.450652 -70.688196)
			(xy 261.493 -70.687692) (xy 261.493508 -70.687692) (xy 261.53984 -70.688298) (xy 261.631998 -70.697969)
			(xy 261.722652 -70.717165) (xy 261.810821 -70.745677) (xy 261.853426 -70.763892) (xy 261.863368 -70.767698)
			(xy 261.884632 -70.767698) (xy 261.894574 -70.763892) (xy 261.937177 -70.74567) (xy 262.025344 -70.717152)
			(xy 262.116 -70.69796) (xy 262.20816 -70.6883) (xy 262.254492 -70.687692) (xy 262.255 -70.687692)
			(xy 262.297348 -70.688196) (xy 262.381662 -70.696247) (xy 262.464828 -70.712276) (xy 262.546095 -70.736137)
			(xy 262.624725 -70.767616) (xy 262.700006 -70.806427) (xy 262.771258 -70.852217) (xy 262.837834 -70.904573)
			(xy 262.899132 -70.963021) (xy 262.954597 -71.027031) (xy 263.003726 -71.096023) (xy 263.046075 -71.169373)
			(xy 263.081259 -71.246416) (xy 263.108961 -71.326455) (xy 263.128929 -71.408764) (xy 263.140982 -71.492599)
			(xy 263.145013 -71.5772) (xy 263.140982 -71.661801) (xy 263.128929 -71.745636) (xy 263.108961 -71.827945)
			(xy 263.081259 -71.907984) (xy 263.046075 -71.985027) (xy 263.003726 -72.058377) (xy 262.954597 -72.127369)
			(xy 262.899132 -72.191379) (xy 262.837834 -72.249827) (xy 262.771258 -72.302183) (xy 262.700006 -72.347973)
			(xy 262.624725 -72.386784) (xy 262.546095 -72.418263) (xy 262.464828 -72.442124) (xy 262.381662 -72.458153)
			(xy 262.297348 -72.466204) (xy 262.255 -72.466708) (xy 262.254492 -72.466708) (xy 262.20816 -72.466102)
			(xy 262.116002 -72.456431) (xy 262.025348 -72.437235) (xy 261.937179 -72.408723) (xy 261.894574 -72.390508)
			(xy 261.884632 -72.386702) (xy 261.863368 -72.386702) (xy 261.853426 -72.390508) (xy 261.810823 -72.40873)
			(xy 261.722656 -72.437248) (xy 261.632 -72.45644) (xy 261.53984 -72.4661) (xy 261.493508 -72.466708)
			(xy 261.493 -72.466708) (xy 261.450652 -72.466204) (xy 261.366338 -72.458153) (xy 261.283172 -72.442124)
			(xy 261.201905 -72.418263) (xy 261.123275 -72.386784) (xy 261.047994 -72.347973) (xy 260.976742 -72.302183)
			(xy 260.910166 -72.249827) (xy 260.848868 -72.191379) (xy 260.793403 -72.127369) (xy 260.744274 -72.058377)
			(xy 260.701925 -71.985027) (xy 260.666741 -71.907984) (xy 260.639039 -71.827945) (xy 260.619071 -71.745636)
			(xy 260.607018 -71.661801) (xy 260.602988 -71.5772) (xy 183.275677 -71.5772) (xy 183.230113 -71.609646)
			(xy 183.156763 -71.651995) (xy 183.07972 -71.687179) (xy 182.999681 -71.714881) (xy 182.917372 -71.734849)
			(xy 182.833537 -71.746902) (xy 182.748936 -71.750933) (xy 182.664335 -71.746902) (xy 182.5805 -71.734849)
			(xy 182.498191 -71.714881) (xy 182.418152 -71.687179) (xy 182.341109 -71.651995) (xy 182.267759 -71.609646)
			(xy 182.198767 -71.560517) (xy 182.134757 -71.505052) (xy 182.076309 -71.443754) (xy 182.023953 -71.377178)
			(xy 181.978163 -71.305926) (xy 181.939352 -71.230645) (xy 181.907873 -71.152015) (xy 181.884012 -71.070748)
			(xy 181.867983 -70.987582) (xy 181.859932 -70.903268) (xy 181.859428 -70.86092) (xy 181.859428 -70.860158)
			(xy 181.860007 -70.81491) (xy 181.869227 -70.724884) (xy 181.887547 -70.636261) (xy 181.914778 -70.549959)
			(xy 181.950636 -70.466869) (xy 181.972204 -70.427088) (xy 181.977111 -70.417122) (xy 181.978678 -70.394985)
			(xy 181.975252 -70.384416) (xy 181.94401 -70.301104) (xy 181.928262 -70.28561) (xy 181.917594 -70.2818)
			(xy 181.878145 -70.267193) (xy 181.801896 -70.23165) (xy 181.729343 -70.189068) (xy 181.661134 -70.139826)
			(xy 181.597877 -70.084366) (xy 181.540139 -70.023182) (xy 181.488434 -69.956821) (xy 181.443225 -69.885875)
			(xy 181.404914 -69.810979) (xy 181.373845 -69.7328) (xy 181.350295 -69.652037) (xy 181.334473 -69.569413)
			(xy 181.326523 -69.485663) (xy 181.326028 -69.4436) (xy 180.350534 -69.4436) (xy 180.323962 -69.520376)
			(xy 180.28878 -69.597418) (xy 180.246433 -69.670766) (xy 180.197307 -69.739757) (xy 180.141844 -69.803766)
			(xy 180.080549 -69.862214) (xy 180.013976 -69.91457) (xy 179.942727 -69.960361) (xy 179.867448 -69.999173)
			(xy 179.788821 -70.030653) (xy 179.707558 -70.054517) (xy 179.624394 -70.070549) (xy 179.540083 -70.078603)
			(xy 179.497736 -70.079108) (xy 179.497228 -70.079108) (xy 179.45848 -70.078658) (xy 179.38128 -70.0719)
			(xy 179.304961 -70.058451) (xy 179.230101 -70.038412) (xy 179.157268 -70.011936) (xy 179.087016 -69.979222)
			(xy 179.053236 -69.960236) (xy 179.045362 -69.956077) (xy 179.027836 -69.952983) (xy 179.01031 -69.956077)
			(xy 179.002436 -69.960236) (xy 178.968662 -69.979233) (xy 178.898407 -70.011945) (xy 178.825574 -70.038422)
			(xy 178.750713 -70.058462) (xy 178.674393 -70.071915) (xy 178.597192 -70.078678) (xy 178.558444 -70.079108)
			(xy 178.557936 -70.079108) (xy 178.515586 -70.078622) (xy 178.431268 -70.070573) (xy 178.348098 -70.054547)
			(xy 178.266827 -70.030686) (xy 178.188193 -69.999209) (xy 178.112907 -69.960399) (xy 178.041651 -69.914608)
			(xy 177.97507 -69.862251) (xy 177.913768 -69.803802) (xy 177.8583 -69.739791) (xy 177.809168 -69.670796)
			(xy 177.766817 -69.597444) (xy 177.73163 -69.520398) (xy 177.703926 -69.440356) (xy 177.683957 -69.358043)
			(xy 177.671902 -69.274205) (xy 177.667872 -69.1896) (xy 143.804198 -69.1896) (xy 143.823089 -69.251765)
			(xy 143.840228 -69.337814) (xy 143.848829 -69.42513) (xy 143.849344 -69.469) (xy 143.848824 -69.512819)
			(xy 143.840185 -69.60003) (xy 143.82303 -69.685972) (xy 143.797525 -69.769817) (xy 143.763915 -69.850753)
			(xy 143.74368 -69.889624) (xy 143.738368 -69.90098) (xy 143.738368 -69.92602) (xy 143.74368 -69.937376)
			(xy 143.763922 -69.976244) (xy 143.797557 -70.057173) (xy 143.82307 -70.141017) (xy 143.840214 -70.226964)
			(xy 143.848823 -70.31418) (xy 143.849344 -70.358) (xy 143.84884 -70.400397) (xy 143.84078 -70.484807)
			(xy 143.824732 -70.568068) (xy 143.800843 -70.649427) (xy 143.769328 -70.728147) (xy 143.730474 -70.803515)
			(xy 143.684631 -70.874848) (xy 143.632215 -70.9415) (xy 143.5737 -71.002868) (xy 143.509618 -71.058396)
			(xy 143.440547 -71.107581) (xy 143.367113 -71.149978) (xy 143.289982 -71.185203) (xy 143.209852 -71.212936)
			(xy 143.127448 -71.232927) (xy 143.043518 -71.244994) (xy 142.95882 -71.249029) (xy 142.874122 -71.244994)
			(xy 142.790192 -71.232927) (xy 142.707788 -71.212936) (xy 142.627658 -71.185203) (xy 142.550527 -71.149978)
			(xy 142.477093 -71.107581) (xy 142.408022 -71.058396) (xy 142.34394 -71.002868) (xy 142.285425 -70.9415)
			(xy 142.233009 -70.874848) (xy 142.187166 -70.803515) (xy 142.148312 -70.728147) (xy 142.116797 -70.649427)
			(xy 142.092908 -70.568068) (xy 142.07686 -70.484807) (xy 142.0688 -70.400397) (xy 142.068296 -70.358)
			(xy 142.068812 -70.314181) (xy 142.077451 -70.22697) (xy 142.094607 -70.141027) (xy 142.120113 -70.057183)
			(xy 142.153725 -69.976247) (xy 142.17396 -69.937376) (xy 142.179269 -69.92602) (xy 142.179269 -69.90098)
			(xy 142.17396 -69.889624) (xy 142.153713 -69.850758) (xy 142.12008 -69.769829) (xy 142.094568 -69.685984)
			(xy 142.077425 -69.600037) (xy 142.068817 -69.51282) (xy 142.068296 -69.469) (xy 142.068784 -69.425129)
			(xy 142.077376 -69.337809) (xy 142.094516 -69.251758) (xy 142.120037 -69.16781) (xy 142.153693 -69.08678)
			(xy 142.17396 -69.047868) (xy 142.179366 -69.036553) (xy 142.179479 -69.0115) (xy 142.174214 -69.000116)
			(xy 142.154023 -68.961286) (xy 142.120474 -68.880446) (xy 142.095025 -68.796702) (xy 142.07792 -68.710865)
			(xy 142.069327 -68.623763) (xy 142.068804 -68.58) (xy 142.069352 -68.536149) (xy 142.077992 -68.448872)
			(xy 142.095177 -68.362869) (xy 142.120741 -68.278975) (xy 142.154437 -68.198003) (xy 142.174722 -68.159122)
			(xy 142.180144 -68.147657) (xy 142.18014 -68.122329) (xy 142.174722 -68.110862) (xy 142.154472 -68.071891)
			(xy 142.120849 -67.990752) (xy 142.095381 -67.906695) (xy 142.08633 -67.86372) (xy 142.082774 -67.845686)
			(xy 142.054834 -67.822826) (xy 140.90904 -67.822826) (xy 140.89952 -67.823236) (xy 140.881795 -67.830194)
			(xy 140.867822 -67.84313) (xy 140.86332 -67.851528) (xy 140.844752 -67.888594) (xy 140.801694 -67.959444)
			(xy 140.752233 -68.025982) (xy 140.696797 -68.08763) (xy 140.635867 -68.143854) (xy 140.56997 -68.194166)
			(xy 140.49968 -68.238131) (xy 140.425604 -68.275367) (xy 140.348386 -68.30555) (xy 140.268695 -68.32842)
			(xy 140.187222 -68.343777) (xy 140.104674 -68.351489) (xy 140.021766 -68.351489) (xy 139.939218 -68.343777)
			(xy 139.857745 -68.32842) (xy 139.778054 -68.30555) (xy 139.700836 -68.275367) (xy 139.62676 -68.238131)
			(xy 139.55647 -68.194166) (xy 139.490573 -68.143854) (xy 139.429643 -68.08763) (xy 139.374207 -68.025982)
			(xy 139.324746 -67.959444) (xy 139.281688 -67.888594) (xy 139.26312 -67.851528) (xy 139.258628 -67.843121)
			(xy 139.244657 -67.830174) (xy 139.226924 -67.823221) (xy 139.2174 -67.822826) (xy 138.0871 -67.822826)
			(xy 138.07703 -67.823245) (xy 138.058432 -67.830969) (xy 138.051032 -67.837812) (xy 137.389616 -68.499228)
			(xy 137.382773 -68.506626) (xy 137.375054 -68.525227) (xy 137.37463 -68.535296) (xy 137.37463 -71.85406)
			(xy 149.046184 -71.85406) (xy 149.046695 -71.811643) (xy 149.054765 -71.727194) (xy 149.070836 -71.643896)
			(xy 149.094764 -71.562507) (xy 149.12633 -71.483764) (xy 149.165248 -71.408384) (xy 149.211164 -71.33705)
			(xy 149.263662 -71.270412) (xy 149.322265 -71.209073) (xy 149.354032 -71.18096) (xy 149.361938 -71.173399)
			(xy 149.371032 -71.153531) (xy 149.371558 -71.142606) (xy 149.371558 -71.06539) (xy 149.371056 -71.054461)
			(xy 149.361953 -71.034585) (xy 149.354032 -71.027036) (xy 149.322275 -70.998912) (xy 149.263673 -70.937573)
			(xy 149.211174 -70.870935) (xy 149.165256 -70.799603) (xy 149.126335 -70.724225) (xy 149.094765 -70.645485)
			(xy 149.070832 -70.564097) (xy 149.054754 -70.480801) (xy 149.046677 -70.396353) (xy 149.046184 -70.353936)
			(xy 149.046688 -70.311588) (xy 149.054739 -70.227274) (xy 149.070768 -70.144108) (xy 149.094629 -70.062841)
			(xy 149.126108 -69.984211) (xy 149.164919 -69.90893) (xy 149.210709 -69.837678) (xy 149.263065 -69.771102)
			(xy 149.321513 -69.709804) (xy 149.385523 -69.654339) (xy 149.454515 -69.60521) (xy 149.527865 -69.562861)
			(xy 149.604908 -69.527677) (xy 149.684947 -69.499975) (xy 149.767256 -69.480007) (xy 149.851091 -69.467954)
			(xy 149.935692 -69.463924) (xy 150.020293 -69.467954) (xy 150.104128 -69.480007) (xy 150.186437 -69.499975)
			(xy 150.266476 -69.527677) (xy 150.343519 -69.562861) (xy 150.416869 -69.60521) (xy 150.485861 -69.654339)
			(xy 150.549871 -69.709804) (xy 150.608319 -69.771102) (xy 150.660675 -69.837678) (xy 150.706465 -69.90893)
			(xy 150.745276 -69.984211) (xy 150.776755 -70.062841) (xy 150.800616 -70.144108) (xy 150.816645 -70.227274)
			(xy 150.824696 -70.311588) (xy 150.8252 -70.353936) (xy 150.824691 -70.396353) (xy 150.816622 -70.480803)
			(xy 150.800551 -70.5641) (xy 150.776623 -70.64549) (xy 150.745057 -70.724233) (xy 150.706139 -70.799613)
			(xy 150.660221 -70.870946) (xy 150.607723 -70.937585) (xy 150.549119 -70.998924) (xy 150.517352 -71.027036)
			(xy 150.509446 -71.034596) (xy 150.500353 -71.054465) (xy 150.499826 -71.06539) (xy 150.499826 -71.142606)
			(xy 150.500336 -71.153534) (xy 150.509433 -71.173409) (xy 150.517352 -71.18096) (xy 150.549103 -71.20909)
			(xy 150.607707 -71.270428) (xy 150.660206 -71.337064) (xy 150.706125 -71.408396) (xy 150.745047 -71.483773)
			(xy 150.776617 -71.562513) (xy 150.800551 -71.6439) (xy 150.816629 -71.727196) (xy 150.824707 -71.811643)
			(xy 150.8252 -71.85406) (xy 150.824696 -71.896408) (xy 150.816645 -71.980722) (xy 150.811195 -72.009)
			(xy 177.667872 -72.009) (xy 177.671902 -71.924395) (xy 177.683957 -71.840557) (xy 177.703926 -71.758244)
			(xy 177.73163 -71.678202) (xy 177.766817 -71.601156) (xy 177.809168 -71.527804) (xy 177.8583 -71.458809)
			(xy 177.913768 -71.394798) (xy 177.97507 -71.336349) (xy 178.041651 -71.283992) (xy 178.112907 -71.238201)
			(xy 178.188193 -71.199391) (xy 178.266827 -71.167914) (xy 178.348098 -71.144053) (xy 178.431268 -71.128027)
			(xy 178.515586 -71.119978) (xy 178.557936 -71.119492) (xy 178.596727 -71.119889) (xy 178.674016 -71.126624)
			(xy 178.750424 -71.140065) (xy 178.825371 -71.16011) (xy 178.898288 -71.186607) (xy 178.968619 -71.219355)
			(xy 179.002436 -71.238364) (xy 179.01031 -71.242523) (xy 179.027836 -71.245617) (xy 179.045362 -71.242523)
			(xy 179.053236 -71.238364) (xy 179.087054 -71.219359) (xy 179.157387 -71.186616) (xy 179.230303 -71.160122)
			(xy 179.30525 -71.140079) (xy 179.381658 -71.126639) (xy 179.458946 -71.119903) (xy 179.497736 -71.119492)
			(xy 179.540083 -71.119997) (xy 179.624394 -71.128051) (xy 179.707558 -71.144083) (xy 179.788821 -71.167947)
			(xy 179.867448 -71.199427) (xy 179.942727 -71.238239) (xy 180.013976 -71.28403) (xy 180.080549 -71.336386)
			(xy 180.141844 -71.394834) (xy 180.197307 -71.458843) (xy 180.246433 -71.527834) (xy 180.28878 -71.601182)
			(xy 180.323962 -71.678224) (xy 180.351663 -71.758261) (xy 180.37163 -71.840568) (xy 180.383683 -71.924401)
			(xy 180.387713 -72.009) (xy 180.383683 -72.093599) (xy 180.37163 -72.177432) (xy 180.351663 -72.259739)
			(xy 180.323962 -72.339776) (xy 180.28878 -72.416818) (xy 180.246433 -72.490166) (xy 180.197307 -72.559157)
			(xy 180.141844 -72.623166) (xy 180.080549 -72.681614) (xy 180.013976 -72.73397) (xy 179.942727 -72.779761)
			(xy 179.867448 -72.818573) (xy 179.788821 -72.850053) (xy 179.707558 -72.873917) (xy 179.624394 -72.889949)
			(xy 179.540083 -72.898003) (xy 179.497736 -72.898508) (xy 179.458945 -72.898124) (xy 179.381656 -72.891387)
			(xy 179.305247 -72.877943) (xy 179.2303 -72.857895) (xy 179.157383 -72.831396) (xy 179.087053 -72.798646)
			(xy 179.053236 -72.779636) (xy 179.045362 -72.775477) (xy 179.027836 -72.772383) (xy 179.01031 -72.775477)
			(xy 179.002436 -72.779636) (xy 178.968624 -72.798653) (xy 178.89829 -72.831394) (xy 178.825372 -72.857885)
			(xy 178.750424 -72.877926) (xy 178.674015 -72.891365) (xy 178.596727 -72.898098) (xy 178.557936 -72.898508)
			(xy 178.515586 -72.898022) (xy 178.431268 -72.889973) (xy 178.348098 -72.873947) (xy 178.266827 -72.850086)
			(xy 178.188193 -72.818609) (xy 178.112907 -72.779799) (xy 178.041651 -72.734008) (xy 177.97507 -72.681651)
			(xy 177.913768 -72.623202) (xy 177.8583 -72.559191) (xy 177.809168 -72.490196) (xy 177.766817 -72.416844)
			(xy 177.73163 -72.339798) (xy 177.703926 -72.259756) (xy 177.683957 -72.177443) (xy 177.671902 -72.093605)
			(xy 177.667872 -72.009) (xy 150.811195 -72.009) (xy 150.800616 -72.063888) (xy 150.776755 -72.145155)
			(xy 150.745276 -72.223785) (xy 150.706465 -72.299066) (xy 150.660675 -72.370318) (xy 150.608319 -72.436894)
			(xy 150.549871 -72.498192) (xy 150.485861 -72.553657) (xy 150.416869 -72.602786) (xy 150.343519 -72.645135)
			(xy 150.266476 -72.680319) (xy 150.186437 -72.708021) (xy 150.104128 -72.727989) (xy 150.020293 -72.740042)
			(xy 149.935692 -72.744073) (xy 149.851091 -72.740042) (xy 149.767256 -72.727989) (xy 149.684947 -72.708021)
			(xy 149.604908 -72.680319) (xy 149.527865 -72.645135) (xy 149.454515 -72.602786) (xy 149.385523 -72.553657)
			(xy 149.321513 -72.498192) (xy 149.263065 -72.436894) (xy 149.210709 -72.370318) (xy 149.164919 -72.299066)
			(xy 149.126108 -72.223785) (xy 149.094629 -72.145155) (xy 149.070768 -72.063888) (xy 149.054739 -71.980722)
			(xy 149.046688 -71.896408) (xy 149.046184 -71.85406) (xy 137.37463 -71.85406) (xy 137.37463 -74.360278)
			(xy 144.226788 -74.360278) (xy 144.227274 -74.317132) (xy 144.23562 -74.231244) (xy 144.252241 -74.146568)
			(xy 144.276981 -74.063898) (xy 144.309607 -73.984012) (xy 144.349813 -73.907659) (xy 144.373092 -73.871328)
			(xy 144.377639 -73.863717) (xy 144.381747 -73.846485) (xy 144.37974 -73.828884) (xy 144.37614 -73.820782)
			(xy 144.358096 -73.78366) (xy 144.328174 -73.706728) (xy 144.305503 -73.627357) (xy 144.290279 -73.546227)
			(xy 144.28263 -73.464037) (xy 144.28216 -73.422764) (xy 144.28216 -73.42251) (xy 144.282664 -73.380162)
			(xy 144.290715 -73.295848) (xy 144.306744 -73.212682) (xy 144.330605 -73.131415) (xy 144.362084 -73.052785)
			(xy 144.400895 -72.977504) (xy 144.446685 -72.906252) (xy 144.499041 -72.839676) (xy 144.557489 -72.778378)
			(xy 144.621499 -72.722913) (xy 144.690491 -72.673784) (xy 144.763841 -72.631435) (xy 144.840884 -72.596251)
			(xy 144.920923 -72.568549) (xy 145.003232 -72.548581) (xy 145.087067 -72.536528) (xy 145.171668 -72.532498)
			(xy 145.256269 -72.536528) (xy 145.340104 -72.548581) (xy 145.422413 -72.568549) (xy 145.502452 -72.596251)
			(xy 145.579495 -72.631435) (xy 145.652845 -72.673784) (xy 145.721837 -72.722913) (xy 145.785847 -72.778378)
			(xy 145.844295 -72.839676) (xy 145.896651 -72.906252) (xy 145.942441 -72.977504) (xy 145.981252 -73.052785)
			(xy 146.012731 -73.131415) (xy 146.036592 -73.212682) (xy 146.052621 -73.295848) (xy 146.060672 -73.380162)
			(xy 146.061176 -73.42251) (xy 146.061176 -73.423272) (xy 146.060668 -73.466348) (xy 146.052315 -73.552094)
			(xy 146.035714 -73.636632) (xy 146.011019 -73.719169) (xy 145.978463 -73.798933) (xy 145.93835 -73.875177)
			(xy 145.915126 -73.91146) (xy 145.910587 -73.919075) (xy 145.906476 -73.936305) (xy 145.908479 -73.953905)
			(xy 145.912078 -73.962006) (xy 145.930176 -73.999137) (xy 145.960164 -74.076112) (xy 145.982889 -74.155534)
			(xy 145.998156 -74.236721) (xy 146.005833 -74.318973) (xy 146.006046 -74.337361) (xy 183.260742 -74.337361)
			(xy 183.260742 -74.252639) (xy 183.268795 -74.168302) (xy 183.284829 -74.085112) (xy 183.308697 -74.003822)
			(xy 183.340185 -73.92517) (xy 183.379007 -73.849867) (xy 183.42481 -73.778595) (xy 183.477181 -73.711999)
			(xy 183.535646 -73.650684) (xy 183.599674 -73.595203) (xy 183.668686 -73.54606) (xy 183.742056 -73.5037)
			(xy 183.819121 -73.468505) (xy 183.899183 -73.440796) (xy 183.981516 -73.420822) (xy 184.065375 -73.408765)
			(xy 184.15 -73.404734) (xy 184.234625 -73.408765) (xy 184.318484 -73.420822) (xy 184.400817 -73.440796)
			(xy 184.480879 -73.468505) (xy 184.557944 -73.5037) (xy 184.631314 -73.54606) (xy 184.700326 -73.595203)
			(xy 184.764354 -73.650684) (xy 184.822819 -73.711999) (xy 184.87519 -73.778595) (xy 184.920993 -73.849867)
			(xy 184.940962 -73.8886) (xy 266.368788 -73.8886) (xy 266.372818 -73.803999) (xy 266.384871 -73.720164)
			(xy 266.404839 -73.637855) (xy 266.432541 -73.557816) (xy 266.467725 -73.480773) (xy 266.510074 -73.407423)
			(xy 266.559203 -73.338431) (xy 266.614668 -73.274421) (xy 266.675966 -73.215973) (xy 266.742542 -73.163617)
			(xy 266.813794 -73.117827) (xy 266.889075 -73.079016) (xy 266.967705 -73.047537) (xy 267.048972 -73.023676)
			(xy 267.132138 -73.007647) (xy 267.216452 -72.999596) (xy 267.2588 -72.999092) (xy 267.259562 -72.999092)
			(xy 267.297909 -72.999501) (xy 267.374317 -73.006133) (xy 267.449868 -73.019325) (xy 267.524002 -73.038978)
			(xy 267.596166 -73.064947) (xy 267.631164 -73.080626) (xy 267.641437 -73.084766) (xy 267.663563 -73.084766)
			(xy 267.673836 -73.080626) (xy 267.708833 -73.064947) (xy 267.781003 -73.039) (xy 267.855138 -73.019357)
			(xy 267.930687 -73.006163) (xy 268.007092 -72.999518) (xy 268.045438 -72.999092) (xy 268.0462 -72.999092)
			(xy 268.088548 -72.999596) (xy 268.172862 -73.007647) (xy 268.256028 -73.023676) (xy 268.337295 -73.047537)
			(xy 268.415925 -73.079016) (xy 268.491206 -73.117827) (xy 268.562458 -73.163617) (xy 268.629034 -73.215973)
			(xy 268.690332 -73.274421) (xy 268.745797 -73.338431) (xy 268.794926 -73.407423) (xy 268.837275 -73.480773)
			(xy 268.872459 -73.557816) (xy 268.900161 -73.637855) (xy 268.920129 -73.720164) (xy 268.932182 -73.803999)
			(xy 268.936213 -73.8886) (xy 268.932182 -73.973201) (xy 268.920129 -74.057036) (xy 268.900161 -74.139345)
			(xy 268.872459 -74.219384) (xy 268.837275 -74.296427) (xy 268.794926 -74.369777) (xy 268.745797 -74.438769)
			(xy 268.697852 -74.4941) (xy 303.021024 -74.4941) (xy 303.025053 -74.409502) (xy 303.037107 -74.325671)
			(xy 303.057074 -74.243365) (xy 303.084774 -74.163329) (xy 303.119957 -74.086289) (xy 303.162304 -74.012942)
			(xy 303.211431 -73.943953) (xy 303.266894 -73.879946) (xy 303.328189 -73.821501) (xy 303.394763 -73.769147)
			(xy 303.466012 -73.723358) (xy 303.54129 -73.684549) (xy 303.619917 -73.653071) (xy 303.70118 -73.629211)
			(xy 303.784343 -73.613182) (xy 303.868653 -73.605132) (xy 303.911 -73.604628) (xy 303.951046 -73.605059)
			(xy 304.030815 -73.612254) (xy 304.109614 -73.626586) (xy 304.186807 -73.647939) (xy 304.26177 -73.67614)
			(xy 304.333897 -73.710962) (xy 304.402603 -73.752123) (xy 304.467334 -73.799289) (xy 304.49774 -73.825354)
			(xy 304.504826 -73.831124) (xy 304.521886 -73.837632) (xy 304.531014 -73.838054) (xy 304.560986 -73.838054)
			(xy 304.570108 -73.837612) (xy 304.587158 -73.831097) (xy 304.59426 -73.825354) (xy 304.624664 -73.799286)
			(xy 304.689385 -73.752101) (xy 304.758087 -73.710928) (xy 304.830213 -73.676099) (xy 304.905178 -73.647896)
			(xy 304.982375 -73.626549) (xy 305.06118 -73.61223) (xy 305.140952 -73.605055) (xy 305.181 -73.604628)
			(xy 305.22335 -73.60506) (xy 305.307667 -73.613111) (xy 305.390837 -73.629141) (xy 305.472106 -73.653003)
			(xy 305.55074 -73.684483) (xy 305.626024 -73.723295) (xy 305.697279 -73.769088) (xy 305.763858 -73.821446)
			(xy 305.825158 -73.879896) (xy 305.880625 -73.943909) (xy 305.929756 -74.012903) (xy 305.972107 -74.086256)
			(xy 306.007292 -74.163302) (xy 306.034995 -74.243344) (xy 306.054964 -74.325657) (xy 306.067018 -74.409496)
			(xy 306.071049 -74.4941) (xy 306.067018 -74.578704) (xy 306.054964 -74.662543) (xy 306.034995 -74.744856)
			(xy 306.007292 -74.824898) (xy 305.972107 -74.901944) (xy 305.929756 -74.975297) (xy 305.880625 -75.044291)
			(xy 305.825158 -75.108304) (xy 305.763858 -75.166754) (xy 305.697279 -75.219112) (xy 305.626024 -75.264905)
			(xy 305.55074 -75.303717) (xy 305.472106 -75.335197) (xy 305.390837 -75.359059) (xy 305.307667 -75.375089)
			(xy 305.22335 -75.38314) (xy 305.181 -75.383644) (xy 305.140954 -75.38322) (xy 305.061185 -75.376025)
			(xy 304.982385 -75.361692) (xy 304.905191 -75.340339) (xy 304.830228 -75.312136) (xy 304.758102 -75.277313)
			(xy 304.689396 -75.236152) (xy 304.624665 -75.188984) (xy 304.59426 -75.162918) (xy 304.587168 -75.157157)
			(xy 304.570113 -75.150642) (xy 304.560986 -75.150218) (xy 304.531014 -75.150218) (xy 304.521893 -75.150666)
			(xy 304.504843 -75.157178) (xy 304.49774 -75.162918) (xy 304.467332 -75.188982) (xy 304.402612 -75.236167)
			(xy 304.333911 -75.277342) (xy 304.261786 -75.312171) (xy 304.186821 -75.340374) (xy 304.109624 -75.361722)
			(xy 304.03082 -75.376042) (xy 303.951047 -75.383217) (xy 303.911 -75.383644) (xy 303.868653 -75.383068)
			(xy 303.784343 -75.375018) (xy 303.70118 -75.358989) (xy 303.619917 -75.335129) (xy 303.54129 -75.303651)
			(xy 303.466012 -75.264842) (xy 303.394763 -75.219053) (xy 303.328189 -75.166699) (xy 303.266894 -75.108254)
			(xy 303.211431 -75.044247) (xy 303.162304 -74.975258) (xy 303.119957 -74.901911) (xy 303.084774 -74.824871)
			(xy 303.057074 -74.744835) (xy 303.037107 -74.662529) (xy 303.025053 -74.578698) (xy 303.021024 -74.4941)
			(xy 268.697852 -74.4941) (xy 268.690332 -74.502779) (xy 268.629034 -74.561227) (xy 268.562458 -74.613583)
			(xy 268.491206 -74.659373) (xy 268.415925 -74.698184) (xy 268.337295 -74.729663) (xy 268.256028 -74.753524)
			(xy 268.172862 -74.769553) (xy 268.088548 -74.777604) (xy 268.0462 -74.778108) (xy 268.045438 -74.778108)
			(xy 268.007091 -74.777699) (xy 267.930683 -74.771067) (xy 267.855132 -74.757875) (xy 267.780998 -74.738222)
			(xy 267.708834 -74.712253) (xy 267.673836 -74.696574) (xy 267.663563 -74.692434) (xy 267.641437 -74.692434)
			(xy 267.631164 -74.696574) (xy 267.596167 -74.712253) (xy 267.523997 -74.7382) (xy 267.449862 -74.757843)
			(xy 267.374313 -74.771037) (xy 267.297908 -74.777682) (xy 267.259562 -74.778108) (xy 267.2588 -74.778108)
			(xy 267.216452 -74.777604) (xy 267.132138 -74.769553) (xy 267.048972 -74.753524) (xy 266.967705 -74.729663)
			(xy 266.889075 -74.698184) (xy 266.813794 -74.659373) (xy 266.742542 -74.613583) (xy 266.675966 -74.561227)
			(xy 266.614668 -74.502779) (xy 266.559203 -74.438769) (xy 266.510074 -74.369777) (xy 266.467725 -74.296427)
			(xy 266.432541 -74.219384) (xy 266.404839 -74.139345) (xy 266.384871 -74.057036) (xy 266.372818 -73.973201)
			(xy 266.368788 -73.8886) (xy 184.940962 -73.8886) (xy 184.959815 -73.92517) (xy 184.991303 -74.003822)
			(xy 185.015171 -74.085112) (xy 185.031205 -74.168302) (xy 185.039258 -74.252639) (xy 185.039762 -74.295)
			(xy 185.039258 -74.337361) (xy 185.031205 -74.421698) (xy 185.015171 -74.504888) (xy 184.991303 -74.586178)
			(xy 184.959815 -74.66483) (xy 184.920993 -74.740133) (xy 184.87519 -74.811405) (xy 184.822819 -74.878001)
			(xy 184.764354 -74.939316) (xy 184.700326 -74.994797) (xy 184.631314 -75.04394) (xy 184.557944 -75.0863)
			(xy 184.480879 -75.121495) (xy 184.400817 -75.149204) (xy 184.318484 -75.169178) (xy 184.234625 -75.181235)
			(xy 184.15 -75.185267) (xy 184.065375 -75.181235) (xy 183.981516 -75.169178) (xy 183.899183 -75.149204)
			(xy 183.819121 -75.121495) (xy 183.742056 -75.0863) (xy 183.668686 -75.04394) (xy 183.599674 -74.994797)
			(xy 183.535646 -74.939316) (xy 183.477181 -74.878001) (xy 183.42481 -74.811405) (xy 183.379007 -74.740133)
			(xy 183.340185 -74.66483) (xy 183.308697 -74.586178) (xy 183.284829 -74.504888) (xy 183.268795 -74.421698)
			(xy 183.260742 -74.337361) (xy 146.006046 -74.337361) (xy 146.006312 -74.360278) (xy 146.005808 -74.402639)
			(xy 145.997755 -74.486976) (xy 145.981721 -74.570166) (xy 145.957853 -74.651456) (xy 145.926365 -74.730108)
			(xy 145.887543 -74.805411) (xy 145.84174 -74.876683) (xy 145.789369 -74.943279) (xy 145.730904 -75.004594)
			(xy 145.666876 -75.060075) (xy 145.597864 -75.109218) (xy 145.524494 -75.151578) (xy 145.447429 -75.186773)
			(xy 145.367367 -75.214482) (xy 145.285034 -75.234456) (xy 145.201175 -75.246513) (xy 145.11655 -75.250545)
			(xy 145.031925 -75.246513) (xy 144.948066 -75.234456) (xy 144.865733 -75.214482) (xy 144.785671 -75.186773)
			(xy 144.708606 -75.151578) (xy 144.635236 -75.109218) (xy 144.566224 -75.060075) (xy 144.502196 -75.004594)
			(xy 144.443731 -74.943279) (xy 144.39136 -74.876683) (xy 144.345557 -74.805411) (xy 144.306735 -74.730108)
			(xy 144.275247 -74.651456) (xy 144.251379 -74.570166) (xy 144.235345 -74.486976) (xy 144.227292 -74.402639)
			(xy 144.226788 -74.360278) (xy 137.37463 -74.360278) (xy 137.37463 -75.861361) (xy 297.179742 -75.861361)
			(xy 297.179742 -75.776639) (xy 297.187795 -75.692302) (xy 297.203829 -75.609112) (xy 297.227697 -75.527822)
			(xy 297.259185 -75.44917) (xy 297.298007 -75.373867) (xy 297.34381 -75.302595) (xy 297.396181 -75.235999)
			(xy 297.454646 -75.174684) (xy 297.518674 -75.119203) (xy 297.587686 -75.07006) (xy 297.661056 -75.0277)
			(xy 297.738121 -74.992505) (xy 297.818183 -74.964796) (xy 297.900516 -74.944822) (xy 297.984375 -74.932765)
			(xy 298.069 -74.928734) (xy 298.153625 -74.932765) (xy 298.237484 -74.944822) (xy 298.319817 -74.964796)
			(xy 298.399879 -74.992505) (xy 298.476944 -75.0277) (xy 298.550314 -75.07006) (xy 298.619326 -75.119203)
			(xy 298.683354 -75.174684) (xy 298.741819 -75.235999) (xy 298.79419 -75.302595) (xy 298.839993 -75.373867)
			(xy 298.878815 -75.44917) (xy 298.910303 -75.527822) (xy 298.934171 -75.609112) (xy 298.950205 -75.692302)
			(xy 298.958258 -75.776639) (xy 298.958762 -75.819) (xy 298.958258 -75.861361) (xy 298.950205 -75.945698)
			(xy 298.934171 -76.028888) (xy 298.910303 -76.110178) (xy 298.878815 -76.18883) (xy 298.839993 -76.264133)
			(xy 298.810167 -76.310544) (xy 305.873647 -76.310544) (xy 305.873647 -76.181404) (xy 305.881597 -76.052509)
			(xy 305.897467 -75.924349) (xy 305.921196 -75.797408) (xy 305.952695 -75.672169) (xy 305.991844 -75.549106)
			(xy 306.038495 -75.428687) (xy 306.09247 -75.311368) (xy 306.153565 -75.197594) (xy 306.221548 -75.087797)
			(xy 306.296162 -74.982394) (xy 306.377123 -74.881784) (xy 306.464123 -74.786349) (xy 306.556834 -74.69645)
			(xy 306.654904 -74.612429) (xy 306.757959 -74.534605) (xy 306.86561 -74.463273) (xy 306.977449 -74.398703)
			(xy 307.09305 -74.341141) (xy 307.211975 -74.290804) (xy 307.333774 -74.247884) (xy 307.457984 -74.212543)
			(xy 307.584133 -74.184916) (xy 307.711745 -74.165107) (xy 307.840334 -74.153191) (xy 307.969412 -74.149215)
			(xy 308.09849 -74.153191) (xy 308.227079 -74.165107) (xy 308.354691 -74.184916) (xy 308.48084 -74.212543)
			(xy 308.60505 -74.247884) (xy 308.726849 -74.290804) (xy 308.845774 -74.341141) (xy 308.961375 -74.398703)
			(xy 309.073214 -74.463273) (xy 309.180865 -74.534605) (xy 309.28392 -74.612429) (xy 309.38199 -74.69645)
			(xy 309.474701 -74.786349) (xy 309.561701 -74.881784) (xy 309.642662 -74.982394) (xy 309.717276 -75.087797)
			(xy 309.785259 -75.197594) (xy 309.846354 -75.311368) (xy 309.900329 -75.428687) (xy 309.94698 -75.549106)
			(xy 309.986129 -75.672169) (xy 310.017628 -75.797408) (xy 310.041357 -75.924349) (xy 310.057227 -76.052509)
			(xy 310.065177 -76.181404) (xy 310.065674 -76.245974) (xy 310.065177 -76.310544) (xy 310.057227 -76.439439)
			(xy 310.041357 -76.567599) (xy 310.017628 -76.69454) (xy 309.986129 -76.819779) (xy 309.94698 -76.942842)
			(xy 309.900329 -77.063261) (xy 309.846354 -77.18058) (xy 309.785259 -77.294354) (xy 309.717276 -77.404151)
			(xy 309.642662 -77.509554) (xy 309.561701 -77.610164) (xy 309.474701 -77.705599) (xy 309.38199 -77.795498)
			(xy 309.28392 -77.879519) (xy 309.180865 -77.957343) (xy 309.073214 -78.028675) (xy 308.961375 -78.093245)
			(xy 308.845774 -78.150807) (xy 308.726849 -78.201144) (xy 308.60505 -78.244064) (xy 308.48084 -78.279405)
			(xy 308.354691 -78.307032) (xy 308.227079 -78.326841) (xy 308.09849 -78.338757) (xy 307.969412 -78.342734)
			(xy 307.840334 -78.338757) (xy 307.711745 -78.326841) (xy 307.584133 -78.307032) (xy 307.457984 -78.279405)
			(xy 307.333774 -78.244064) (xy 307.211975 -78.201144) (xy 307.09305 -78.150807) (xy 306.977449 -78.093245)
			(xy 306.86561 -78.028675) (xy 306.757959 -77.957343) (xy 306.654904 -77.879519) (xy 306.556834 -77.795498)
			(xy 306.464123 -77.705599) (xy 306.377123 -77.610164) (xy 306.296162 -77.509554) (xy 306.221548 -77.404151)
			(xy 306.153565 -77.294354) (xy 306.09247 -77.18058) (xy 306.038495 -77.063261) (xy 305.991844 -76.942842)
			(xy 305.952695 -76.819779) (xy 305.921196 -76.69454) (xy 305.897467 -76.567599) (xy 305.881597 -76.439439)
			(xy 305.873647 -76.310544) (xy 298.810167 -76.310544) (xy 298.79419 -76.335405) (xy 298.741819 -76.402001)
			(xy 298.683354 -76.463316) (xy 298.619326 -76.518797) (xy 298.550314 -76.56794) (xy 298.476944 -76.6103)
			(xy 298.399879 -76.645495) (xy 298.319817 -76.673204) (xy 298.237484 -76.693178) (xy 298.153625 -76.705235)
			(xy 298.069 -76.709267) (xy 297.984375 -76.705235) (xy 297.900516 -76.693178) (xy 297.818183 -76.673204)
			(xy 297.738121 -76.645495) (xy 297.661056 -76.6103) (xy 297.587686 -76.56794) (xy 297.518674 -76.518797)
			(xy 297.454646 -76.463316) (xy 297.396181 -76.402001) (xy 297.34381 -76.335405) (xy 297.298007 -76.264133)
			(xy 297.259185 -76.18883) (xy 297.227697 -76.110178) (xy 297.203829 -76.028888) (xy 297.187795 -75.945698)
			(xy 297.179742 -75.861361) (xy 137.37463 -75.861361) (xy 137.37463 -76.8584) (xy 142.64304 -76.8584)
			(xy 142.64707 -76.773794) (xy 142.659125 -76.689953) (xy 142.679094 -76.607639) (xy 142.706798 -76.527595)
			(xy 142.741985 -76.450547) (xy 142.784337 -76.377193) (xy 142.833469 -76.308197) (xy 142.888938 -76.244183)
			(xy 142.95024 -76.185733) (xy 143.016821 -76.133374) (xy 143.088078 -76.087581) (xy 143.163365 -76.048769)
			(xy 143.242 -76.017289) (xy 143.323272 -75.993427) (xy 143.406444 -75.977398) (xy 143.490763 -75.969347)
			(xy 143.533114 -75.96886) (xy 143.533368 -75.96886) (xy 143.576522 -75.969355) (xy 143.662423 -75.977737)
			(xy 143.747109 -75.994397) (xy 143.829784 -76.019177) (xy 143.909671 -76.051846) (xy 143.98602 -76.092095)
			(xy 144.058114 -76.139548) (xy 144.125275 -76.193757) (xy 144.15643 -76.223622) (xy 144.163594 -76.230101)
			(xy 144.181339 -76.237687) (xy 144.190974 -76.238354) (xy 144.270476 -76.239878) (xy 144.28851 -76.23302)
			(xy 144.295876 -76.226416) (xy 144.32649 -76.199346) (xy 144.391887 -76.150331) (xy 144.461506 -76.107524)
			(xy 144.534759 -76.071287) (xy 144.611029 -76.041924) (xy 144.689671 -76.019684) (xy 144.770022 -76.004754)
			(xy 144.851405 -75.997261) (xy 144.892268 -75.9968) (xy 144.892522 -75.9968) (xy 144.93487 -75.997289)
			(xy 145.019183 -76.005341) (xy 145.102348 -76.021372) (xy 145.183614 -76.045236) (xy 145.262242 -76.076716)
			(xy 145.337523 -76.115527) (xy 145.408773 -76.161318) (xy 145.475349 -76.213675) (xy 145.536645 -76.272123)
			(xy 145.592109 -76.336133) (xy 145.641237 -76.405125) (xy 145.683585 -76.478475) (xy 145.718768 -76.555518)
			(xy 145.74647 -76.635556) (xy 145.766437 -76.717865) (xy 145.778491 -76.8017) (xy 145.782521 -76.8863)
			(xy 145.778491 -76.9709) (xy 145.766437 -77.054735) (xy 145.74647 -77.137044) (xy 145.718768 -77.217082)
			(xy 145.683585 -77.294125) (xy 145.641237 -77.367475) (xy 145.592109 -77.436467) (xy 145.536645 -77.500477)
			(xy 145.475349 -77.558925) (xy 145.408773 -77.611282) (xy 145.337523 -77.657073) (xy 145.262242 -77.695884)
			(xy 145.183614 -77.727364) (xy 145.102348 -77.751228) (xy 145.019183 -77.767259) (xy 144.93487 -77.775311)
			(xy 144.892522 -77.775816) (xy 144.892268 -77.775816) (xy 144.849115 -77.775276) (xy 144.763216 -77.766898)
			(xy 144.678532 -77.750243) (xy 144.595858 -77.725468) (xy 144.515971 -77.692806) (xy 144.439621 -77.652563)
			(xy 144.367526 -77.605117) (xy 144.300363 -77.550915) (xy 144.269206 -77.521054) (xy 144.262065 -77.514545)
			(xy 144.244303 -77.506978) (xy 144.234662 -77.506322) (xy 144.15516 -77.504798) (xy 144.137126 -77.511656)
			(xy 144.12976 -77.51826) (xy 144.099127 -77.545309) (xy 144.033734 -77.594326) (xy 143.964118 -77.637135)
			(xy 143.890867 -77.673375) (xy 143.8146 -77.702741) (xy 143.73596 -77.724984) (xy 143.655611 -77.739917)
			(xy 143.574231 -77.747414) (xy 143.533368 -77.747876) (xy 143.533114 -77.747876) (xy 143.490763 -77.747453)
			(xy 143.406444 -77.739402) (xy 143.323272 -77.723373) (xy 143.242 -77.699511) (xy 143.163365 -77.668031)
			(xy 143.088078 -77.629219) (xy 143.016821 -77.583426) (xy 142.95024 -77.531067) (xy 142.888938 -77.472617)
			(xy 142.833469 -77.408603) (xy 142.784337 -77.339607) (xy 142.741985 -77.266253) (xy 142.706798 -77.189205)
			(xy 142.679094 -77.109161) (xy 142.659125 -77.026847) (xy 142.64707 -76.943006) (xy 142.64304 -76.8584)
			(xy 137.37463 -76.8584) (xy 137.37463 -79.7052) (xy 149.144228 -79.7052) (xy 149.144228 -79.704692)
			(xy 149.144831 -79.65836) (xy 149.154503 -79.566202) (xy 149.173699 -79.475548) (xy 149.202212 -79.387379)
			(xy 149.220428 -79.344774) (xy 149.224232 -79.334831) (xy 149.224232 -79.313569) (xy 149.220428 -79.303626)
			(xy 149.202202 -79.261025) (xy 149.173686 -79.172856) (xy 149.154495 -79.082201) (xy 149.144836 -78.99004)
			(xy 149.144228 -78.943708) (xy 149.144228 -78.9432) (xy 149.144732 -78.900852) (xy 149.152783 -78.816538)
			(xy 149.168812 -78.733372) (xy 149.192673 -78.652105) (xy 149.224152 -78.573475) (xy 149.262963 -78.498194)
			(xy 149.308753 -78.426942) (xy 149.361109 -78.360366) (xy 149.419557 -78.299068) (xy 149.483567 -78.243603)
			(xy 149.552559 -78.194474) (xy 149.625909 -78.152125) (xy 149.702952 -78.116941) (xy 149.782991 -78.089239)
			(xy 149.8653 -78.069271) (xy 149.949135 -78.057218) (xy 150.033736 -78.053188) (xy 150.118337 -78.057218)
			(xy 150.202172 -78.069271) (xy 150.284481 -78.089239) (xy 150.36452 -78.116941) (xy 150.441563 -78.152125)
			(xy 150.514913 -78.194474) (xy 150.583905 -78.243603) (xy 150.647915 -78.299068) (xy 150.706363 -78.360366)
			(xy 150.758719 -78.426942) (xy 150.804509 -78.498194) (xy 150.84332 -78.573475) (xy 150.874799 -78.652105)
			(xy 150.89866 -78.733372) (xy 150.914689 -78.816538) (xy 150.92274 -78.900852) (xy 150.923244 -78.9432)
			(xy 150.923244 -78.943708) (xy 150.922635 -78.99004) (xy 150.912964 -79.082198) (xy 150.893769 -79.172852)
			(xy 150.865258 -79.26102) (xy 150.847044 -79.303626) (xy 150.843237 -79.313568) (xy 150.843237 -79.334832)
			(xy 150.847044 -79.344774) (xy 150.865268 -79.387376) (xy 150.893785 -79.475544) (xy 150.912977 -79.5662)
			(xy 150.922636 -79.65836) (xy 150.923244 -79.704692) (xy 150.923244 -79.7052) (xy 150.923186 -79.710114)
			(xy 205.177635 -79.710114) (xy 205.177635 -79.539758) (xy 205.18562 -79.36959) (xy 205.201572 -79.199983)
			(xy 205.225457 -79.031311) (xy 205.257221 -78.863943) (xy 205.296796 -78.698248) (xy 205.344093 -78.53459)
			(xy 205.39901 -78.373329) (xy 205.461425 -78.214819) (xy 205.531201 -78.059409) (xy 205.608184 -77.907441)
			(xy 205.692206 -77.759247) (xy 205.783082 -77.615155) (xy 205.880612 -77.475481) (xy 205.984582 -77.340532)
			(xy 206.094763 -77.210604) (xy 206.210912 -77.085984) (xy 206.332776 -76.966945) (xy 206.460084 -76.853749)
			(xy 206.592559 -76.746644) (xy 206.729909 -76.645867) (xy 206.871831 -76.551638) (xy 207.018013 -76.464165)
			(xy 207.168136 -76.38364) (xy 207.321867 -76.31024) (xy 207.47887 -76.244126) (xy 207.6388 -76.185444)
			(xy 207.801304 -76.134323) (xy 207.966025 -76.090875) (xy 208.132603 -76.055196) (xy 208.300669 -76.027364)
			(xy 208.469855 -76.00744) (xy 208.639789 -75.995468) (xy 208.810098 -75.991475) (xy 208.980407 -75.995468)
			(xy 209.150341 -76.00744) (xy 209.319527 -76.027364) (xy 209.487593 -76.055196) (xy 209.654171 -76.090875)
			(xy 209.818892 -76.134323) (xy 209.981396 -76.185444) (xy 210.141326 -76.244126) (xy 210.298329 -76.31024)
			(xy 210.45206 -76.38364) (xy 210.602183 -76.464165) (xy 210.748365 -76.551638) (xy 210.890287 -76.645867)
			(xy 211.027637 -76.746644) (xy 211.160112 -76.853749) (xy 211.28742 -76.966945) (xy 211.409284 -77.085984)
			(xy 211.525433 -77.210604) (xy 211.635614 -77.340532) (xy 211.739584 -77.475481) (xy 211.837114 -77.615155)
			(xy 211.92799 -77.759247) (xy 212.012012 -77.907441) (xy 212.088995 -78.059409) (xy 212.158771 -78.214819)
			(xy 212.221186 -78.373329) (xy 212.276103 -78.53459) (xy 212.3234 -78.698248) (xy 212.362975 -78.863943)
			(xy 212.394739 -79.031311) (xy 212.418624 -79.199983) (xy 212.434576 -79.36959) (xy 212.442561 -79.539758)
			(xy 212.44306 -79.624936) (xy 212.442561 -79.710114) (xy 235.177575 -79.710114) (xy 235.177575 -79.539758)
			(xy 235.18556 -79.36959) (xy 235.201512 -79.199983) (xy 235.225397 -79.031311) (xy 235.257161 -78.863943)
			(xy 235.296736 -78.698248) (xy 235.344033 -78.53459) (xy 235.39895 -78.373329) (xy 235.461365 -78.214819)
			(xy 235.531141 -78.059409) (xy 235.608124 -77.907441) (xy 235.692146 -77.759247) (xy 235.783022 -77.615155)
			(xy 235.880552 -77.475481) (xy 235.984522 -77.340532) (xy 236.094703 -77.210604) (xy 236.210852 -77.085984)
			(xy 236.332716 -76.966945) (xy 236.460024 -76.853749) (xy 236.592499 -76.746644) (xy 236.729849 -76.645867)
			(xy 236.871771 -76.551638) (xy 237.017953 -76.464165) (xy 237.168076 -76.38364) (xy 237.321807 -76.31024)
			(xy 237.47881 -76.244126) (xy 237.63874 -76.185444) (xy 237.801244 -76.134323) (xy 237.965965 -76.090875)
			(xy 238.132543 -76.055196) (xy 238.300609 -76.027364) (xy 238.469795 -76.00744) (xy 238.639729 -75.995468)
			(xy 238.810038 -75.991475) (xy 238.980347 -75.995468) (xy 239.150281 -76.00744) (xy 239.319467 -76.027364)
			(xy 239.487533 -76.055196) (xy 239.654111 -76.090875) (xy 239.818832 -76.134323) (xy 239.981336 -76.185444)
			(xy 240.141266 -76.244126) (xy 240.298269 -76.31024) (xy 240.452 -76.38364) (xy 240.602123 -76.464165)
			(xy 240.748305 -76.551638) (xy 240.890227 -76.645867) (xy 241.027577 -76.746644) (xy 241.160052 -76.853749)
			(xy 241.28736 -76.966945) (xy 241.409224 -77.085984) (xy 241.525373 -77.210604) (xy 241.635554 -77.340532)
			(xy 241.739524 -77.475481) (xy 241.837054 -77.615155) (xy 241.92793 -77.759247) (xy 242.011952 -77.907441)
			(xy 242.088935 -78.059409) (xy 242.132213 -78.1558) (xy 279.439887 -78.1558) (xy 279.443918 -78.071199)
			(xy 279.455971 -77.987365) (xy 279.475939 -77.905056) (xy 279.50364 -77.825017) (xy 279.538825 -77.747974)
			(xy 279.581173 -77.674625) (xy 279.630301 -77.605633) (xy 279.685766 -77.541623) (xy 279.747063 -77.483176)
			(xy 279.813639 -77.430819) (xy 279.88489 -77.385029) (xy 279.960171 -77.346218) (xy 280.038801 -77.314739)
			(xy 280.120067 -77.290877) (xy 280.203233 -77.274847) (xy 280.287546 -77.266796) (xy 280.329894 -77.266292)
			(xy 280.330402 -77.266292) (xy 280.376734 -77.2669) (xy 280.468892 -77.276571) (xy 280.559546 -77.295766)
			(xy 280.647715 -77.324277) (xy 280.69032 -77.342492) (xy 280.700262 -77.346298) (xy 280.721526 -77.346298)
			(xy 280.731468 -77.342492) (xy 280.774072 -77.324272) (xy 280.862239 -77.295754) (xy 280.952894 -77.276561)
			(xy 281.045054 -77.2669) (xy 281.091386 -77.266292) (xy 281.091894 -77.266292) (xy 281.134243 -77.26678)
			(xy 281.218559 -77.27483) (xy 281.301727 -77.290859) (xy 281.382995 -77.314721) (xy 281.461627 -77.3462)
			(xy 281.536911 -77.385011) (xy 281.608164 -77.430802) (xy 281.674742 -77.48316) (xy 281.736042 -77.541608)
			(xy 281.791508 -77.605619) (xy 281.840638 -77.674613) (xy 281.882988 -77.747964) (xy 281.918173 -77.825009)
			(xy 281.945875 -77.905049) (xy 281.965844 -77.98736) (xy 281.977898 -78.071197) (xy 281.981928 -78.1558)
			(xy 281.977898 -78.240403) (xy 281.965844 -78.32424) (xy 281.945875 -78.406551) (xy 281.918173 -78.486591)
			(xy 281.882988 -78.563636) (xy 281.840638 -78.636987) (xy 281.791508 -78.705981) (xy 281.736042 -78.769992)
			(xy 281.674742 -78.82844) (xy 281.608164 -78.880798) (xy 281.536911 -78.926589) (xy 281.461627 -78.9654)
			(xy 281.382995 -78.996879) (xy 281.301727 -79.020741) (xy 281.218559 -79.03677) (xy 281.134243 -79.04482)
			(xy 281.091894 -79.045308) (xy 281.091386 -79.045308) (xy 281.045054 -79.044704) (xy 280.952896 -79.035032)
			(xy 280.862242 -79.015836) (xy 280.774073 -78.987323) (xy 280.731468 -78.969108) (xy 280.721526 -78.965302)
			(xy 280.700262 -78.965302) (xy 280.69032 -78.969108) (xy 280.647718 -78.987332) (xy 280.55955 -79.015849)
			(xy 280.468894 -79.035041) (xy 280.376734 -79.0447) (xy 280.330402 -79.045308) (xy 280.329894 -79.045308)
			(xy 280.287546 -79.044804) (xy 280.203233 -79.036753) (xy 280.120067 -79.020723) (xy 280.038801 -78.996861)
			(xy 279.960171 -78.965382) (xy 279.88489 -78.926571) (xy 279.813639 -78.880781) (xy 279.747063 -78.828424)
			(xy 279.685766 -78.769977) (xy 279.630301 -78.705967) (xy 279.581173 -78.636975) (xy 279.538825 -78.563626)
			(xy 279.50364 -78.486583) (xy 279.475939 -78.406544) (xy 279.455971 -78.324235) (xy 279.443918 -78.240401)
			(xy 279.439887 -78.1558) (xy 242.132213 -78.1558) (xy 242.158711 -78.214819) (xy 242.221126 -78.373329)
			(xy 242.276043 -78.53459) (xy 242.32334 -78.698248) (xy 242.362915 -78.863943) (xy 242.394679 -79.031311)
			(xy 242.418564 -79.199983) (xy 242.434516 -79.36959) (xy 242.442501 -79.539758) (xy 242.443 -79.624936)
			(xy 242.442501 -79.710114) (xy 242.434516 -79.880282) (xy 242.418564 -80.049889) (xy 242.394679 -80.218561)
			(xy 242.362915 -80.385929) (xy 242.361704 -80.391) (xy 297.102788 -80.391) (xy 297.106818 -80.306399)
			(xy 297.118871 -80.222564) (xy 297.138839 -80.140255) (xy 297.166541 -80.060216) (xy 297.201725 -79.983173)
			(xy 297.244074 -79.909823) (xy 297.293203 -79.840831) (xy 297.348668 -79.776821) (xy 297.409966 -79.718373)
			(xy 297.476542 -79.666017) (xy 297.547794 -79.620227) (xy 297.623075 -79.581416) (xy 297.701705 -79.549937)
			(xy 297.782972 -79.526076) (xy 297.866138 -79.510047) (xy 297.950452 -79.501996) (xy 297.9928 -79.501492)
			(xy 297.993308 -79.501492) (xy 298.03964 -79.502098) (xy 298.131798 -79.511769) (xy 298.222452 -79.530965)
			(xy 298.310621 -79.559477) (xy 298.353226 -79.577692) (xy 298.363168 -79.581498) (xy 298.384432 -79.581498)
			(xy 298.394374 -79.577692) (xy 298.436977 -79.55947) (xy 298.525144 -79.530952) (xy 298.6158 -79.51176)
			(xy 298.70796 -79.5021) (xy 298.754292 -79.501492) (xy 298.7548 -79.501492) (xy 298.797148 -79.501996)
			(xy 298.881462 -79.510047) (xy 298.964628 -79.526076) (xy 299.045895 -79.549937) (xy 299.124525 -79.581416)
			(xy 299.199806 -79.620227) (xy 299.271058 -79.666017) (xy 299.337634 -79.718373) (xy 299.398932 -79.776821)
			(xy 299.450937 -79.836838) (xy 303.180186 -79.836838) (xy 303.182815 -79.753015) (xy 303.19332 -79.66981)
			(xy 303.211608 -79.587964) (xy 303.237517 -79.508202) (xy 303.270817 -79.431231) (xy 303.311212 -79.357736)
			(xy 303.358343 -79.288368) (xy 303.411794 -79.223743) (xy 303.471088 -79.164435) (xy 303.5357 -79.110969)
			(xy 303.605057 -79.063821) (xy 303.678543 -79.023409) (xy 303.755505 -78.990091) (xy 303.835261 -78.964164)
			(xy 303.917103 -78.945856) (xy 304.000305 -78.935331) (xy 304.084128 -78.932683) (xy 304.167828 -78.937934)
			(xy 304.250663 -78.951038) (xy 304.331897 -78.971879) (xy 304.410809 -79.000271) (xy 304.4867 -79.035964)
			(xy 304.558894 -79.078639) (xy 304.626753 -79.127919) (xy 304.689673 -79.183366) (xy 304.747097 -79.244487)
			(xy 304.798514 -79.310741) (xy 304.843468 -79.38154) (xy 304.881561 -79.456254) (xy 304.912453 -79.534222)
			(xy 304.935872 -79.61475) (xy 304.951609 -79.697125) (xy 304.959525 -79.780616) (xy 304.96002 -79.822548)
			(xy 304.96002 -79.823056) (xy 304.959492 -79.865875) (xy 304.951224 -79.951114) (xy 304.94351 -79.993236)
			(xy 304.941789 -80.004521) (xy 304.94747 -80.026607) (xy 304.954432 -80.035654) (xy 305.012852 -80.104996)
			(xy 305.03368 -80.114394) (xy 305.044856 -80.11414) (xy 305.045872 -80.11414) (xy 305.063398 -80.11414)
			(xy 305.105333 -80.11462) (xy 305.18883 -80.122512) (xy 305.271215 -80.138226) (xy 305.351755 -80.161624)
			(xy 305.429736 -80.192496) (xy 305.504465 -80.23057) (xy 305.57528 -80.275507) (xy 305.641553 -80.326908)
			(xy 305.702694 -80.384318) (xy 305.758161 -80.447227) (xy 305.807463 -80.515076) (xy 305.85016 -80.587263)
			(xy 305.885876 -80.663148) (xy 305.914292 -80.742058) (xy 305.935156 -80.823291) (xy 305.948283 -80.906127)
			(xy 305.953557 -80.98983) (xy 305.950931 -81.073659) (xy 305.940428 -81.156868) (xy 305.922142 -81.23872)
			(xy 305.896234 -81.318488) (xy 305.862935 -81.395464) (xy 305.82254 -81.468965) (xy 305.775407 -81.538338)
			(xy 305.721955 -81.602968) (xy 305.662659 -81.662282) (xy 305.598045 -81.715752) (xy 305.528685 -81.762905)
			(xy 305.455196 -81.803321) (xy 305.37823 -81.836643) (xy 305.298469 -81.862574) (xy 305.216623 -81.880884)
			(xy 305.133416 -81.891411) (xy 305.049589 -81.894061) (xy 304.965883 -81.888812) (xy 304.883044 -81.875708)
			(xy 304.801804 -81.854868) (xy 304.722887 -81.826475) (xy 304.646992 -81.790781) (xy 304.574792 -81.748104)
			(xy 304.506928 -81.698823) (xy 304.444004 -81.643373) (xy 304.386576 -81.582249) (xy 304.335155 -81.515992)
			(xy 304.290198 -81.445189) (xy 304.252102 -81.370471) (xy 304.221207 -81.292499) (xy 304.197787 -81.211966)
			(xy 304.182048 -81.129586) (xy 304.174132 -81.046091) (xy 304.173636 -81.004156) (xy 304.173636 -81.003648)
			(xy 304.174164 -80.960829) (xy 304.182432 -80.87559) (xy 304.190146 -80.833468) (xy 304.191851 -80.822182)
			(xy 304.186179 -80.800099) (xy 304.179224 -80.79105) (xy 304.120804 -80.721708) (xy 304.099976 -80.71231)
			(xy 304.0888 -80.712564) (xy 304.087784 -80.712564) (xy 304.070258 -80.712564) (xy 304.028326 -80.712034)
			(xy 303.944833 -80.704139) (xy 303.862455 -80.688421) (xy 303.78192 -80.665021) (xy 303.703946 -80.634147)
			(xy 303.629222 -80.596072) (xy 303.558413 -80.551135) (xy 303.492147 -80.499733) (xy 303.431012 -80.442324)
			(xy 303.37555 -80.379417) (xy 303.326255 -80.31157) (xy 303.283562 -80.239385) (xy 303.247852 -80.163503)
			(xy 303.219441 -80.084598) (xy 303.198581 -80.003369) (xy 303.185457 -79.920537) (xy 303.180186 -79.836838)
			(xy 299.450937 -79.836838) (xy 299.454397 -79.840831) (xy 299.503526 -79.909823) (xy 299.545875 -79.983173)
			(xy 299.581059 -80.060216) (xy 299.608761 -80.140255) (xy 299.628729 -80.222564) (xy 299.640782 -80.306399)
			(xy 299.644813 -80.391) (xy 299.640782 -80.475601) (xy 299.628729 -80.559436) (xy 299.608761 -80.641745)
			(xy 299.581059 -80.721784) (xy 299.545875 -80.798827) (xy 299.503526 -80.872177) (xy 299.454397 -80.941169)
			(xy 299.398932 -81.005179) (xy 299.337634 -81.063627) (xy 299.271058 -81.115983) (xy 299.199806 -81.161773)
			(xy 299.124525 -81.200584) (xy 299.045895 -81.232063) (xy 298.964628 -81.255924) (xy 298.881462 -81.271953)
			(xy 298.797148 -81.280004) (xy 298.7548 -81.280508) (xy 298.754292 -81.280508) (xy 298.70796 -81.279902)
			(xy 298.615802 -81.270231) (xy 298.525148 -81.251035) (xy 298.436979 -81.222523) (xy 298.394374 -81.204308)
			(xy 298.384432 -81.200502) (xy 298.363168 -81.200502) (xy 298.353226 -81.204308) (xy 298.310623 -81.22253)
			(xy 298.222456 -81.251048) (xy 298.1318 -81.27024) (xy 298.03964 -81.2799) (xy 297.993308 -81.280508)
			(xy 297.9928 -81.280508) (xy 297.950452 -81.280004) (xy 297.866138 -81.271953) (xy 297.782972 -81.255924)
			(xy 297.701705 -81.232063) (xy 297.623075 -81.200584) (xy 297.547794 -81.161773) (xy 297.476542 -81.115983)
			(xy 297.409966 -81.063627) (xy 297.348668 -81.005179) (xy 297.293203 -80.941169) (xy 297.244074 -80.872177)
			(xy 297.201725 -80.798827) (xy 297.166541 -80.721784) (xy 297.138839 -80.641745) (xy 297.118871 -80.559436)
			(xy 297.106818 -80.475601) (xy 297.102788 -80.391) (xy 242.361704 -80.391) (xy 242.32334 -80.551624)
			(xy 242.276043 -80.715282) (xy 242.221126 -80.876543) (xy 242.158711 -81.035053) (xy 242.088935 -81.190463)
			(xy 242.011952 -81.342431) (xy 241.92793 -81.490625) (xy 241.837054 -81.634717) (xy 241.739524 -81.774391)
			(xy 241.635554 -81.90934) (xy 241.525373 -82.039268) (xy 241.409224 -82.163888) (xy 241.28736 -82.282927)
			(xy 241.160052 -82.396123) (xy 241.027577 -82.503228) (xy 240.890227 -82.604005) (xy 240.748305 -82.698234)
			(xy 240.602123 -82.785707) (xy 240.452 -82.866232) (xy 240.298269 -82.939632) (xy 240.141266 -83.005746)
			(xy 239.981336 -83.064428) (xy 239.818832 -83.115549) (xy 239.654111 -83.158997) (xy 239.487533 -83.194676)
			(xy 239.319467 -83.222508) (xy 239.150281 -83.242432) (xy 238.980347 -83.254404) (xy 238.810038 -83.258398)
			(xy 238.639729 -83.254404) (xy 238.469795 -83.242432) (xy 238.300609 -83.222508) (xy 238.132543 -83.194676)
			(xy 237.965965 -83.158997) (xy 237.801244 -83.115549) (xy 237.63874 -83.064428) (xy 237.47881 -83.005746)
			(xy 237.321807 -82.939632) (xy 237.168076 -82.866232) (xy 237.017953 -82.785707) (xy 236.871771 -82.698234)
			(xy 236.729849 -82.604005) (xy 236.592499 -82.503228) (xy 236.460024 -82.396123) (xy 236.332716 -82.282927)
			(xy 236.210852 -82.163888) (xy 236.094703 -82.039268) (xy 235.984522 -81.90934) (xy 235.880552 -81.774391)
			(xy 235.783022 -81.634717) (xy 235.692146 -81.490625) (xy 235.608124 -81.342431) (xy 235.531141 -81.190463)
			(xy 235.461365 -81.035053) (xy 235.39895 -80.876543) (xy 235.344033 -80.715282) (xy 235.296736 -80.551624)
			(xy 235.257161 -80.385929) (xy 235.225397 -80.218561) (xy 235.201512 -80.049889) (xy 235.18556 -79.880282)
			(xy 235.177575 -79.710114) (xy 212.442561 -79.710114) (xy 212.434576 -79.880282) (xy 212.418624 -80.049889)
			(xy 212.394739 -80.218561) (xy 212.362975 -80.385929) (xy 212.3234 -80.551624) (xy 212.276103 -80.715282)
			(xy 212.221186 -80.876543) (xy 212.158771 -81.035053) (xy 212.088995 -81.190463) (xy 212.012012 -81.342431)
			(xy 211.92799 -81.490625) (xy 211.837114 -81.634717) (xy 211.739584 -81.774391) (xy 211.635614 -81.90934)
			(xy 211.525433 -82.039268) (xy 211.409284 -82.163888) (xy 211.28742 -82.282927) (xy 211.160112 -82.396123)
			(xy 211.027637 -82.503228) (xy 210.890287 -82.604005) (xy 210.748365 -82.698234) (xy 210.602183 -82.785707)
			(xy 210.45206 -82.866232) (xy 210.298329 -82.939632) (xy 210.141326 -83.005746) (xy 209.981396 -83.064428)
			(xy 209.818892 -83.115549) (xy 209.654171 -83.158997) (xy 209.487593 -83.194676) (xy 209.319527 -83.222508)
			(xy 209.150341 -83.242432) (xy 208.980407 -83.254404) (xy 208.810098 -83.258398) (xy 208.639789 -83.254404)
			(xy 208.469855 -83.242432) (xy 208.300669 -83.222508) (xy 208.132603 -83.194676) (xy 207.966025 -83.158997)
			(xy 207.801304 -83.115549) (xy 207.6388 -83.064428) (xy 207.47887 -83.005746) (xy 207.321867 -82.939632)
			(xy 207.168136 -82.866232) (xy 207.018013 -82.785707) (xy 206.871831 -82.698234) (xy 206.729909 -82.604005)
			(xy 206.592559 -82.503228) (xy 206.460084 -82.396123) (xy 206.332776 -82.282927) (xy 206.210912 -82.163888)
			(xy 206.094763 -82.039268) (xy 205.984582 -81.90934) (xy 205.880612 -81.774391) (xy 205.783082 -81.634717)
			(xy 205.692206 -81.490625) (xy 205.608184 -81.342431) (xy 205.531201 -81.190463) (xy 205.461425 -81.035053)
			(xy 205.39901 -80.876543) (xy 205.344093 -80.715282) (xy 205.296796 -80.551624) (xy 205.257221 -80.385929)
			(xy 205.225457 -80.218561) (xy 205.201572 -80.049889) (xy 205.18562 -79.880282) (xy 205.177635 -79.710114)
			(xy 150.923186 -79.710114) (xy 150.92274 -79.747548) (xy 150.914689 -79.831862) (xy 150.89866 -79.915028)
			(xy 150.874799 -79.996295) (xy 150.84332 -80.074925) (xy 150.804509 -80.150206) (xy 150.758719 -80.221458)
			(xy 150.706363 -80.288034) (xy 150.647915 -80.349332) (xy 150.583905 -80.404797) (xy 150.514913 -80.453926)
			(xy 150.441563 -80.496275) (xy 150.36452 -80.531459) (xy 150.284481 -80.559161) (xy 150.202172 -80.579129)
			(xy 150.118337 -80.591182) (xy 150.033736 -80.595213) (xy 149.949135 -80.591182) (xy 149.8653 -80.579129)
			(xy 149.782991 -80.559161) (xy 149.702952 -80.531459) (xy 149.625909 -80.496275) (xy 149.552559 -80.453926)
			(xy 149.483567 -80.404797) (xy 149.419557 -80.349332) (xy 149.361109 -80.288034) (xy 149.308753 -80.221458)
			(xy 149.262963 -80.150206) (xy 149.224152 -80.074925) (xy 149.192673 -79.996295) (xy 149.168812 -79.915028)
			(xy 149.152783 -79.831862) (xy 149.144732 -79.747548) (xy 149.144228 -79.7052) (xy 137.37463 -79.7052)
			(xy 137.37463 -79.89062) (xy 137.374124 -79.923881) (xy 137.365434 -79.989832) (xy 137.348207 -80.054084)
			(xy 137.322737 -80.115537) (xy 137.28946 -80.173137) (xy 137.248946 -80.225898) (xy 137.225786 -80.249776)
			(xy 136.598406 -80.877156) (xy 136.574543 -80.900332) (xy 136.521779 -80.940843) (xy 136.464175 -80.974115)
			(xy 136.40272 -80.99958) (xy 136.338465 -81.0168) (xy 136.272511 -81.025482) (xy 136.23925 -81.026)
			(xy 123.4694 -81.026) (xy 123.436141 -81.025461) (xy 123.370191 -81.016775) (xy 123.30594 -80.999553)
			(xy 123.244489 -80.974089) (xy 123.186888 -80.940818) (xy 123.134124 -80.900312) (xy 123.110244 -80.877156)
			(xy 122.475244 -80.242156) (xy 122.452092 -80.218271) (xy 122.411579 -80.165511) (xy 122.378303 -80.107912)
			(xy 122.352834 -80.046461) (xy 122.335609 -79.98221) (xy 122.326921 -79.91626) (xy 122.3264 -79.883)
			(xy 62.930237 -79.883) (xy 62.866209 -79.937386) (xy 62.777346 -80.002441) (xy 62.68402 -80.060913)
			(xy 62.586718 -80.1125) (xy 62.485947 -80.156931) (xy 62.382233 -80.193974) (xy 62.276116 -80.223437)
			(xy 62.16815 -80.245167) (xy 62.058897 -80.259049) (xy 61.948927 -80.265011) (xy 61.838814 -80.263023)
			(xy 61.729131 -80.253094) (xy 61.620451 -80.235277) (xy 61.51334 -80.209664) (xy 61.408356 -80.176389)
			(xy 61.306047 -80.135625) (xy 61.206946 -80.087585) (xy 61.111569 -80.03252) (xy 61.020415 -79.970715)
			(xy 60.933958 -79.902495) (xy 60.852649 -79.828214) (xy 60.776912 -79.748259) (xy 60.707141 -79.663048)
			(xy 60.643702 -79.573024) (xy 60.586923 -79.478657) (xy 60.537102 -79.38044) (xy 60.494498 -79.278883)
			(xy 60.459333 -79.174517) (xy 60.43179 -79.067886) (xy 60.412014 -78.959545) (xy 60.400106 -78.850059)
			(xy 60.396131 -78.74) (xy 43.888152 -78.74) (xy 43.887655 -78.795066) (xy 43.879708 -78.90491) (xy 43.863856 -79.013894)
			(xy 43.840181 -79.12145) (xy 43.808807 -79.227018) (xy 43.769897 -79.330046) (xy 43.723654 -79.429998)
			(xy 43.67032 -79.526353) (xy 43.610171 -79.618609) (xy 43.543523 -79.706283) (xy 43.470722 -79.78892)
			(xy 43.392147 -79.866088) (xy 43.308209 -79.937386) (xy 43.219346 -80.002441) (xy 43.12602 -80.060913)
			(xy 43.028718 -80.1125) (xy 42.927947 -80.156931) (xy 42.824233 -80.193974) (xy 42.718116 -80.223437)
			(xy 42.61015 -80.245167) (xy 42.500897 -80.259049) (xy 42.390927 -80.265011) (xy 42.280814 -80.263023)
			(xy 42.171131 -80.253094) (xy 42.062451 -80.235277) (xy 41.95534 -80.209664) (xy 41.850356 -80.176389)
			(xy 41.748047 -80.135625) (xy 41.648946 -80.087585) (xy 41.553569 -80.03252) (xy 41.462415 -79.970715)
			(xy 41.375958 -79.902495) (xy 41.294649 -79.828214) (xy 41.218912 -79.748259) (xy 41.149141 -79.663048)
			(xy 41.085702 -79.573024) (xy 41.028923 -79.478657) (xy 40.979102 -79.38044) (xy 40.936498 -79.278883)
			(xy 40.901333 -79.174517) (xy 40.87379 -79.067886) (xy 40.854014 -78.959545) (xy 40.842106 -78.850059)
			(xy 40.838131 -78.74) (xy 0.509016 -78.74) (xy 0.509016 -82.296) (xy 174.014896 -82.296) (xy 174.018924 -82.211447)
			(xy 174.03097 -82.12766) (xy 174.050927 -82.045398) (xy 174.078613 -81.965405) (xy 174.113777 -81.888406)
			(xy 174.156102 -81.815098) (xy 174.205203 -81.746145) (xy 174.260636 -81.682172) (xy 174.321899 -81.623758)
			(xy 174.388437 -81.571431) (xy 174.459648 -81.525667) (xy 174.534887 -81.486879) (xy 174.613472 -81.455418)
			(xy 174.694691 -81.43157) (xy 174.77781 -81.41555) (xy 174.862076 -81.407504) (xy 174.9044 -81.407)
			(xy 174.950803 -81.407598) (xy 175.043101 -81.417298) (xy 175.133886 -81.43656) (xy 175.222171 -81.465175)
			(xy 175.264826 -81.483454) (xy 175.266604 -81.484216) (xy 175.275737 -81.487398) (xy 175.295063 -81.487398)
			(xy 175.304196 -81.484216) (xy 175.305974 -81.483454) (xy 175.348636 -81.465192) (xy 175.436919 -81.436578)
			(xy 175.527702 -81.417316) (xy 175.619998 -81.407617) (xy 175.6664 -81.407) (xy 175.666654 -81.407)
			(xy 175.715422 -81.407677) (xy 175.812372 -81.418361) (xy 175.907567 -81.439606) (xy 175.953928 -81.454752)
			(xy 175.960648 -81.456851) (xy 175.974701 -81.457612) (xy 175.981614 -81.456276) (xy 175.985678 -81.45526)
			(xy 176.028801 -81.442312) (xy 176.117009 -81.424222) (xy 176.206594 -81.415151) (xy 176.251616 -81.41462)
			(xy 176.293257 -81.415101) (xy 176.376178 -81.422845) (xy 176.458014 -81.438302) (xy 176.538047 -81.461335)
			(xy 176.57699 -81.476088) (xy 176.586068 -81.479207) (xy 176.60525 -81.479207) (xy 176.614328 -81.476088)
			(xy 176.653265 -81.461315) (xy 176.733297 -81.43827) (xy 176.815135 -81.422813) (xy 176.898059 -81.415078)
			(xy 176.939702 -81.41462) (xy 176.962729 -81.414716) (xy 177.008727 -81.417002) (xy 177.03165 -81.419192)
			(xy 177.032158 -81.419192) (xy 177.04562 -81.418938) (xy 177.081557 -81.413372) (xy 177.154037 -81.407395)
			(xy 177.1904 -81.407) (xy 177.236803 -81.407598) (xy 177.329101 -81.417298) (xy 177.419886 -81.43656)
			(xy 177.508171 -81.465175) (xy 177.550826 -81.483454) (xy 177.552604 -81.484216) (xy 177.561737 -81.487398)
			(xy 177.581063 -81.487398) (xy 177.590196 -81.484216) (xy 177.591974 -81.483454) (xy 177.634636 -81.465192)
			(xy 177.722919 -81.436578) (xy 177.813702 -81.417316) (xy 177.905998 -81.407617) (xy 177.9524 -81.407)
			(xy 177.994724 -81.407504) (xy 178.07899 -81.41555) (xy 178.162109 -81.43157) (xy 178.243328 -81.455418)
			(xy 178.321913 -81.486879) (xy 178.397152 -81.525667) (xy 178.468363 -81.571431) (xy 178.534901 -81.623758)
			(xy 178.596164 -81.682172) (xy 178.651597 -81.746145) (xy 178.700698 -81.815098) (xy 178.743023 -81.888406)
			(xy 178.778187 -81.965405) (xy 178.805873 -82.045398) (xy 178.82583 -82.12766) (xy 178.837876 -82.211447)
			(xy 178.841904 -82.296) (xy 178.837876 -82.380553) (xy 178.82583 -82.46434) (xy 178.805873 -82.546602)
			(xy 178.778187 -82.626595) (xy 178.743023 -82.703594) (xy 178.700698 -82.776902) (xy 178.651597 -82.845855)
			(xy 178.596164 -82.909828) (xy 178.534901 -82.968242) (xy 178.468363 -83.020569) (xy 178.397152 -83.066333)
			(xy 178.321913 -83.105121) (xy 178.243328 -83.136582) (xy 178.162109 -83.16043) (xy 178.07899 -83.17645)
			(xy 177.994724 -83.184496) (xy 177.9524 -83.185) (xy 177.905997 -83.184402) (xy 177.813699 -83.174702)
			(xy 177.722914 -83.15544) (xy 177.634629 -83.126825) (xy 177.591974 -83.108546) (xy 177.590196 -83.107784)
			(xy 177.581063 -83.104602) (xy 177.561737 -83.104602) (xy 177.552604 -83.107784) (xy 177.550826 -83.108546)
			(xy 177.508164 -83.126808) (xy 177.419881 -83.155422) (xy 177.329098 -83.174684) (xy 177.236802 -83.184383)
			(xy 177.1904 -83.185) (xy 177.189638 -83.185) (xy 177.167821 -83.184863) (xy 177.12424 -83.182703)
			(xy 177.102516 -83.180682) (xy 177.089054 -83.18119) (xy 177.051996 -83.18706) (xy 176.97722 -83.193289)
			(xy 176.939702 -83.193636) (xy 176.89806 -83.193184) (xy 176.815138 -83.185432) (xy 176.733303 -83.169967)
			(xy 176.65327 -83.146926) (xy 176.614328 -83.132168) (xy 176.605259 -83.128992) (xy 176.586059 -83.128992)
			(xy 176.57699 -83.132168) (xy 176.538052 -83.146938) (xy 176.45802 -83.169983) (xy 176.376183 -83.185441)
			(xy 176.293258 -83.193177) (xy 176.251616 -83.193636) (xy 176.202451 -83.193015) (xy 176.104715 -83.182233)
			(xy 176.008766 -83.160732) (xy 175.962056 -83.145376) (xy 175.954369 -83.143042) (xy 175.938315 -83.142774)
			(xy 175.93056 -83.144868) (xy 175.8877 -83.157609) (xy 175.80008 -83.175465) (xy 175.71111 -83.184444)
			(xy 175.6664 -83.185) (xy 175.619997 -83.184402) (xy 175.527699 -83.174702) (xy 175.436914 -83.15544)
			(xy 175.348629 -83.126825) (xy 175.305974 -83.108546) (xy 175.304196 -83.107784) (xy 175.295063 -83.104602)
			(xy 175.275737 -83.104602) (xy 175.266604 -83.107784) (xy 175.264826 -83.108546) (xy 175.222164 -83.126808)
			(xy 175.133881 -83.155422) (xy 175.043098 -83.174684) (xy 174.950802 -83.184383) (xy 174.9044 -83.185)
			(xy 174.862076 -83.184496) (xy 174.77781 -83.17645) (xy 174.694691 -83.16043) (xy 174.613472 -83.136582)
			(xy 174.534887 -83.105121) (xy 174.459648 -83.066333) (xy 174.388437 -83.020569) (xy 174.321899 -82.968242)
			(xy 174.260636 -82.909828) (xy 174.205203 -82.845855) (xy 174.156102 -82.776902) (xy 174.113777 -82.703594)
			(xy 174.078613 -82.626595) (xy 174.050927 -82.546602) (xy 174.03097 -82.46434) (xy 174.018924 -82.380553)
			(xy 174.014896 -82.296) (xy 0.509016 -82.296) (xy 0.509016 -86.127279) (xy 159.685986 -86.127279)
			(xy 159.685986 -86.042557) (xy 159.694039 -85.95822) (xy 159.710073 -85.87503) (xy 159.733941 -85.79374)
			(xy 159.765429 -85.715088) (xy 159.804251 -85.639785) (xy 159.850054 -85.568513) (xy 159.902425 -85.501917)
			(xy 159.96089 -85.440602) (xy 160.024918 -85.385121) (xy 160.09393 -85.335978) (xy 160.1673 -85.293618)
			(xy 160.244365 -85.258423) (xy 160.324427 -85.230714) (xy 160.40676 -85.21074) (xy 160.490619 -85.198683)
			(xy 160.575244 -85.194652) (xy 160.659869 -85.198683) (xy 160.743728 -85.21074) (xy 160.826061 -85.230714)
			(xy 160.906123 -85.258423) (xy 160.983188 -85.293618) (xy 161.056558 -85.335978) (xy 161.12557 -85.385121)
			(xy 161.189598 -85.440602) (xy 161.248063 -85.501917) (xy 161.300434 -85.568513) (xy 161.346237 -85.639785)
			(xy 161.385059 -85.715088) (xy 161.416547 -85.79374) (xy 161.440415 -85.87503) (xy 161.456449 -85.95822)
			(xy 161.464502 -86.042557) (xy 161.465006 -86.084918) (xy 161.464502 -86.127279) (xy 161.456449 -86.211616)
			(xy 161.452327 -86.233) (xy 269.188188 -86.233) (xy 269.192218 -86.148399) (xy 269.204271 -86.064564)
			(xy 269.224239 -85.982255) (xy 269.251941 -85.902216) (xy 269.287125 -85.825173) (xy 269.329474 -85.751823)
			(xy 269.378603 -85.682831) (xy 269.434068 -85.618821) (xy 269.495366 -85.560373) (xy 269.561942 -85.508017)
			(xy 269.633194 -85.462227) (xy 269.708475 -85.423416) (xy 269.787105 -85.391937) (xy 269.868372 -85.368076)
			(xy 269.951538 -85.352047) (xy 270.035852 -85.343996) (xy 270.0782 -85.343492) (xy 270.078962 -85.343492)
			(xy 270.117182 -85.3439) (xy 270.193341 -85.350465) (xy 270.268653 -85.363549) (xy 270.342563 -85.383056)
			(xy 270.378682 -85.395562) (xy 270.386998 -85.398148) (xy 270.404402 -85.398148) (xy 270.412718 -85.395562)
			(xy 270.448841 -85.383071) (xy 270.522753 -85.363581) (xy 270.598064 -85.350497) (xy 270.674219 -85.343915)
			(xy 270.712438 -85.343492) (xy 270.7132 -85.343492) (xy 270.756684 -85.343995) (xy 270.843237 -85.35248)
			(xy 270.928548 -85.36937) (xy 271.011805 -85.394503) (xy 271.092212 -85.42764) (xy 271.169003 -85.468464)
			(xy 271.241444 -85.516586) (xy 271.308843 -85.571546) (xy 271.340072 -85.60181) (xy 271.340326 -85.602064)
			(xy 271.347704 -85.608646) (xy 271.366008 -85.616084) (xy 271.375886 -85.616542) (xy 271.447514 -85.616542)
			(xy 271.457395 -85.616108) (xy 271.475694 -85.608649) (xy 271.483074 -85.602064) (xy 271.483328 -85.60181)
			(xy 271.514554 -85.571545) (xy 271.581957 -85.51659) (xy 271.6544 -85.468474) (xy 271.731191 -85.427654)
			(xy 271.811598 -85.394521) (xy 271.894855 -85.36939) (xy 271.980165 -85.352502) (xy 272.066717 -85.344018)
			(xy 272.1102 -85.343492) (xy 272.110962 -85.343492) (xy 272.149182 -85.3439) (xy 272.225341 -85.350465)
			(xy 272.300653 -85.363549) (xy 272.374563 -85.383056) (xy 272.410682 -85.395562) (xy 272.418998 -85.398148)
			(xy 272.436402 -85.398148) (xy 272.444718 -85.395562) (xy 272.480841 -85.383071) (xy 272.554753 -85.363581)
			(xy 272.630064 -85.350497) (xy 272.706219 -85.343915) (xy 272.744438 -85.343492) (xy 272.7452 -85.343492)
			(xy 272.788684 -85.343995) (xy 272.875237 -85.35248) (xy 272.960548 -85.36937) (xy 273.043805 -85.394503)
			(xy 273.124212 -85.42764) (xy 273.201003 -85.468464) (xy 273.273444 -85.516586) (xy 273.340843 -85.571546)
			(xy 273.372072 -85.60181) (xy 273.372326 -85.602064) (xy 273.379704 -85.608646) (xy 273.398008 -85.616084)
			(xy 273.407886 -85.616542) (xy 273.479514 -85.616542) (xy 273.489395 -85.616108) (xy 273.507694 -85.608649)
			(xy 273.515074 -85.602064) (xy 273.515328 -85.60181) (xy 273.546554 -85.571545) (xy 273.613957 -85.51659)
			(xy 273.6864 -85.468474) (xy 273.763191 -85.427654) (xy 273.843598 -85.394521) (xy 273.926855 -85.36939)
			(xy 274.012165 -85.352502) (xy 274.098717 -85.344018) (xy 274.1422 -85.343492) (xy 274.142962 -85.343492)
			(xy 274.181182 -85.3439) (xy 274.257341 -85.350465) (xy 274.332653 -85.363549) (xy 274.406563 -85.383056)
			(xy 274.442682 -85.395562) (xy 274.450998 -85.398148) (xy 274.468402 -85.398148) (xy 274.476718 -85.395562)
			(xy 274.512841 -85.383071) (xy 274.586753 -85.363581) (xy 274.662064 -85.350497) (xy 274.738219 -85.343915)
			(xy 274.776438 -85.343492) (xy 274.7772 -85.343492) (xy 274.817247 -85.343907) (xy 274.897016 -85.351102)
			(xy 274.975816 -85.365436) (xy 275.05301 -85.38679) (xy 275.127973 -85.414994) (xy 275.2001 -85.449818)
			(xy 275.268805 -85.490982) (xy 275.333535 -85.538151) (xy 275.36394 -85.564218) (xy 275.371029 -85.569983)
			(xy 275.388086 -85.576495) (xy 275.397214 -85.576918) (xy 275.427186 -85.576918) (xy 275.436309 -85.576484)
			(xy 275.453359 -85.569964) (xy 275.46046 -85.564218) (xy 275.490874 -85.53816) (xy 275.555592 -85.490974)
			(xy 275.624292 -85.449798) (xy 275.696416 -85.414967) (xy 275.77138 -85.386763) (xy 275.848577 -85.365414)
			(xy 275.927381 -85.351094) (xy 276.007153 -85.343919) (xy 276.0472 -85.343492) (xy 276.047962 -85.343492)
			(xy 276.086182 -85.3439) (xy 276.162341 -85.350465) (xy 276.237653 -85.363549) (xy 276.311563 -85.383056)
			(xy 276.347682 -85.395562) (xy 276.355998 -85.398148) (xy 276.373402 -85.398148) (xy 276.381718 -85.395562)
			(xy 276.417841 -85.383071) (xy 276.491753 -85.363581) (xy 276.567064 -85.350497) (xy 276.643219 -85.343915)
			(xy 276.681438 -85.343492) (xy 276.6822 -85.343492) (xy 276.724548 -85.343996) (xy 276.808862 -85.352047)
			(xy 276.892028 -85.368076) (xy 276.973295 -85.391937) (xy 277.051925 -85.423416) (xy 277.127206 -85.462227)
			(xy 277.198458 -85.508017) (xy 277.265034 -85.560373) (xy 277.326332 -85.618821) (xy 277.381797 -85.682831)
			(xy 277.430926 -85.751823) (xy 277.473275 -85.825173) (xy 277.508459 -85.902216) (xy 277.536161 -85.982255)
			(xy 277.556129 -86.064564) (xy 277.568182 -86.148399) (xy 277.572213 -86.233) (xy 277.568182 -86.317601)
			(xy 277.556129 -86.401436) (xy 277.536161 -86.483745) (xy 277.508459 -86.563784) (xy 277.473275 -86.640827)
			(xy 277.430926 -86.714177) (xy 277.381797 -86.783169) (xy 277.326332 -86.847179) (xy 277.265034 -86.905627)
			(xy 277.198458 -86.957983) (xy 277.127206 -87.003773) (xy 277.051925 -87.042584) (xy 276.973295 -87.074063)
			(xy 276.892028 -87.097924) (xy 276.808862 -87.113953) (xy 276.724548 -87.122004) (xy 276.6822 -87.122508)
			(xy 276.681438 -87.122508) (xy 276.643218 -87.1221) (xy 276.567059 -87.115535) (xy 276.491747 -87.102451)
			(xy 276.417837 -87.082944) (xy 276.381718 -87.070438) (xy 276.373402 -87.067852) (xy 276.355998 -87.067852)
			(xy 276.347682 -87.070438) (xy 276.311559 -87.082929) (xy 276.237647 -87.102419) (xy 276.162336 -87.115503)
			(xy 276.086181 -87.122085) (xy 276.047962 -87.122508) (xy 276.0472 -87.122508) (xy 276.007153 -87.122093)
			(xy 275.927384 -87.114898) (xy 275.848584 -87.100564) (xy 275.77139 -87.07921) (xy 275.696427 -87.051006)
			(xy 275.6243 -87.016182) (xy 275.555595 -86.975018) (xy 275.490865 -86.927849) (xy 275.46046 -86.901782)
			(xy 275.453371 -86.896017) (xy 275.436314 -86.889505) (xy 275.427186 -86.889082) (xy 275.397214 -86.889082)
			(xy 275.388091 -86.889516) (xy 275.371041 -86.896036) (xy 275.36394 -86.901782) (xy 275.333526 -86.92784)
			(xy 275.268808 -86.975026) (xy 275.200108 -87.016202) (xy 275.127984 -87.051033) (xy 275.05302 -87.079237)
			(xy 274.975823 -87.100586) (xy 274.897019 -87.114906) (xy 274.817247 -87.122081) (xy 274.7772 -87.122508)
			(xy 274.776438 -87.122508) (xy 274.738218 -87.1221) (xy 274.662059 -87.115535) (xy 274.586747 -87.102451)
			(xy 274.512837 -87.082944) (xy 274.476718 -87.070438) (xy 274.468402 -87.067852) (xy 274.450998 -87.067852)
			(xy 274.442682 -87.070438) (xy 274.406559 -87.082929) (xy 274.332647 -87.102419) (xy 274.257336 -87.115503)
			(xy 274.181181 -87.122085) (xy 274.142962 -87.122508) (xy 274.1422 -87.122508) (xy 274.098716 -87.122005)
			(xy 274.012163 -87.11352) (xy 273.926852 -87.09663) (xy 273.843595 -87.071497) (xy 273.763188 -87.03836)
			(xy 273.686397 -86.997536) (xy 273.613956 -86.949414) (xy 273.546557 -86.894454) (xy 273.515328 -86.86419)
			(xy 273.515074 -86.863936) (xy 273.507696 -86.857354) (xy 273.489392 -86.849916) (xy 273.479514 -86.849458)
			(xy 273.407886 -86.849458) (xy 273.398005 -86.849892) (xy 273.379706 -86.857351) (xy 273.372326 -86.863936)
			(xy 273.372072 -86.86419) (xy 273.340846 -86.894455) (xy 273.273443 -86.94941) (xy 273.201 -86.997526)
			(xy 273.124209 -87.038346) (xy 273.043802 -87.071479) (xy 272.960545 -87.09661) (xy 272.875235 -87.113498)
			(xy 272.788683 -87.121982) (xy 272.7452 -87.122508) (xy 272.744438 -87.122508) (xy 272.706218 -87.1221)
			(xy 272.630059 -87.115535) (xy 272.554747 -87.102451) (xy 272.480837 -87.082944) (xy 272.444718 -87.070438)
			(xy 272.436402 -87.067852) (xy 272.418998 -87.067852) (xy 272.410682 -87.070438) (xy 272.374559 -87.082929)
			(xy 272.300647 -87.102419) (xy 272.225336 -87.115503) (xy 272.149181 -87.122085) (xy 272.110962 -87.122508)
			(xy 272.1102 -87.122508) (xy 272.066716 -87.122005) (xy 271.980163 -87.11352) (xy 271.894852 -87.09663)
			(xy 271.811595 -87.071497) (xy 271.731188 -87.03836) (xy 271.654397 -86.997536) (xy 271.581956 -86.949414)
			(xy 271.514557 -86.894454) (xy 271.483328 -86.86419) (xy 271.483074 -86.863936) (xy 271.475696 -86.857354)
			(xy 271.457392 -86.849916) (xy 271.447514 -86.849458) (xy 271.375886 -86.849458) (xy 271.366005 -86.849892)
			(xy 271.347706 -86.857351) (xy 271.340326 -86.863936) (xy 271.340072 -86.86419) (xy 271.308846 -86.894455)
			(xy 271.241443 -86.94941) (xy 271.169 -86.997526) (xy 271.092209 -87.038346) (xy 271.011802 -87.071479)
			(xy 270.928545 -87.09661) (xy 270.843235 -87.113498) (xy 270.756683 -87.121982) (xy 270.7132 -87.122508)
			(xy 270.712438 -87.122508) (xy 270.674218 -87.1221) (xy 270.598059 -87.115535) (xy 270.522747 -87.102451)
			(xy 270.448837 -87.082944) (xy 270.412718 -87.070438) (xy 270.404402 -87.067852) (xy 270.386998 -87.067852)
			(xy 270.378682 -87.070438) (xy 270.342559 -87.082929) (xy 270.268647 -87.102419) (xy 270.193336 -87.115503)
			(xy 270.117181 -87.122085) (xy 270.078962 -87.122508) (xy 270.0782 -87.122508) (xy 270.035852 -87.122004)
			(xy 269.951538 -87.113953) (xy 269.868372 -87.097924) (xy 269.787105 -87.074063) (xy 269.708475 -87.042584)
			(xy 269.633194 -87.003773) (xy 269.561942 -86.957983) (xy 269.495366 -86.905627) (xy 269.434068 -86.847179)
			(xy 269.378603 -86.783169) (xy 269.329474 -86.714177) (xy 269.287125 -86.640827) (xy 269.251941 -86.563784)
			(xy 269.224239 -86.483745) (xy 269.204271 -86.401436) (xy 269.192218 -86.317601) (xy 269.188188 -86.233)
			(xy 161.452327 -86.233) (xy 161.440415 -86.294806) (xy 161.416547 -86.376096) (xy 161.385059 -86.454748)
			(xy 161.346237 -86.530051) (xy 161.300434 -86.601323) (xy 161.248063 -86.667919) (xy 161.189598 -86.729234)
			(xy 161.12557 -86.784715) (xy 161.056558 -86.833858) (xy 160.983188 -86.876218) (xy 160.906123 -86.911413)
			(xy 160.826061 -86.939122) (xy 160.743728 -86.959096) (xy 160.659869 -86.971153) (xy 160.575244 -86.975185)
			(xy 160.490619 -86.971153) (xy 160.40676 -86.959096) (xy 160.324427 -86.939122) (xy 160.244365 -86.911413)
			(xy 160.1673 -86.876218) (xy 160.09393 -86.833858) (xy 160.024918 -86.784715) (xy 159.96089 -86.729234)
			(xy 159.902425 -86.667919) (xy 159.850054 -86.601323) (xy 159.804251 -86.530051) (xy 159.765429 -86.454748)
			(xy 159.733941 -86.376096) (xy 159.710073 -86.294806) (xy 159.694039 -86.211616) (xy 159.685986 -86.127279)
			(xy 0.509016 -86.127279) (xy 0.509016 -91.559888) (xy 41.345622 -91.559888) (xy 41.349604 -91.469938)
			(xy 41.361521 -91.380691) (xy 41.381279 -91.292847) (xy 41.408723 -91.207093) (xy 41.443639 -91.1241)
			(xy 41.485753 -91.044518) (xy 41.534736 -90.968969) (xy 41.590204 -90.898045) (xy 41.651724 -90.8323)
			(xy 41.718813 -90.77225) (xy 41.790947 -90.718365) (xy 41.867561 -90.671065) (xy 41.948055 -90.630722)
			(xy 42.0318 -90.59765) (xy 42.118141 -90.57211) (xy 42.2064 -90.5543) (xy 42.295889 -90.54436) (xy 42.385905 -90.542369)
			(xy 42.475746 -90.54834) (xy 42.564707 -90.562229) (xy 42.652092 -90.583925) (xy 42.737218 -90.61326)
			(xy 42.819418 -90.650003) (xy 42.898049 -90.693867) (xy 42.972496 -90.744509) (xy 43.042176 -90.801533)
			(xy 43.106543 -90.864492) (xy 43.165094 -90.932893) (xy 43.217371 -91.006201) (xy 43.262964 -91.083843)
			(xy 43.301517 -91.16521) (xy 43.332728 -91.249666) (xy 43.356352 -91.33655) (xy 43.372205 -91.425182)
			(xy 43.380162 -91.514869) (xy 43.38066 -91.559888) (xy 60.903622 -91.559888) (xy 60.907604 -91.469938)
			(xy 60.919521 -91.380691) (xy 60.939279 -91.292847) (xy 60.966723 -91.207093) (xy 61.001639 -91.1241)
			(xy 61.043753 -91.044518) (xy 61.092736 -90.968969) (xy 61.148204 -90.898045) (xy 61.209724 -90.8323)
			(xy 61.276813 -90.77225) (xy 61.348947 -90.718365) (xy 61.425561 -90.671065) (xy 61.506055 -90.630722)
			(xy 61.5898 -90.59765) (xy 61.676141 -90.57211) (xy 61.7644 -90.5543) (xy 61.853889 -90.54436) (xy 61.943905 -90.542369)
			(xy 62.033746 -90.54834) (xy 62.122707 -90.562229) (xy 62.210092 -90.583925) (xy 62.295218 -90.61326)
			(xy 62.377418 -90.650003) (xy 62.456049 -90.693867) (xy 62.530496 -90.744509) (xy 62.600176 -90.801533)
			(xy 62.664543 -90.864492) (xy 62.723094 -90.932893) (xy 62.775371 -91.006201) (xy 62.820964 -91.083843)
			(xy 62.859517 -91.16521) (xy 62.890728 -91.249666) (xy 62.914352 -91.33655) (xy 62.930205 -91.425182)
			(xy 62.938162 -91.514869) (xy 62.93866 -91.559888) (xy 377.061232 -91.559888) (xy 377.065214 -91.469938)
			(xy 377.077131 -91.380691) (xy 377.096889 -91.292847) (xy 377.124333 -91.207093) (xy 377.159249 -91.1241)
			(xy 377.201363 -91.044518) (xy 377.250346 -90.968969) (xy 377.305814 -90.898045) (xy 377.367334 -90.8323)
			(xy 377.434423 -90.77225) (xy 377.506557 -90.718365) (xy 377.583171 -90.671065) (xy 377.663665 -90.630722)
			(xy 377.74741 -90.59765) (xy 377.833751 -90.57211) (xy 377.92201 -90.5543) (xy 378.011499 -90.54436)
			(xy 378.101515 -90.542369) (xy 378.191356 -90.54834) (xy 378.280317 -90.562229) (xy 378.367702 -90.583925)
			(xy 378.452828 -90.61326) (xy 378.535028 -90.650003) (xy 378.613659 -90.693867) (xy 378.688106 -90.744509)
			(xy 378.757786 -90.801533) (xy 378.822153 -90.864492) (xy 378.880704 -90.932893) (xy 378.932981 -91.006201)
			(xy 378.978574 -91.083843) (xy 379.017127 -91.16521) (xy 379.048338 -91.249666) (xy 379.071962 -91.33655)
			(xy 379.087815 -91.425182) (xy 379.095772 -91.514869) (xy 379.09627 -91.559888) (xy 396.619232 -91.559888)
			(xy 396.623214 -91.469938) (xy 396.635131 -91.380691) (xy 396.654889 -91.292847) (xy 396.682333 -91.207093)
			(xy 396.717249 -91.1241) (xy 396.759363 -91.044518) (xy 396.808346 -90.968969) (xy 396.863814 -90.898045)
			(xy 396.925334 -90.8323) (xy 396.992423 -90.77225) (xy 397.064557 -90.718365) (xy 397.141171 -90.671065)
			(xy 397.221665 -90.630722) (xy 397.30541 -90.59765) (xy 397.391751 -90.57211) (xy 397.48001 -90.5543)
			(xy 397.569499 -90.54436) (xy 397.659515 -90.542369) (xy 397.749356 -90.54834) (xy 397.838317 -90.562229)
			(xy 397.925702 -90.583925) (xy 398.010828 -90.61326) (xy 398.093028 -90.650003) (xy 398.171659 -90.693867)
			(xy 398.246106 -90.744509) (xy 398.315786 -90.801533) (xy 398.380153 -90.864492) (xy 398.438704 -90.932893)
			(xy 398.490981 -91.006201) (xy 398.536574 -91.083843) (xy 398.575127 -91.16521) (xy 398.606338 -91.249666)
			(xy 398.629962 -91.33655) (xy 398.645815 -91.425182) (xy 398.653772 -91.514869) (xy 398.65416 -91.549982)
			(xy 470.018373 -91.549982) (xy 470.022363 -91.436999) (xy 470.034312 -91.324578) (xy 470.054162 -91.213281)
			(xy 470.081814 -91.103661) (xy 470.117128 -90.996264) (xy 470.159931 -90.891626) (xy 470.210008 -90.790268)
			(xy 470.26711 -90.692695) (xy 470.330952 -90.599393) (xy 470.401217 -90.510827) (xy 470.477554 -90.427437)
			(xy 470.559583 -90.34964) (xy 470.646896 -90.277823) (xy 470.739057 -90.212344) (xy 470.835607 -90.153529)
			(xy 470.936065 -90.101671) (xy 471.039932 -90.057029) (xy 471.146688 -90.019824) (xy 471.255803 -89.990242)
			(xy 471.366733 -89.968431) (xy 471.478925 -89.9545) (xy 471.59182 -89.948516) (xy 471.704856 -89.950512)
			(xy 471.81747 -89.960475) (xy 471.929101 -89.978358) (xy 472.039192 -90.00407) (xy 472.147195 -90.037484)
			(xy 472.252572 -90.078433) (xy 472.354798 -90.126714) (xy 472.453363 -90.182085) (xy 472.547778 -90.24427)
			(xy 472.63757 -90.312961) (xy 472.722294 -90.387815) (xy 472.801527 -90.468458) (xy 472.874873 -90.55449)
			(xy 472.941969 -90.645481) (xy 473.002478 -90.740978) (xy 473.056101 -90.840505) (xy 473.10257 -90.943568)
			(xy 473.141653 -91.049651) (xy 473.173156 -91.158227) (xy 473.196921 -91.268754) (xy 473.212831 -91.380683)
			(xy 473.220805 -91.493455) (xy 473.221304 -91.549982) (xy 473.220805 -91.606509) (xy 473.212831 -91.719281)
			(xy 473.196921 -91.83121) (xy 473.173156 -91.941737) (xy 473.141653 -92.050313) (xy 473.10257 -92.156396)
			(xy 473.056101 -92.259459) (xy 473.002478 -92.358986) (xy 472.941969 -92.454483) (xy 472.874873 -92.545474)
			(xy 472.801527 -92.631506) (xy 472.722294 -92.712149) (xy 472.63757 -92.787003) (xy 472.547778 -92.855694)
			(xy 472.453363 -92.917879) (xy 472.354798 -92.97325) (xy 472.252572 -93.021531) (xy 472.147195 -93.06248)
			(xy 472.039192 -93.095894) (xy 471.929101 -93.121606) (xy 471.81747 -93.139489) (xy 471.704856 -93.149452)
			(xy 471.59182 -93.151448) (xy 471.478925 -93.145464) (xy 471.366733 -93.131533) (xy 471.255803 -93.109722)
			(xy 471.146688 -93.08014) (xy 471.039932 -93.042935) (xy 470.936065 -92.998293) (xy 470.835607 -92.946435)
			(xy 470.739057 -92.88762) (xy 470.646896 -92.822141) (xy 470.559583 -92.750324) (xy 470.477554 -92.672527)
			(xy 470.401217 -92.589137) (xy 470.330952 -92.500571) (xy 470.26711 -92.407269) (xy 470.210008 -92.309696)
			(xy 470.159931 -92.208338) (xy 470.117128 -92.1037) (xy 470.081814 -91.996303) (xy 470.054162 -91.886683)
			(xy 470.034312 -91.775386) (xy 470.022363 -91.662965) (xy 470.018373 -91.549982) (xy 398.65416 -91.549982)
			(xy 398.65427 -91.559888) (xy 398.653772 -91.604907) (xy 398.645815 -91.694594) (xy 398.629962 -91.783226)
			(xy 398.606338 -91.87011) (xy 398.575127 -91.954566) (xy 398.536574 -92.035933) (xy 398.490981 -92.113575)
			(xy 398.438704 -92.186883) (xy 398.380153 -92.255284) (xy 398.315786 -92.318243) (xy 398.246106 -92.375267)
			(xy 398.171659 -92.425909) (xy 398.093028 -92.469773) (xy 398.010828 -92.506516) (xy 397.925702 -92.535851)
			(xy 397.838317 -92.557547) (xy 397.749356 -92.571436) (xy 397.659515 -92.577407) (xy 397.569499 -92.575416)
			(xy 397.48001 -92.565476) (xy 397.391751 -92.547666) (xy 397.30541 -92.522126) (xy 397.221665 -92.489054)
			(xy 397.141171 -92.448711) (xy 397.064557 -92.401411) (xy 396.992423 -92.347526) (xy 396.925334 -92.287476)
			(xy 396.863814 -92.221731) (xy 396.808346 -92.150807) (xy 396.759363 -92.075258) (xy 396.717249 -91.995676)
			(xy 396.682333 -91.912683) (xy 396.654889 -91.826929) (xy 396.635131 -91.739085) (xy 396.623214 -91.649838)
			(xy 396.619232 -91.559888) (xy 379.09627 -91.559888) (xy 379.095772 -91.604907) (xy 379.087815 -91.694594)
			(xy 379.071962 -91.783226) (xy 379.048338 -91.87011) (xy 379.017127 -91.954566) (xy 378.978574 -92.035933)
			(xy 378.932981 -92.113575) (xy 378.880704 -92.186883) (xy 378.822153 -92.255284) (xy 378.757786 -92.318243)
			(xy 378.688106 -92.375267) (xy 378.613659 -92.425909) (xy 378.535028 -92.469773) (xy 378.452828 -92.506516)
			(xy 378.367702 -92.535851) (xy 378.280317 -92.557547) (xy 378.191356 -92.571436) (xy 378.101515 -92.577407)
			(xy 378.011499 -92.575416) (xy 377.92201 -92.565476) (xy 377.833751 -92.547666) (xy 377.74741 -92.522126)
			(xy 377.663665 -92.489054) (xy 377.583171 -92.448711) (xy 377.506557 -92.401411) (xy 377.434423 -92.347526)
			(xy 377.367334 -92.287476) (xy 377.305814 -92.221731) (xy 377.250346 -92.150807) (xy 377.201363 -92.075258)
			(xy 377.159249 -91.995676) (xy 377.124333 -91.912683) (xy 377.096889 -91.826929) (xy 377.077131 -91.739085)
			(xy 377.065214 -91.649838) (xy 377.061232 -91.559888) (xy 62.93866 -91.559888) (xy 62.938162 -91.604907)
			(xy 62.930205 -91.694594) (xy 62.914352 -91.783226) (xy 62.890728 -91.87011) (xy 62.859517 -91.954566)
			(xy 62.820964 -92.035933) (xy 62.775371 -92.113575) (xy 62.723094 -92.186883) (xy 62.664543 -92.255284)
			(xy 62.600176 -92.318243) (xy 62.530496 -92.375267) (xy 62.456049 -92.425909) (xy 62.377418 -92.469773)
			(xy 62.295218 -92.506516) (xy 62.210092 -92.535851) (xy 62.122707 -92.557547) (xy 62.033746 -92.571436)
			(xy 61.943905 -92.577407) (xy 61.853889 -92.575416) (xy 61.7644 -92.565476) (xy 61.676141 -92.547666)
			(xy 61.5898 -92.522126) (xy 61.506055 -92.489054) (xy 61.425561 -92.448711) (xy 61.348947 -92.401411)
			(xy 61.276813 -92.347526) (xy 61.209724 -92.287476) (xy 61.148204 -92.221731) (xy 61.092736 -92.150807)
			(xy 61.043753 -92.075258) (xy 61.001639 -91.995676) (xy 60.966723 -91.912683) (xy 60.939279 -91.826929)
			(xy 60.919521 -91.739085) (xy 60.907604 -91.649838) (xy 60.903622 -91.559888) (xy 43.38066 -91.559888)
			(xy 43.380162 -91.604907) (xy 43.372205 -91.694594) (xy 43.356352 -91.783226) (xy 43.332728 -91.87011)
			(xy 43.301517 -91.954566) (xy 43.262964 -92.035933) (xy 43.217371 -92.113575) (xy 43.165094 -92.186883)
			(xy 43.106543 -92.255284) (xy 43.042176 -92.318243) (xy 42.972496 -92.375267) (xy 42.898049 -92.425909)
			(xy 42.819418 -92.469773) (xy 42.737218 -92.506516) (xy 42.652092 -92.535851) (xy 42.564707 -92.557547)
			(xy 42.475746 -92.571436) (xy 42.385905 -92.577407) (xy 42.295889 -92.575416) (xy 42.2064 -92.565476)
			(xy 42.118141 -92.547666) (xy 42.0318 -92.522126) (xy 41.948055 -92.489054) (xy 41.867561 -92.448711)
			(xy 41.790947 -92.401411) (xy 41.718813 -92.347526) (xy 41.651724 -92.287476) (xy 41.590204 -92.221731)
			(xy 41.534736 -92.150807) (xy 41.485753 -92.075258) (xy 41.443639 -91.995676) (xy 41.408723 -91.912683)
			(xy 41.381279 -91.826929) (xy 41.361521 -91.739085) (xy 41.349604 -91.649838) (xy 41.345622 -91.559888)
			(xy 0.509016 -91.559888) (xy 0.509016 -96.308361) (xy 157.479742 -96.308361) (xy 157.479742 -96.223639)
			(xy 157.487795 -96.139302) (xy 157.503829 -96.056112) (xy 157.527697 -95.974822) (xy 157.559185 -95.89617)
			(xy 157.598007 -95.820867) (xy 157.64381 -95.749595) (xy 157.696181 -95.682999) (xy 157.754646 -95.621684)
			(xy 157.818674 -95.566203) (xy 157.887686 -95.51706) (xy 157.961056 -95.4747) (xy 158.038121 -95.439505)
			(xy 158.118183 -95.411796) (xy 158.200516 -95.391822) (xy 158.284375 -95.379765) (xy 158.369 -95.375734)
			(xy 158.453625 -95.379765) (xy 158.537484 -95.391822) (xy 158.619817 -95.411796) (xy 158.699879 -95.439505)
			(xy 158.776944 -95.4747) (xy 158.850314 -95.51706) (xy 158.919326 -95.566203) (xy 158.983354 -95.621684)
			(xy 159.041819 -95.682999) (xy 159.09419 -95.749595) (xy 159.139993 -95.820867) (xy 159.178815 -95.89617)
			(xy 159.210303 -95.974822) (xy 159.234171 -96.056112) (xy 159.250205 -96.139302) (xy 159.258258 -96.223639)
			(xy 159.258762 -96.266) (xy 159.258258 -96.308361) (xy 159.250205 -96.392698) (xy 159.234171 -96.475888)
			(xy 159.210303 -96.557178) (xy 159.178815 -96.63583) (xy 159.139993 -96.711133) (xy 159.09419 -96.782405)
			(xy 159.041819 -96.849001) (xy 158.983354 -96.910316) (xy 158.919326 -96.965797) (xy 158.850314 -97.01494)
			(xy 158.776944 -97.0573) (xy 158.699879 -97.092495) (xy 158.619817 -97.120204) (xy 158.537484 -97.140178)
			(xy 158.453625 -97.152235) (xy 158.369 -97.156267) (xy 158.284375 -97.152235) (xy 158.200516 -97.140178)
			(xy 158.118183 -97.120204) (xy 158.038121 -97.092495) (xy 157.961056 -97.0573) (xy 157.887686 -97.01494)
			(xy 157.818674 -96.965797) (xy 157.754646 -96.910316) (xy 157.696181 -96.849001) (xy 157.64381 -96.782405)
			(xy 157.598007 -96.711133) (xy 157.559185 -96.63583) (xy 157.527697 -96.557178) (xy 157.503829 -96.475888)
			(xy 157.487795 -96.392698) (xy 157.479742 -96.308361) (xy 0.509016 -96.308361) (xy 0.509016 -99.06)
			(xy 40.838131 -99.06) (xy 40.842106 -98.949941) (xy 40.854014 -98.840455) (xy 40.87379 -98.732114)
			(xy 40.901333 -98.625483) (xy 40.936498 -98.521117) (xy 40.979102 -98.41956) (xy 41.028923 -98.321343)
			(xy 41.085702 -98.226976) (xy 41.149141 -98.136952) (xy 41.218912 -98.051741) (xy 41.294649 -97.971786)
			(xy 41.375958 -97.897505) (xy 41.462415 -97.829285) (xy 41.553569 -97.76748) (xy 41.648946 -97.712415)
			(xy 41.748047 -97.664375) (xy 41.850356 -97.623611) (xy 41.95534 -97.590336) (xy 42.062451 -97.564723)
			(xy 42.171131 -97.546906) (xy 42.280814 -97.536977) (xy 42.390927 -97.534989) (xy 42.500897 -97.540951)
			(xy 42.61015 -97.554833) (xy 42.718116 -97.576563) (xy 42.824233 -97.606026) (xy 42.927947 -97.643069)
			(xy 43.028718 -97.6875) (xy 43.12602 -97.739087) (xy 43.219346 -97.797559) (xy 43.308209 -97.862614)
			(xy 43.392147 -97.933912) (xy 43.470722 -98.01108) (xy 43.543523 -98.093717) (xy 43.610171 -98.181391)
			(xy 43.67032 -98.273647) (xy 43.723654 -98.370002) (xy 43.769897 -98.469954) (xy 43.808807 -98.572982)
			(xy 43.840181 -98.67855) (xy 43.863856 -98.786106) (xy 43.879708 -98.89509) (xy 43.887655 -99.004934)
			(xy 43.888152 -99.06) (xy 60.396131 -99.06) (xy 60.400106 -98.949941) (xy 60.412014 -98.840455) (xy 60.43179 -98.732114)
			(xy 60.459333 -98.625483) (xy 60.494498 -98.521117) (xy 60.537102 -98.41956) (xy 60.586923 -98.321343)
			(xy 60.643702 -98.226976) (xy 60.707141 -98.136952) (xy 60.776912 -98.051741) (xy 60.852649 -97.971786)
			(xy 60.933958 -97.897505) (xy 61.020415 -97.829285) (xy 61.111569 -97.76748) (xy 61.206946 -97.712415)
			(xy 61.306047 -97.664375) (xy 61.408356 -97.623611) (xy 61.51334 -97.590336) (xy 61.620451 -97.564723)
			(xy 61.729131 -97.546906) (xy 61.838814 -97.536977) (xy 61.948927 -97.534989) (xy 62.058897 -97.540951)
			(xy 62.16815 -97.554833) (xy 62.276116 -97.576563) (xy 62.382233 -97.606026) (xy 62.485947 -97.643069)
			(xy 62.586718 -97.6875) (xy 62.68402 -97.739087) (xy 62.777346 -97.797559) (xy 62.866209 -97.862614)
			(xy 62.950147 -97.933912) (xy 63.028722 -98.01108) (xy 63.101523 -98.093717) (xy 63.168171 -98.181391)
			(xy 63.22832 -98.273647) (xy 63.281654 -98.370002) (xy 63.327897 -98.469954) (xy 63.366807 -98.572982)
			(xy 63.398181 -98.67855) (xy 63.421856 -98.786106) (xy 63.437708 -98.89509) (xy 63.445655 -99.004934)
			(xy 63.446152 -99.06) (xy 376.553741 -99.06) (xy 376.557716 -98.949941) (xy 376.569624 -98.840455)
			(xy 376.5894 -98.732114) (xy 376.616943 -98.625483) (xy 376.652108 -98.521117) (xy 376.694712 -98.41956)
			(xy 376.744533 -98.321343) (xy 376.801312 -98.226976) (xy 376.864751 -98.136952) (xy 376.934522 -98.051741)
			(xy 377.010259 -97.971786) (xy 377.091568 -97.897505) (xy 377.178025 -97.829285) (xy 377.269179 -97.76748)
			(xy 377.364556 -97.712415) (xy 377.463657 -97.664375) (xy 377.565966 -97.623611) (xy 377.67095 -97.590336)
			(xy 377.778061 -97.564723) (xy 377.886741 -97.546906) (xy 377.996424 -97.536977) (xy 378.106537 -97.534989)
			(xy 378.216507 -97.540951) (xy 378.32576 -97.554833) (xy 378.433726 -97.576563) (xy 378.539843 -97.606026)
			(xy 378.643557 -97.643069) (xy 378.744328 -97.6875) (xy 378.84163 -97.739087) (xy 378.934956 -97.797559)
			(xy 379.023819 -97.862614) (xy 379.107757 -97.933912) (xy 379.186332 -98.01108) (xy 379.259133 -98.093717)
			(xy 379.325781 -98.181391) (xy 379.38593 -98.273647) (xy 379.439264 -98.370002) (xy 379.485507 -98.469954)
			(xy 379.524417 -98.572982) (xy 379.555791 -98.67855) (xy 379.579466 -98.786106) (xy 379.595318 -98.89509)
			(xy 379.603265 -99.004934) (xy 379.603762 -99.06) (xy 396.111741 -99.06) (xy 396.115716 -98.949941)
			(xy 396.127624 -98.840455) (xy 396.1474 -98.732114) (xy 396.174943 -98.625483) (xy 396.210108 -98.521117)
			(xy 396.252712 -98.41956) (xy 396.302533 -98.321343) (xy 396.359312 -98.226976) (xy 396.422751 -98.136952)
			(xy 396.492522 -98.051741) (xy 396.568259 -97.971786) (xy 396.649568 -97.897505) (xy 396.736025 -97.829285)
			(xy 396.827179 -97.76748) (xy 396.922556 -97.712415) (xy 397.021657 -97.664375) (xy 397.123966 -97.623611)
			(xy 397.22895 -97.590336) (xy 397.336061 -97.564723) (xy 397.444741 -97.546906) (xy 397.554424 -97.536977)
			(xy 397.664537 -97.534989) (xy 397.774507 -97.540951) (xy 397.88376 -97.554833) (xy 397.991726 -97.576563)
			(xy 398.097843 -97.606026) (xy 398.201557 -97.643069) (xy 398.302328 -97.6875) (xy 398.39963 -97.739087)
			(xy 398.492956 -97.797559) (xy 398.581819 -97.862614) (xy 398.665757 -97.933912) (xy 398.744332 -98.01108)
			(xy 398.817133 -98.093717) (xy 398.883781 -98.181391) (xy 398.94393 -98.273647) (xy 398.997264 -98.370002)
			(xy 399.043507 -98.469954) (xy 399.082417 -98.572982) (xy 399.113791 -98.67855) (xy 399.137466 -98.786106)
			(xy 399.153318 -98.89509) (xy 399.161265 -99.004934) (xy 399.161762 -99.06) (xy 399.161265 -99.115066)
			(xy 399.153318 -99.22491) (xy 399.137466 -99.333894) (xy 399.113791 -99.44145) (xy 399.082417 -99.547018)
			(xy 399.043507 -99.650046) (xy 398.997264 -99.749998) (xy 398.94393 -99.846353) (xy 398.883781 -99.938609)
			(xy 398.817133 -100.026283) (xy 398.744332 -100.10892) (xy 398.665757 -100.186088) (xy 398.581819 -100.257386)
			(xy 398.492956 -100.322441) (xy 398.39963 -100.380913) (xy 398.302328 -100.4325) (xy 398.201557 -100.476931)
			(xy 398.097843 -100.513974) (xy 397.991726 -100.543437) (xy 397.88376 -100.565167) (xy 397.774507 -100.579049)
			(xy 397.664537 -100.585011) (xy 397.554424 -100.583023) (xy 397.444741 -100.573094) (xy 397.336061 -100.555277)
			(xy 397.22895 -100.529664) (xy 397.123966 -100.496389) (xy 397.021657 -100.455625) (xy 396.922556 -100.407585)
			(xy 396.827179 -100.35252) (xy 396.736025 -100.290715) (xy 396.649568 -100.222495) (xy 396.568259 -100.148214)
			(xy 396.492522 -100.068259) (xy 396.422751 -99.983048) (xy 396.359312 -99.893024) (xy 396.302533 -99.798657)
			(xy 396.252712 -99.70044) (xy 396.210108 -99.598883) (xy 396.174943 -99.494517) (xy 396.1474 -99.387886)
			(xy 396.127624 -99.279545) (xy 396.115716 -99.170059) (xy 396.111741 -99.06) (xy 379.603762 -99.06)
			(xy 379.603265 -99.115066) (xy 379.595318 -99.22491) (xy 379.579466 -99.333894) (xy 379.555791 -99.44145)
			(xy 379.524417 -99.547018) (xy 379.485507 -99.650046) (xy 379.439264 -99.749998) (xy 379.38593 -99.846353)
			(xy 379.325781 -99.938609) (xy 379.259133 -100.026283) (xy 379.186332 -100.10892) (xy 379.107757 -100.186088)
			(xy 379.023819 -100.257386) (xy 378.934956 -100.322441) (xy 378.84163 -100.380913) (xy 378.744328 -100.4325)
			(xy 378.643557 -100.476931) (xy 378.539843 -100.513974) (xy 378.433726 -100.543437) (xy 378.32576 -100.565167)
			(xy 378.216507 -100.579049) (xy 378.106537 -100.585011) (xy 377.996424 -100.583023) (xy 377.886741 -100.573094)
			(xy 377.778061 -100.555277) (xy 377.67095 -100.529664) (xy 377.565966 -100.496389) (xy 377.463657 -100.455625)
			(xy 377.364556 -100.407585) (xy 377.269179 -100.35252) (xy 377.178025 -100.290715) (xy 377.091568 -100.222495)
			(xy 377.010259 -100.148214) (xy 376.934522 -100.068259) (xy 376.864751 -99.983048) (xy 376.801312 -99.893024)
			(xy 376.744533 -99.798657) (xy 376.694712 -99.70044) (xy 376.652108 -99.598883) (xy 376.616943 -99.494517)
			(xy 376.5894 -99.387886) (xy 376.569624 -99.279545) (xy 376.557716 -99.170059) (xy 376.553741 -99.06)
			(xy 63.446152 -99.06) (xy 63.445655 -99.115066) (xy 63.437708 -99.22491) (xy 63.421856 -99.333894)
			(xy 63.398181 -99.44145) (xy 63.366807 -99.547018) (xy 63.327897 -99.650046) (xy 63.281654 -99.749998)
			(xy 63.22832 -99.846353) (xy 63.168171 -99.938609) (xy 63.101523 -100.026283) (xy 63.028722 -100.10892)
			(xy 62.950147 -100.186088) (xy 62.866209 -100.257386) (xy 62.777346 -100.322441) (xy 62.68402 -100.380913)
			(xy 62.586718 -100.4325) (xy 62.485947 -100.476931) (xy 62.382233 -100.513974) (xy 62.276116 -100.543437)
			(xy 62.16815 -100.565167) (xy 62.058897 -100.579049) (xy 61.948927 -100.585011) (xy 61.838814 -100.583023)
			(xy 61.729131 -100.573094) (xy 61.620451 -100.555277) (xy 61.51334 -100.529664) (xy 61.408356 -100.496389)
			(xy 61.306047 -100.455625) (xy 61.206946 -100.407585) (xy 61.111569 -100.35252) (xy 61.020415 -100.290715)
			(xy 60.933958 -100.222495) (xy 60.852649 -100.148214) (xy 60.776912 -100.068259) (xy 60.707141 -99.983048)
			(xy 60.643702 -99.893024) (xy 60.586923 -99.798657) (xy 60.537102 -99.70044) (xy 60.494498 -99.598883)
			(xy 60.459333 -99.494517) (xy 60.43179 -99.387886) (xy 60.412014 -99.279545) (xy 60.400106 -99.170059)
			(xy 60.396131 -99.06) (xy 43.888152 -99.06) (xy 43.887655 -99.115066) (xy 43.879708 -99.22491) (xy 43.863856 -99.333894)
			(xy 43.840181 -99.44145) (xy 43.808807 -99.547018) (xy 43.769897 -99.650046) (xy 43.723654 -99.749998)
			(xy 43.67032 -99.846353) (xy 43.610171 -99.938609) (xy 43.543523 -100.026283) (xy 43.470722 -100.10892)
			(xy 43.392147 -100.186088) (xy 43.308209 -100.257386) (xy 43.219346 -100.322441) (xy 43.12602 -100.380913)
			(xy 43.028718 -100.4325) (xy 42.927947 -100.476931) (xy 42.824233 -100.513974) (xy 42.718116 -100.543437)
			(xy 42.61015 -100.565167) (xy 42.500897 -100.579049) (xy 42.390927 -100.585011) (xy 42.280814 -100.583023)
			(xy 42.171131 -100.573094) (xy 42.062451 -100.555277) (xy 41.95534 -100.529664) (xy 41.850356 -100.496389)
			(xy 41.748047 -100.455625) (xy 41.648946 -100.407585) (xy 41.553569 -100.35252) (xy 41.462415 -100.290715)
			(xy 41.375958 -100.222495) (xy 41.294649 -100.148214) (xy 41.218912 -100.068259) (xy 41.149141 -99.983048)
			(xy 41.085702 -99.893024) (xy 41.028923 -99.798657) (xy 40.979102 -99.70044) (xy 40.936498 -99.598883)
			(xy 40.901333 -99.494517) (xy 40.87379 -99.387886) (xy 40.854014 -99.279545) (xy 40.842106 -99.170059)
			(xy 40.838131 -99.06) (xy 0.509016 -99.06) (xy 0.509016 -104.544876) (xy 12.484104 -104.544876) (xy 12.488134 -104.402541)
			(xy 12.500209 -104.260661) (xy 12.520292 -104.119693) (xy 12.548319 -103.980086) (xy 12.584199 -103.842288)
			(xy 12.627817 -103.706741) (xy 12.679034 -103.573879) (xy 12.737685 -103.444127) (xy 12.803583 -103.317901)
			(xy 12.876517 -103.195605) (xy 12.956254 -103.077632) (xy 13.042536 -102.964359) (xy 13.135089 -102.856148)
			(xy 13.233616 -102.753347) (xy 13.337801 -102.656285) (xy 13.44731 -102.565273) (xy 13.561793 -102.480601)
			(xy 13.680883 -102.402543) (xy 13.804198 -102.331347) (xy 13.931344 -102.267241) (xy 14.061913 -102.210432)
			(xy 14.195487 -102.1611) (xy 14.331638 -102.119404) (xy 14.469929 -102.085478) (xy 14.609919 -102.05943)
			(xy 14.751158 -102.041344) (xy 14.893194 -102.031277) (xy 15.035572 -102.029262) (xy 15.177836 -102.035305)
			(xy 15.31953 -102.049387) (xy 15.4602 -102.071463) (xy 15.599397 -102.101463) (xy 15.736673 -102.139289)
			(xy 15.871589 -102.184821) (xy 16.003713 -102.237912) (xy 16.132622 -102.298394) (xy 16.257903 -102.366072)
			(xy 16.379154 -102.440729) (xy 16.495987 -102.522127) (xy 16.608028 -102.610004) (xy 16.714918 -102.704079)
			(xy 16.816315 -102.804051) (xy 16.911893 -102.909599) (xy 17.001347 -103.020385) (xy 17.084389 -103.136054)
			(xy 17.160755 -103.256237) (xy 17.230199 -103.380547) (xy 17.292499 -103.508588) (xy 17.347455 -103.639947)
			(xy 17.394892 -103.774206) (xy 17.434656 -103.910933) (xy 17.466622 -104.049691) (xy 17.490687 -104.190035)
			(xy 17.506773 -104.331516) (xy 17.514828 -104.47368) (xy 17.515332 -104.544876) (xy 17.514828 -104.616072)
			(xy 17.506773 -104.758236) (xy 17.490687 -104.899717) (xy 17.466622 -105.040061) (xy 17.434656 -105.178819)
			(xy 17.394892 -105.315546) (xy 17.347455 -105.449805) (xy 17.292499 -105.581164) (xy 17.230199 -105.709205)
			(xy 17.160755 -105.833515) (xy 17.084389 -105.953698) (xy 17.001347 -106.069367) (xy 16.911893 -106.180153)
			(xy 16.816315 -106.285701) (xy 16.714918 -106.385673) (xy 16.608028 -106.479748) (xy 16.495987 -106.567625)
			(xy 16.379154 -106.649023) (xy 16.257903 -106.72368) (xy 16.132622 -106.791358) (xy 16.003713 -106.85184)
			(xy 15.871589 -106.904931) (xy 15.736673 -106.950463) (xy 15.599397 -106.988289) (xy 15.4602 -107.018289)
			(xy 15.31953 -107.040365) (xy 15.177836 -107.054447) (xy 15.035572 -107.06049) (xy 14.893194 -107.058475)
			(xy 14.751158 -107.048408) (xy 14.609919 -107.030322) (xy 14.469929 -107.004274) (xy 14.331638 -106.970348)
			(xy 14.195487 -106.928652) (xy 14.061913 -106.87932) (xy 13.931344 -106.822511) (xy 13.804198 -106.758405)
			(xy 13.680883 -106.687209) (xy 13.561793 -106.609151) (xy 13.44731 -106.524479) (xy 13.337801 -106.433467)
			(xy 13.233616 -106.336405) (xy 13.135089 -106.233604) (xy 13.042536 -106.125393) (xy 12.956254 -106.01212)
			(xy 12.876517 -105.894147) (xy 12.803583 -105.771851) (xy 12.737685 -105.645625) (xy 12.679034 -105.515873)
			(xy 12.627817 -105.383011) (xy 12.584199 -105.247464) (xy 12.548319 -105.109666) (xy 12.520292 -104.970059)
			(xy 12.500209 -104.829091) (xy 12.488134 -104.687211) (xy 12.484104 -104.544876) (xy 0.509016 -104.544876)
			(xy 0.509016 -111.879888) (xy 41.345622 -111.879888) (xy 41.349604 -111.789938) (xy 41.361521 -111.700691)
			(xy 41.381279 -111.612847) (xy 41.408723 -111.527093) (xy 41.443639 -111.4441) (xy 41.485753 -111.364518)
			(xy 41.534736 -111.288969) (xy 41.590204 -111.218045) (xy 41.651724 -111.1523) (xy 41.718813 -111.09225)
			(xy 41.790947 -111.038365) (xy 41.867561 -110.991065) (xy 41.948055 -110.950722) (xy 42.0318 -110.91765)
			(xy 42.118141 -110.89211) (xy 42.2064 -110.8743) (xy 42.295889 -110.86436) (xy 42.385905 -110.862369)
			(xy 42.475746 -110.86834) (xy 42.564707 -110.882229) (xy 42.652092 -110.903925) (xy 42.737218 -110.93326)
			(xy 42.819418 -110.970003) (xy 42.898049 -111.013867) (xy 42.972496 -111.064509) (xy 43.042176 -111.121533)
			(xy 43.106543 -111.184492) (xy 43.165094 -111.252893) (xy 43.217371 -111.326201) (xy 43.262964 -111.403843)
			(xy 43.301517 -111.48521) (xy 43.332728 -111.569666) (xy 43.356352 -111.65655) (xy 43.372205 -111.745182)
			(xy 43.380162 -111.834869) (xy 43.38066 -111.879888) (xy 60.903622 -111.879888) (xy 60.907604 -111.789938)
			(xy 60.919521 -111.700691) (xy 60.939279 -111.612847) (xy 60.966723 -111.527093) (xy 61.001639 -111.4441)
			(xy 61.043753 -111.364518) (xy 61.092736 -111.288969) (xy 61.148204 -111.218045) (xy 61.209724 -111.1523)
			(xy 61.276813 -111.09225) (xy 61.348947 -111.038365) (xy 61.425561 -110.991065) (xy 61.506055 -110.950722)
			(xy 61.5898 -110.91765) (xy 61.676141 -110.89211) (xy 61.7644 -110.8743) (xy 61.853889 -110.86436)
			(xy 61.943905 -110.862369) (xy 62.033746 -110.86834) (xy 62.122707 -110.882229) (xy 62.210092 -110.903925)
			(xy 62.295218 -110.93326) (xy 62.377418 -110.970003) (xy 62.456049 -111.013867) (xy 62.530496 -111.064509)
			(xy 62.600176 -111.121533) (xy 62.664543 -111.184492) (xy 62.723094 -111.252893) (xy 62.775371 -111.326201)
			(xy 62.820964 -111.403843) (xy 62.859517 -111.48521) (xy 62.890728 -111.569666) (xy 62.914352 -111.65655)
			(xy 62.930205 -111.745182) (xy 62.938162 -111.834869) (xy 62.93866 -111.879888) (xy 62.938162 -111.924907)
			(xy 62.930205 -112.014594) (xy 62.914352 -112.103226) (xy 62.890728 -112.19011) (xy 62.859517 -112.274566)
			(xy 62.820964 -112.355933) (xy 62.775371 -112.433575) (xy 62.723094 -112.506883) (xy 62.664543 -112.575284)
			(xy 62.600176 -112.638243) (xy 62.530496 -112.695267) (xy 62.456049 -112.745909) (xy 62.377418 -112.789773)
			(xy 62.295218 -112.826516) (xy 62.210092 -112.855851) (xy 62.122707 -112.877547) (xy 62.033746 -112.891436)
			(xy 61.943905 -112.897407) (xy 61.853889 -112.895416) (xy 61.7644 -112.885476) (xy 61.676141 -112.867666)
			(xy 61.5898 -112.842126) (xy 61.506055 -112.809054) (xy 61.425561 -112.768711) (xy 61.348947 -112.721411)
			(xy 61.276813 -112.667526) (xy 61.209724 -112.607476) (xy 61.148204 -112.541731) (xy 61.092736 -112.470807)
			(xy 61.043753 -112.395258) (xy 61.001639 -112.315676) (xy 60.966723 -112.232683) (xy 60.939279 -112.146929)
			(xy 60.919521 -112.059085) (xy 60.907604 -111.969838) (xy 60.903622 -111.879888) (xy 43.38066 -111.879888)
			(xy 43.380162 -111.924907) (xy 43.372205 -112.014594) (xy 43.356352 -112.103226) (xy 43.332728 -112.19011)
			(xy 43.301517 -112.274566) (xy 43.262964 -112.355933) (xy 43.217371 -112.433575) (xy 43.165094 -112.506883)
			(xy 43.106543 -112.575284) (xy 43.042176 -112.638243) (xy 42.972496 -112.695267) (xy 42.898049 -112.745909)
			(xy 42.819418 -112.789773) (xy 42.737218 -112.826516) (xy 42.652092 -112.855851) (xy 42.564707 -112.877547)
			(xy 42.475746 -112.891436) (xy 42.385905 -112.897407) (xy 42.295889 -112.895416) (xy 42.2064 -112.885476)
			(xy 42.118141 -112.867666) (xy 42.0318 -112.842126) (xy 41.948055 -112.809054) (xy 41.867561 -112.768711)
			(xy 41.790947 -112.721411) (xy 41.718813 -112.667526) (xy 41.651724 -112.607476) (xy 41.590204 -112.541731)
			(xy 41.534736 -112.470807) (xy 41.485753 -112.395258) (xy 41.443639 -112.315676) (xy 41.408723 -112.232683)
			(xy 41.381279 -112.146929) (xy 41.361521 -112.059085) (xy 41.349604 -111.969838) (xy 41.345622 -111.879888)
			(xy 0.509016 -111.879888) (xy 0.509016 -119.38) (xy 40.838131 -119.38) (xy 40.842106 -119.269941)
			(xy 40.854014 -119.160455) (xy 40.87379 -119.052114) (xy 40.901333 -118.945483) (xy 40.936498 -118.841117)
			(xy 40.979102 -118.73956) (xy 41.028923 -118.641343) (xy 41.085702 -118.546976) (xy 41.149141 -118.456952)
			(xy 41.218912 -118.371741) (xy 41.294649 -118.291786) (xy 41.375958 -118.217505) (xy 41.462415 -118.149285)
			(xy 41.553569 -118.08748) (xy 41.648946 -118.032415) (xy 41.748047 -117.984375) (xy 41.850356 -117.943611)
			(xy 41.95534 -117.910336) (xy 42.062451 -117.884723) (xy 42.171131 -117.866906) (xy 42.280814 -117.856977)
			(xy 42.390927 -117.854989) (xy 42.500897 -117.860951) (xy 42.61015 -117.874833) (xy 42.718116 -117.896563)
			(xy 42.824233 -117.926026) (xy 42.927947 -117.963069) (xy 43.028718 -118.0075) (xy 43.12602 -118.059087)
			(xy 43.219346 -118.117559) (xy 43.308209 -118.182614) (xy 43.392147 -118.253912) (xy 43.470722 -118.33108)
			(xy 43.543523 -118.413717) (xy 43.610171 -118.501391) (xy 43.67032 -118.593647) (xy 43.723654 -118.690002)
			(xy 43.769897 -118.789954) (xy 43.808807 -118.892982) (xy 43.840181 -118.99855) (xy 43.863856 -119.106106)
			(xy 43.879708 -119.21509) (xy 43.887655 -119.324934) (xy 43.888152 -119.38) (xy 60.396131 -119.38)
			(xy 60.400106 -119.269941) (xy 60.412014 -119.160455) (xy 60.43179 -119.052114) (xy 60.459333 -118.945483)
			(xy 60.494498 -118.841117) (xy 60.537102 -118.73956) (xy 60.586923 -118.641343) (xy 60.643702 -118.546976)
			(xy 60.707141 -118.456952) (xy 60.776912 -118.371741) (xy 60.852649 -118.291786) (xy 60.933958 -118.217505)
			(xy 61.020415 -118.149285) (xy 61.111569 -118.08748) (xy 61.206946 -118.032415) (xy 61.306047 -117.984375)
			(xy 61.408356 -117.943611) (xy 61.51334 -117.910336) (xy 61.620451 -117.884723) (xy 61.729131 -117.866906)
			(xy 61.838814 -117.856977) (xy 61.948927 -117.854989) (xy 62.058897 -117.860951) (xy 62.16815 -117.874833)
			(xy 62.276116 -117.896563) (xy 62.382233 -117.926026) (xy 62.485947 -117.963069) (xy 62.586718 -118.0075)
			(xy 62.68402 -118.059087) (xy 62.777346 -118.117559) (xy 62.866209 -118.182614) (xy 62.950147 -118.253912)
			(xy 63.028722 -118.33108) (xy 63.101523 -118.413717) (xy 63.168171 -118.501391) (xy 63.22832 -118.593647)
			(xy 63.281654 -118.690002) (xy 63.327897 -118.789954) (xy 63.366807 -118.892982) (xy 63.398181 -118.99855)
			(xy 63.421856 -119.106106) (xy 63.437708 -119.21509) (xy 63.445655 -119.324934) (xy 63.446152 -119.38)
			(xy 63.445655 -119.435066) (xy 63.437708 -119.54491) (xy 63.421856 -119.653894) (xy 63.398181 -119.76145)
			(xy 63.366807 -119.867018) (xy 63.327897 -119.970046) (xy 63.281654 -120.069998) (xy 63.22832 -120.166353)
			(xy 63.168171 -120.258609) (xy 63.101523 -120.346283) (xy 63.028722 -120.42892) (xy 62.950147 -120.506088)
			(xy 62.866209 -120.577386) (xy 62.777346 -120.642441) (xy 62.68402 -120.700913) (xy 62.586718 -120.7525)
			(xy 62.485947 -120.796931) (xy 62.382233 -120.833974) (xy 62.276116 -120.863437) (xy 62.16815 -120.885167)
			(xy 62.058897 -120.899049) (xy 61.948927 -120.905011) (xy 61.838814 -120.903023) (xy 61.729131 -120.893094)
			(xy 61.620451 -120.875277) (xy 61.51334 -120.849664) (xy 61.408356 -120.816389) (xy 61.306047 -120.775625)
			(xy 61.206946 -120.727585) (xy 61.111569 -120.67252) (xy 61.020415 -120.610715) (xy 60.933958 -120.542495)
			(xy 60.852649 -120.468214) (xy 60.776912 -120.388259) (xy 60.707141 -120.303048) (xy 60.643702 -120.213024)
			(xy 60.586923 -120.118657) (xy 60.537102 -120.02044) (xy 60.494498 -119.918883) (xy 60.459333 -119.814517)
			(xy 60.43179 -119.707886) (xy 60.412014 -119.599545) (xy 60.400106 -119.490059) (xy 60.396131 -119.38)
			(xy 43.888152 -119.38) (xy 43.887655 -119.435066) (xy 43.879708 -119.54491) (xy 43.863856 -119.653894)
			(xy 43.840181 -119.76145) (xy 43.808807 -119.867018) (xy 43.769897 -119.970046) (xy 43.723654 -120.069998)
			(xy 43.67032 -120.166353) (xy 43.610171 -120.258609) (xy 43.543523 -120.346283) (xy 43.470722 -120.42892)
			(xy 43.392147 -120.506088) (xy 43.308209 -120.577386) (xy 43.219346 -120.642441) (xy 43.12602 -120.700913)
			(xy 43.028718 -120.7525) (xy 42.927947 -120.796931) (xy 42.824233 -120.833974) (xy 42.718116 -120.863437)
			(xy 42.61015 -120.885167) (xy 42.500897 -120.899049) (xy 42.390927 -120.905011) (xy 42.280814 -120.903023)
			(xy 42.171131 -120.893094) (xy 42.062451 -120.875277) (xy 41.95534 -120.849664) (xy 41.850356 -120.816389)
			(xy 41.748047 -120.775625) (xy 41.648946 -120.727585) (xy 41.553569 -120.67252) (xy 41.462415 -120.610715)
			(xy 41.375958 -120.542495) (xy 41.294649 -120.468214) (xy 41.218912 -120.388259) (xy 41.149141 -120.303048)
			(xy 41.085702 -120.213024) (xy 41.028923 -120.118657) (xy 40.979102 -120.02044) (xy 40.936498 -119.918883)
			(xy 40.901333 -119.814517) (xy 40.87379 -119.707886) (xy 40.854014 -119.599545) (xy 40.842106 -119.490059)
			(xy 40.838131 -119.38) (xy 0.509016 -119.38) (xy 0.509016 -132.199888) (xy 41.345622 -132.199888)
			(xy 41.349604 -132.109938) (xy 41.361521 -132.020691) (xy 41.381279 -131.932847) (xy 41.408723 -131.847093)
			(xy 41.443639 -131.7641) (xy 41.485753 -131.684518) (xy 41.534736 -131.608969) (xy 41.590204 -131.538045)
			(xy 41.651724 -131.4723) (xy 41.718813 -131.41225) (xy 41.790947 -131.358365) (xy 41.867561 -131.311065)
			(xy 41.948055 -131.270722) (xy 42.0318 -131.23765) (xy 42.118141 -131.21211) (xy 42.2064 -131.1943)
			(xy 42.295889 -131.18436) (xy 42.385905 -131.182369) (xy 42.475746 -131.18834) (xy 42.564707 -131.202229)
			(xy 42.652092 -131.223925) (xy 42.737218 -131.25326) (xy 42.819418 -131.290003) (xy 42.898049 -131.333867)
			(xy 42.972496 -131.384509) (xy 43.042176 -131.441533) (xy 43.106543 -131.504492) (xy 43.165094 -131.572893)
			(xy 43.217371 -131.646201) (xy 43.262964 -131.723843) (xy 43.301517 -131.80521) (xy 43.332728 -131.889666)
			(xy 43.356352 -131.97655) (xy 43.372205 -132.065182) (xy 43.380162 -132.154869) (xy 43.38066 -132.199888)
			(xy 60.903622 -132.199888) (xy 60.907604 -132.109938) (xy 60.919521 -132.020691) (xy 60.939279 -131.932847)
			(xy 60.966723 -131.847093) (xy 61.001639 -131.7641) (xy 61.043753 -131.684518) (xy 61.092736 -131.608969)
			(xy 61.148204 -131.538045) (xy 61.209724 -131.4723) (xy 61.276813 -131.41225) (xy 61.348947 -131.358365)
			(xy 61.425561 -131.311065) (xy 61.506055 -131.270722) (xy 61.5898 -131.23765) (xy 61.676141 -131.21211)
			(xy 61.7644 -131.1943) (xy 61.853889 -131.18436) (xy 61.943905 -131.182369) (xy 62.033746 -131.18834)
			(xy 62.122707 -131.202229) (xy 62.210092 -131.223925) (xy 62.295218 -131.25326) (xy 62.377418 -131.290003)
			(xy 62.456049 -131.333867) (xy 62.530496 -131.384509) (xy 62.600176 -131.441533) (xy 62.664543 -131.504492)
			(xy 62.723094 -131.572893) (xy 62.775371 -131.646201) (xy 62.820964 -131.723843) (xy 62.859517 -131.80521)
			(xy 62.890728 -131.889666) (xy 62.914352 -131.97655) (xy 62.930205 -132.065182) (xy 62.938162 -132.154869)
			(xy 62.93866 -132.199888) (xy 62.938162 -132.244907) (xy 62.930205 -132.334594) (xy 62.914352 -132.423226)
			(xy 62.890728 -132.51011) (xy 62.859517 -132.594566) (xy 62.820964 -132.675933) (xy 62.775371 -132.753575)
			(xy 62.723094 -132.826883) (xy 62.664543 -132.895284) (xy 62.600176 -132.958243) (xy 62.530496 -133.015267)
			(xy 62.456049 -133.065909) (xy 62.377418 -133.109773) (xy 62.295218 -133.146516) (xy 62.210092 -133.175851)
			(xy 62.122707 -133.197547) (xy 62.033746 -133.211436) (xy 61.943905 -133.217407) (xy 61.853889 -133.215416)
			(xy 61.7644 -133.205476) (xy 61.676141 -133.187666) (xy 61.5898 -133.162126) (xy 61.506055 -133.129054)
			(xy 61.425561 -133.088711) (xy 61.348947 -133.041411) (xy 61.276813 -132.987526) (xy 61.209724 -132.927476)
			(xy 61.148204 -132.861731) (xy 61.092736 -132.790807) (xy 61.043753 -132.715258) (xy 61.001639 -132.635676)
			(xy 60.966723 -132.552683) (xy 60.939279 -132.466929) (xy 60.919521 -132.379085) (xy 60.907604 -132.289838)
			(xy 60.903622 -132.199888) (xy 43.38066 -132.199888) (xy 43.380162 -132.244907) (xy 43.372205 -132.334594)
			(xy 43.356352 -132.423226) (xy 43.332728 -132.51011) (xy 43.301517 -132.594566) (xy 43.262964 -132.675933)
			(xy 43.217371 -132.753575) (xy 43.165094 -132.826883) (xy 43.106543 -132.895284) (xy 43.042176 -132.958243)
			(xy 42.972496 -133.015267) (xy 42.898049 -133.065909) (xy 42.819418 -133.109773) (xy 42.737218 -133.146516)
			(xy 42.652092 -133.175851) (xy 42.564707 -133.197547) (xy 42.475746 -133.211436) (xy 42.385905 -133.217407)
			(xy 42.295889 -133.215416) (xy 42.2064 -133.205476) (xy 42.118141 -133.187666) (xy 42.0318 -133.162126)
			(xy 41.948055 -133.129054) (xy 41.867561 -133.088711) (xy 41.790947 -133.041411) (xy 41.718813 -132.987526)
			(xy 41.651724 -132.927476) (xy 41.590204 -132.861731) (xy 41.534736 -132.790807) (xy 41.485753 -132.715258)
			(xy 41.443639 -132.635676) (xy 41.408723 -132.552683) (xy 41.381279 -132.466929) (xy 41.361521 -132.379085)
			(xy 41.349604 -132.289838) (xy 41.345622 -132.199888) (xy 0.509016 -132.199888) (xy 0.509016 -139.7)
			(xy 40.838131 -139.7) (xy 40.842106 -139.589941) (xy 40.854014 -139.480455) (xy 40.87379 -139.372114)
			(xy 40.901333 -139.265483) (xy 40.936498 -139.161117) (xy 40.979102 -139.05956) (xy 41.028923 -138.961343)
			(xy 41.085702 -138.866976) (xy 41.149141 -138.776952) (xy 41.218912 -138.691741) (xy 41.294649 -138.611786)
			(xy 41.375958 -138.537505) (xy 41.462415 -138.469285) (xy 41.553569 -138.40748) (xy 41.648946 -138.352415)
			(xy 41.748047 -138.304375) (xy 41.850356 -138.263611) (xy 41.95534 -138.230336) (xy 42.062451 -138.204723)
			(xy 42.171131 -138.186906) (xy 42.280814 -138.176977) (xy 42.390927 -138.174989) (xy 42.500897 -138.180951)
			(xy 42.61015 -138.194833) (xy 42.718116 -138.216563) (xy 42.824233 -138.246026) (xy 42.927947 -138.283069)
			(xy 43.028718 -138.3275) (xy 43.12602 -138.379087) (xy 43.219346 -138.437559) (xy 43.308209 -138.502614)
			(xy 43.392147 -138.573912) (xy 43.470722 -138.65108) (xy 43.543523 -138.733717) (xy 43.610171 -138.821391)
			(xy 43.67032 -138.913647) (xy 43.723654 -139.010002) (xy 43.769897 -139.109954) (xy 43.808807 -139.212982)
			(xy 43.840181 -139.31855) (xy 43.863856 -139.426106) (xy 43.879708 -139.53509) (xy 43.887655 -139.644934)
			(xy 43.888152 -139.7) (xy 60.396131 -139.7) (xy 60.400106 -139.589941) (xy 60.412014 -139.480455)
			(xy 60.43179 -139.372114) (xy 60.459333 -139.265483) (xy 60.494498 -139.161117) (xy 60.537102 -139.05956)
			(xy 60.586923 -138.961343) (xy 60.643702 -138.866976) (xy 60.707141 -138.776952) (xy 60.776912 -138.691741)
			(xy 60.852649 -138.611786) (xy 60.933958 -138.537505) (xy 61.020415 -138.469285) (xy 61.111569 -138.40748)
			(xy 61.206946 -138.352415) (xy 61.306047 -138.304375) (xy 61.408356 -138.263611) (xy 61.51334 -138.230336)
			(xy 61.620451 -138.204723) (xy 61.729131 -138.186906) (xy 61.838814 -138.176977) (xy 61.948927 -138.174989)
			(xy 62.058897 -138.180951) (xy 62.16815 -138.194833) (xy 62.276116 -138.216563) (xy 62.382233 -138.246026)
			(xy 62.485947 -138.283069) (xy 62.586718 -138.3275) (xy 62.68402 -138.379087) (xy 62.777346 -138.437559)
			(xy 62.866209 -138.502614) (xy 62.950147 -138.573912) (xy 63.028722 -138.65108) (xy 63.101523 -138.733717)
			(xy 63.168171 -138.821391) (xy 63.22832 -138.913647) (xy 63.281654 -139.010002) (xy 63.327897 -139.109954)
			(xy 63.366807 -139.212982) (xy 63.398181 -139.31855) (xy 63.421856 -139.426106) (xy 63.437708 -139.53509)
			(xy 63.445655 -139.644934) (xy 63.446152 -139.7) (xy 63.445655 -139.755066) (xy 63.437708 -139.86491)
			(xy 63.421856 -139.973894) (xy 63.398181 -140.08145) (xy 63.366807 -140.187018) (xy 63.327897 -140.290046)
			(xy 63.281654 -140.389998) (xy 63.22832 -140.486353) (xy 63.168171 -140.578609) (xy 63.101523 -140.666283)
			(xy 63.028722 -140.74892) (xy 62.950147 -140.826088) (xy 62.866209 -140.897386) (xy 62.777346 -140.962441)
			(xy 62.68402 -141.020913) (xy 62.586718 -141.0725) (xy 62.485947 -141.116931) (xy 62.382233 -141.153974)
			(xy 62.276116 -141.183437) (xy 62.16815 -141.205167) (xy 62.058897 -141.219049) (xy 61.948927 -141.225011)
			(xy 61.838814 -141.223023) (xy 61.729131 -141.213094) (xy 61.620451 -141.195277) (xy 61.51334 -141.169664)
			(xy 61.408356 -141.136389) (xy 61.306047 -141.095625) (xy 61.206946 -141.047585) (xy 61.111569 -140.99252)
			(xy 61.020415 -140.930715) (xy 60.933958 -140.862495) (xy 60.852649 -140.788214) (xy 60.776912 -140.708259)
			(xy 60.707141 -140.623048) (xy 60.643702 -140.533024) (xy 60.586923 -140.438657) (xy 60.537102 -140.34044)
			(xy 60.494498 -140.238883) (xy 60.459333 -140.134517) (xy 60.43179 -140.027886) (xy 60.412014 -139.919545)
			(xy 60.400106 -139.810059) (xy 60.396131 -139.7) (xy 43.888152 -139.7) (xy 43.887655 -139.755066)
			(xy 43.879708 -139.86491) (xy 43.863856 -139.973894) (xy 43.840181 -140.08145) (xy 43.808807 -140.187018)
			(xy 43.769897 -140.290046) (xy 43.723654 -140.389998) (xy 43.67032 -140.486353) (xy 43.610171 -140.578609)
			(xy 43.543523 -140.666283) (xy 43.470722 -140.74892) (xy 43.392147 -140.826088) (xy 43.308209 -140.897386)
			(xy 43.219346 -140.962441) (xy 43.12602 -141.020913) (xy 43.028718 -141.0725) (xy 42.927947 -141.116931)
			(xy 42.824233 -141.153974) (xy 42.718116 -141.183437) (xy 42.61015 -141.205167) (xy 42.500897 -141.219049)
			(xy 42.390927 -141.225011) (xy 42.280814 -141.223023) (xy 42.171131 -141.213094) (xy 42.062451 -141.195277)
			(xy 41.95534 -141.169664) (xy 41.850356 -141.136389) (xy 41.748047 -141.095625) (xy 41.648946 -141.047585)
			(xy 41.553569 -140.99252) (xy 41.462415 -140.930715) (xy 41.375958 -140.862495) (xy 41.294649 -140.788214)
			(xy 41.218912 -140.708259) (xy 41.149141 -140.623048) (xy 41.085702 -140.533024) (xy 41.028923 -140.438657)
			(xy 40.979102 -140.34044) (xy 40.936498 -140.238883) (xy 40.901333 -140.134517) (xy 40.87379 -140.027886)
			(xy 40.854014 -139.919545) (xy 40.842106 -139.810059) (xy 40.838131 -139.7) (xy 0.509016 -139.7)
			(xy 0.509016 -153.299922) (xy 0.509522 -153.395255) (xy 0.517614 -153.58575) (xy 0.533784 -153.77573)
			(xy 0.558002 -153.964852) (xy 0.590225 -154.152777) (xy 0.630395 -154.339164) (xy 0.678438 -154.523678)
			(xy 0.73427 -154.705987) (xy 0.797789 -154.885763) (xy 0.86888 -155.06268) (xy 0.947416 -155.236421)
			(xy 1.033255 -155.406672) (xy 1.126242 -155.573127) (xy 1.22621 -155.735485) (xy 1.332979 -155.893455)
			(xy 1.446356 -156.04675) (xy 1.566136 -156.195096) (xy 1.692105 -156.338224) (xy 1.824035 -156.475877)
			(xy 1.961688 -156.607806) (xy 2.104816 -156.733775) (xy 2.253162 -156.853556) (xy 2.406457 -156.966932)
			(xy 2.564426 -157.073701) (xy 2.726785 -157.173669) (xy 2.893239 -157.266656) (xy 3.063491 -157.352495)
			(xy 3.237232 -157.431031) (xy 3.414149 -157.502122) (xy 3.593924 -157.565641) (xy 3.776234 -157.621472)
			(xy 3.960748 -157.669516) (xy 4.147135 -157.709685) (xy 4.335059 -157.741908) (xy 4.524182 -157.766126)
			(xy 4.714162 -157.782296) (xy 4.904657 -157.790388) (xy 4.99999 -157.790896) (xy 25.999948 -157.790896)
			(xy 26.105482 -157.791395) (xy 26.316396 -157.79948) (xy 26.526845 -157.815637) (xy 26.73652 -157.839843)
			(xy 26.945115 -157.872062) (xy 27.152323 -157.912248) (xy 27.357839 -157.96034) (xy 27.561362 -158.016269)
			(xy 27.762594 -158.079953) (xy 27.961239 -158.151298) (xy 28.157005 -158.230198) (xy 28.349606 -158.31654)
			(xy 28.538758 -158.410195) (xy 28.724184 -158.511027) (xy 28.905612 -158.618886) (xy 29.082776 -158.733616)
			(xy 29.255415 -158.855048) (xy 29.423276 -158.983003) (xy 29.586113 -159.117293) (xy 29.743686 -159.257723)
			(xy 29.895766 -159.404084) (xy 30.042127 -159.556164) (xy 30.182557 -159.713737) (xy 30.316847 -159.876574)
			(xy 30.444802 -160.044435) (xy 30.566234 -160.217074) (xy 30.680964 -160.394238) (xy 30.788823 -160.575666)
			(xy 30.889655 -160.761092) (xy 30.98331 -160.950244) (xy 31.069652 -161.142845) (xy 31.148552 -161.338611)
			(xy 31.219897 -161.537256) (xy 31.283581 -161.738488) (xy 31.33951 -161.942011) (xy 31.387602 -162.147527)
			(xy 31.427788 -162.354735) (xy 31.460007 -162.56333) (xy 31.484213 -162.773005) (xy 31.50037 -162.983454)
			(xy 31.508455 -163.194368) (xy 31.508954 -163.299902) (xy 31.508954 -166.649908) (xy 31.50946 -166.745241)
			(xy 31.517552 -166.935736) (xy 31.533721 -167.125716) (xy 31.557939 -167.314839) (xy 31.590162 -167.502763)
			(xy 31.630332 -167.689151) (xy 31.678375 -167.873665) (xy 31.734207 -168.055975) (xy 31.797726 -168.23575)
			(xy 31.868817 -168.412668) (xy 31.947353 -168.586409) (xy 32.033192 -168.75666) (xy 32.074156 -168.82999)
			(xy 33.661096 -168.82999) (xy 33.661535 -168.782327) (xy 33.669022 -168.687296) (xy 33.683942 -168.593144)
			(xy 33.706203 -168.500454) (xy 33.735667 -168.409796) (xy 33.772152 -168.321729) (xy 33.815435 -168.236795)
			(xy 33.865248 -168.15552) (xy 33.921283 -168.078402) (xy 33.983196 -168.005919) (xy 34.050605 -167.938517)
			(xy 34.086546 -167.907208) (xy 34.094571 -167.899638) (xy 34.103786 -167.879619) (xy 34.104326 -167.8686)
			(xy 34.104326 -167.791384) (xy 34.103789 -167.780365) (xy 34.094568 -167.760349) (xy 34.086546 -167.752776)
			(xy 34.050612 -167.721463) (xy 33.983218 -167.654051) (xy 33.921318 -167.581561) (xy 33.865293 -167.504441)
			(xy 33.815489 -167.423164) (xy 33.772212 -167.338232) (xy 33.735729 -167.250168) (xy 33.706265 -167.159514)
			(xy 33.684 -167.066828) (xy 33.669073 -166.972682) (xy 33.661575 -166.877655) (xy 33.661096 -166.829994)
			(xy 33.661537 -166.782331) (xy 33.669025 -166.6873) (xy 33.683944 -166.593149) (xy 33.706205 -166.500458)
			(xy 33.735668 -166.4098) (xy 33.772154 -166.321733) (xy 33.815436 -166.2368) (xy 33.865249 -166.155524)
			(xy 33.921284 -166.078407) (xy 33.983197 -166.005923) (xy 34.050605 -165.938521) (xy 34.086546 -165.907212)
			(xy 34.094569 -165.89964) (xy 34.103786 -165.879623) (xy 34.104326 -165.868604) (xy 34.104326 -165.791388)
			(xy 34.103786 -165.78037) (xy 34.094567 -165.760354) (xy 34.086546 -165.75278) (xy 34.050614 -165.721464)
			(xy 33.98322 -165.654053) (xy 33.92132 -165.581563) (xy 33.865295 -165.504443) (xy 33.815491 -165.423167)
			(xy 33.772214 -165.338235) (xy 33.735731 -165.250171) (xy 33.706266 -165.159517) (xy 33.684001 -165.066832)
			(xy 33.669073 -164.972686) (xy 33.661575 -164.877659) (xy 33.661096 -164.829998) (xy 33.66154 -164.782335)
			(xy 33.669027 -164.687304) (xy 33.683947 -164.593153) (xy 33.706207 -164.500463) (xy 33.73567 -164.409804)
			(xy 33.772155 -164.321737) (xy 33.815437 -164.236804) (xy 33.865249 -164.155528) (xy 33.921284 -164.078411)
			(xy 33.983197 -164.005927) (xy 34.050606 -163.938525) (xy 34.086546 -163.907216) (xy 34.094567 -163.899643)
			(xy 34.103785 -163.879626) (xy 34.104326 -163.868608) (xy 34.104326 -163.791392) (xy 34.103784 -163.780374)
			(xy 34.094567 -163.760358) (xy 34.086546 -163.752784) (xy 34.050616 -163.721466) (xy 33.983221 -163.654055)
			(xy 33.921321 -163.581566) (xy 33.865297 -163.504446) (xy 33.815492 -163.42317) (xy 33.772215 -163.338238)
			(xy 33.735732 -163.250174) (xy 33.706267 -163.15952) (xy 33.684002 -163.066835) (xy 33.669074 -162.972689)
			(xy 33.661575 -162.877663) (xy 33.661096 -162.830002) (xy 33.661543 -162.782339) (xy 33.66903 -162.687308)
			(xy 33.683949 -162.593157) (xy 33.706209 -162.500467) (xy 33.735672 -162.409809) (xy 33.772157 -162.321741)
			(xy 33.815438 -162.236808) (xy 33.86525 -162.155532) (xy 33.921285 -162.078415) (xy 33.983197 -162.005932)
			(xy 34.050606 -161.938529) (xy 34.086546 -161.90722) (xy 34.094565 -161.899645) (xy 34.103784 -161.87963)
			(xy 34.104326 -161.868612) (xy 34.104326 -161.791396) (xy 34.103782 -161.780378) (xy 34.094566 -161.760362)
			(xy 34.086546 -161.752788) (xy 34.050618 -161.721468) (xy 33.983223 -161.654057) (xy 33.921323 -161.581568)
			(xy 33.865298 -161.504448) (xy 33.815494 -161.423172) (xy 33.772217 -161.338241) (xy 33.735733 -161.250177)
			(xy 33.706268 -161.159524) (xy 33.684002 -161.066839) (xy 33.669074 -160.972693) (xy 33.661575 -160.877667)
			(xy 33.661096 -160.830006) (xy 33.661546 -160.782343) (xy 33.669032 -160.687312) (xy 33.683951 -160.593161)
			(xy 33.70621 -160.500471) (xy 33.735673 -160.409813) (xy 33.772158 -160.321746) (xy 33.815439 -160.236812)
			(xy 33.865251 -160.155537) (xy 33.921286 -160.078419) (xy 33.983198 -160.005936) (xy 34.050606 -159.938533)
			(xy 34.086546 -159.907224) (xy 34.094563 -159.899647) (xy 34.103783 -159.879633) (xy 34.104326 -159.868616)
			(xy 34.104326 -159.7914) (xy 34.10378 -159.780382) (xy 34.094565 -159.760366) (xy 34.086546 -159.752792)
			(xy 34.05062 -159.72147) (xy 33.983225 -159.654059) (xy 33.921325 -159.58157) (xy 33.8653 -159.504451)
			(xy 33.815495 -159.423175) (xy 33.772218 -159.338244) (xy 33.735734 -159.250181) (xy 33.706269 -159.159527)
			(xy 33.684003 -159.066842) (xy 33.669075 -158.972697) (xy 33.661575 -158.877671) (xy 33.661096 -158.83001)
			(xy 33.661549 -158.782347) (xy 33.669035 -158.687316) (xy 33.683953 -158.593165) (xy 33.706212 -158.500475)
			(xy 33.735675 -158.409817) (xy 33.772159 -158.32175) (xy 33.815441 -158.236817) (xy 33.865252 -158.155541)
			(xy 33.921286 -158.078423) (xy 33.983198 -158.00594) (xy 34.050606 -157.938537) (xy 34.086546 -157.907228)
			(xy 34.094562 -157.89965) (xy 34.103782 -157.879637) (xy 34.104326 -157.86862) (xy 34.104326 -157.791404)
			(xy 34.103778 -157.780387) (xy 34.094565 -157.76037) (xy 34.086546 -157.752796) (xy 34.050621 -157.721472)
			(xy 33.983227 -157.654061) (xy 33.921327 -157.581573) (xy 33.865302 -157.504453) (xy 33.815497 -157.423178)
			(xy 33.772219 -157.338247) (xy 33.735735 -157.250184) (xy 33.70627 -157.159531) (xy 33.684004 -157.066846)
			(xy 33.669075 -156.972701) (xy 33.661575 -156.877675) (xy 33.661096 -156.830014) (xy 33.661552 -156.782351)
			(xy 33.669037 -156.68732) (xy 33.683956 -156.59317) (xy 33.706214 -156.50048) (xy 33.735677 -156.409821)
			(xy 33.772161 -156.321754) (xy 33.815442 -156.236821) (xy 33.865253 -156.155545) (xy 33.921287 -156.078428)
			(xy 33.983198 -156.005944) (xy 34.050606 -155.938541) (xy 34.086546 -155.907232) (xy 34.09456 -155.899652)
			(xy 34.103782 -155.879641) (xy 34.104326 -155.868624) (xy 34.104326 -155.791408) (xy 34.103776 -155.780391)
			(xy 34.094564 -155.760375) (xy 34.086546 -155.7528) (xy 34.050623 -155.721473) (xy 33.983229 -155.654063)
			(xy 33.921329 -155.581575) (xy 33.865303 -155.504456) (xy 33.815499 -155.423181) (xy 33.772221 -155.33825)
			(xy 33.735736 -155.250187) (xy 33.706271 -155.159534) (xy 33.684005 -155.06685) (xy 33.669076 -154.972705)
			(xy 33.661575 -154.877679) (xy 33.661096 -154.830018) (xy 33.661555 -154.782355) (xy 33.66904 -154.687325)
			(xy 33.683958 -154.593174) (xy 33.706216 -154.500484) (xy 33.735678 -154.409826) (xy 33.772162 -154.321759)
			(xy 33.815443 -154.236825) (xy 33.865254 -154.155549) (xy 33.921287 -154.078432) (xy 33.983199 -154.005948)
			(xy 34.050606 -153.938545) (xy 34.086546 -153.907236) (xy 34.094558 -153.899654) (xy 34.103781 -153.879644)
			(xy 34.104326 -153.868628) (xy 34.104326 -153.791412) (xy 34.103773 -153.780395) (xy 34.094564 -153.760379)
			(xy 34.086546 -153.752804) (xy 34.050625 -153.721475) (xy 33.983231 -153.654065) (xy 33.92133 -153.581577)
			(xy 33.865305 -153.504458) (xy 33.8155 -153.423183) (xy 33.772222 -153.338253) (xy 33.735738 -153.25019)
			(xy 33.706272 -153.159538) (xy 33.684005 -153.066853) (xy 33.669076 -152.972708) (xy 33.661576 -152.877683)
			(xy 33.661096 -152.830022) (xy 33.661673 -152.779839) (xy 33.66996 -152.679815) (xy 33.686478 -152.580818)
			(xy 33.711114 -152.483522) (xy 33.743701 -152.388593) (xy 33.784016 -152.29668) (xy 33.831783 -152.208409)
			(xy 33.886676 -152.124385) (xy 33.94832 -152.04518) (xy 34.016294 -151.971337) (xy 34.090135 -151.903359)
			(xy 34.169336 -151.841711) (xy 34.253358 -151.786813) (xy 34.341626 -151.739042) (xy 34.433537 -151.698723)
			(xy 34.528465 -151.666131) (xy 34.625759 -151.64149) (xy 34.724756 -151.624967) (xy 34.824779 -151.616676)
			(xy 34.874962 -151.616156) (xy 34.922624 -151.616643) (xy 35.017654 -151.624127) (xy 35.111803 -151.639042)
			(xy 35.204493 -151.661299) (xy 35.29515 -151.690758) (xy 35.383217 -151.727239) (xy 35.468151 -151.770517)
			(xy 35.549427 -151.820325) (xy 35.626545 -151.876355) (xy 35.69903 -151.938264) (xy 35.766434 -152.005668)
			(xy 35.797744 -152.041606) (xy 35.80534 -152.049603) (xy 35.825339 -152.058836) (xy 35.836352 -152.059386)
			(xy 35.913568 -152.059386) (xy 35.924585 -152.058835) (xy 35.944602 -152.049625) (xy 35.952176 -152.041606)
			(xy 35.983506 -152.005687) (xy 36.050917 -151.938293) (xy 36.123405 -151.876393) (xy 36.200524 -151.820369)
			(xy 36.281799 -151.770564) (xy 36.366729 -151.727286) (xy 36.454792 -151.690802) (xy 36.545444 -151.661335)
			(xy 36.638128 -151.639068) (xy 36.732272 -151.624138) (xy 36.827298 -151.616636) (xy 36.874958 -151.616156)
			(xy 36.925143 -151.616679) (xy 37.02517 -151.624964) (xy 37.124172 -151.641481) (xy 37.221471 -151.666118)
			(xy 37.316403 -151.698706) (xy 37.40832 -151.739022) (xy 37.496594 -151.786792) (xy 37.580621 -151.841687)
			(xy 37.659828 -151.903335) (xy 37.733673 -151.971313) (xy 37.801652 -152.045157) (xy 37.863301 -152.124363)
			(xy 37.918198 -152.208389) (xy 37.965969 -152.296662) (xy 38.006287 -152.388578) (xy 38.038876 -152.48351)
			(xy 38.063514 -152.580809) (xy 38.080034 -152.67981) (xy 38.08832 -152.779837) (xy 38.088824 -152.830022)
			(xy 38.088387 -152.877685) (xy 38.080899 -152.972716) (xy 38.065978 -153.066867) (xy 38.043717 -153.159558)
			(xy 38.014253 -153.250216) (xy 37.977767 -153.338283) (xy 37.934484 -153.423216) (xy 37.884671 -153.504492)
			(xy 37.828636 -153.581609) (xy 37.766723 -153.654092) (xy 37.699315 -153.721495) (xy 37.663374 -153.752804)
			(xy 37.655347 -153.760372) (xy 37.646132 -153.780392) (xy 37.645594 -153.791412) (xy 37.645594 -153.868628)
			(xy 37.646118 -153.879648) (xy 37.655348 -153.899665) (xy 37.663374 -153.907236) (xy 37.699318 -153.938538)
			(xy 37.766712 -154.005952) (xy 37.828611 -154.078443) (xy 37.884634 -154.155565) (xy 37.934437 -154.236842)
			(xy 37.977713 -154.321776) (xy 38.014195 -154.409841) (xy 38.043659 -154.500496) (xy 38.065922 -154.593182)
			(xy 38.080849 -154.687329) (xy 38.088346 -154.782357) (xy 38.088824 -154.830018) (xy 38.088384 -154.877681)
			(xy 38.080896 -154.972712) (xy 38.065976 -155.066863) (xy 38.043715 -155.159553) (xy 38.014251 -155.250211)
			(xy 37.977765 -155.338278) (xy 37.934483 -155.423212) (xy 37.884671 -155.504487) (xy 37.828635 -155.581605)
			(xy 37.766723 -155.654088) (xy 37.699314 -155.721491) (xy 37.663374 -155.7528) (xy 37.655349 -155.76037)
			(xy 37.646132 -155.780389) (xy 37.645594 -155.791408) (xy 37.645594 -155.868624) (xy 37.64612 -155.879644)
			(xy 37.655348 -155.89966) (xy 37.663374 -155.907232) (xy 37.699316 -155.938536) (xy 37.76671 -156.00595)
			(xy 37.828609 -156.07844) (xy 37.884632 -156.155562) (xy 37.934436 -156.23684) (xy 37.977712 -156.321773)
			(xy 38.014194 -156.409838) (xy 38.043658 -156.500492) (xy 38.065921 -156.593179) (xy 38.080848 -156.687325)
			(xy 38.088346 -156.782353) (xy 38.088824 -156.830014) (xy 38.088381 -156.877677) (xy 38.080894 -156.972708)
			(xy 38.065974 -157.066859) (xy 38.043713 -157.159549) (xy 38.014249 -157.250207) (xy 37.977764 -157.338274)
			(xy 37.934482 -157.423207) (xy 37.88467 -157.504483) (xy 37.828635 -157.581601) (xy 37.766722 -157.654084)
			(xy 37.699314 -157.721487) (xy 37.663374 -157.752796) (xy 37.65535 -157.760367) (xy 37.646133 -157.780385)
			(xy 37.645594 -157.791404) (xy 37.645594 -157.86862) (xy 37.646123 -157.87964) (xy 37.655349 -157.899656)
			(xy 37.663374 -157.907228) (xy 37.699314 -157.938534) (xy 37.766708 -158.005947) (xy 37.828607 -158.078438)
			(xy 37.884631 -158.155559) (xy 37.934434 -158.236837) (xy 37.97771 -158.32177) (xy 38.014193 -158.409834)
			(xy 38.043657 -158.500489) (xy 38.065921 -158.593175) (xy 38.080848 -158.687322) (xy 38.088346 -158.782349)
			(xy 38.088824 -158.830006) (xy 47.585872 -158.830006) (xy 47.589977 -158.730238) (xy 47.602263 -158.631145)
			(xy 47.62265 -158.533395) (xy 47.650997 -158.437651) (xy 47.687114 -158.344559) (xy 47.730757 -158.254749)
			(xy 47.781631 -158.168828) (xy 47.839391 -158.087377) (xy 47.903647 -158.010946) (xy 47.973966 -157.940053)
			(xy 48.011588 -157.907228) (xy 48.019595 -157.899641) (xy 48.028823 -157.879635) (xy 48.029368 -157.86862)
			(xy 48.029368 -157.791404) (xy 48.028838 -157.780384) (xy 48.019614 -157.760367) (xy 48.011588 -157.752796)
			(xy 47.975656 -157.721488) (xy 47.908285 -157.654066) (xy 47.846409 -157.581568) (xy 47.790409 -157.504442)
			(xy 47.74063 -157.423161) (xy 47.697378 -157.338227) (xy 47.660919 -157.250163) (xy 47.631479 -157.159511)
			(xy 47.609239 -157.06683) (xy 47.594335 -156.972689) (xy 47.586859 -156.87767) (xy 47.586392 -156.830014)
			(xy 47.586965 -156.779838) (xy 47.59525 -156.679827) (xy 47.611764 -156.580842) (xy 47.636395 -156.483559)
			(xy 47.668973 -156.388642) (xy 47.709278 -156.296738) (xy 47.757033 -156.208477) (xy 47.811913 -156.124459)
			(xy 47.873542 -156.04526) (xy 47.9415 -155.97142) (xy 48.015323 -155.903443) (xy 48.094507 -155.841793)
			(xy 48.17851 -155.786892) (xy 48.26676 -155.739114) (xy 48.358653 -155.698786) (xy 48.453562 -155.666183)
			(xy 48.550839 -155.641528) (xy 48.64982 -155.624989) (xy 48.749828 -155.616678) (xy 48.800004 -155.616148)
			(xy 48.847666 -155.616608) (xy 48.942697 -155.624094) (xy 49.036847 -155.639013) (xy 49.129537 -155.661272)
			(xy 49.220195 -155.690735) (xy 49.308261 -155.727219) (xy 49.393195 -155.770499) (xy 49.474471 -155.820309)
			(xy 49.551588 -155.876342) (xy 49.624073 -155.938253) (xy 49.691476 -156.005659) (xy 49.722786 -156.041598)
			(xy 49.730366 -156.049613) (xy 49.750377 -156.058836) (xy 49.761394 -156.059378) (xy 49.83861 -156.059378)
			(xy 49.849631 -156.058852) (xy 49.869647 -156.049625) (xy 49.877218 -156.041598) (xy 49.908523 -156.005656)
			(xy 49.975937 -155.938264) (xy 50.048428 -155.876365) (xy 50.12555 -155.820342) (xy 50.206827 -155.770539)
			(xy 50.29176 -155.727263) (xy 50.379825 -155.690781) (xy 50.470479 -155.661317) (xy 50.563165 -155.639053)
			(xy 50.657312 -155.624125) (xy 50.752339 -155.616627) (xy 50.8 -155.616148) (xy 50.850166 -155.616706)
			(xy 50.950156 -155.62499) (xy 51.04912 -155.641502) (xy 51.146384 -155.666128) (xy 51.241281 -155.698701)
			(xy 51.333166 -155.738998) (xy 51.421409 -155.786744) (xy 51.505409 -155.841614) (xy 51.584592 -155.903231)
			(xy 51.658416 -155.971176) (xy 51.726379 -156.044984) (xy 51.788016 -156.124152) (xy 51.842905 -156.208138)
			(xy 51.890673 -156.29637) (xy 51.930992 -156.388245) (xy 51.963588 -156.483134) (xy 51.988238 -156.580392)
			(xy 52.004774 -156.679352) (xy 52.013082 -156.77934) (xy 52.013612 -156.829506) (xy 52.013612 -156.830014)
			(xy 52.013125 -156.87767) (xy 52.005656 -156.972689) (xy 51.990757 -157.06683) (xy 51.968521 -157.159512)
			(xy 51.939083 -157.250164) (xy 51.902626 -157.338228) (xy 51.859375 -157.423162) (xy 51.809594 -157.504441)
			(xy 51.753592 -157.581566) (xy 51.691714 -157.65406) (xy 51.62434 -157.721478) (xy 51.588416 -157.752796)
			(xy 51.580399 -157.760374) (xy 51.571177 -157.780386) (xy 51.570636 -157.791404) (xy 51.570636 -157.86862)
			(xy 51.571152 -157.879642) (xy 51.580386 -157.899659) (xy 51.588416 -157.907228) (xy 51.626049 -157.940041)
			(xy 51.696367 -158.010936) (xy 51.760624 -158.087368) (xy 51.818385 -158.16882) (xy 51.869259 -158.254742)
			(xy 51.912903 -158.344553) (xy 51.94902 -158.437646) (xy 51.977368 -158.533392) (xy 51.997754 -158.631142)
			(xy 52.010041 -158.730237) (xy 52.014146 -158.830007) (xy 52.01004 -158.929776) (xy 51.997752 -159.028871)
			(xy 51.977365 -159.126621) (xy 51.949016 -159.222366) (xy 51.912897 -159.315459) (xy 51.869253 -159.405269)
			(xy 51.818378 -159.491191) (xy 51.760616 -159.572642) (xy 51.696359 -159.649074) (xy 51.626039 -159.719967)
			(xy 51.588416 -159.752792) (xy 51.580401 -159.760372) (xy 51.571178 -159.780383) (xy 51.570636 -159.7914)
			(xy 51.570636 -159.868616) (xy 51.571154 -159.879638) (xy 51.580386 -159.899655) (xy 51.588416 -159.907224)
			(xy 51.624359 -159.93852) (xy 51.691729 -160.005944) (xy 51.753604 -160.078442) (xy 51.809604 -160.15557)
			(xy 51.859382 -160.236852) (xy 51.902633 -160.321787) (xy 51.939091 -160.409853) (xy 51.96853 -160.500506)
			(xy 51.990769 -160.593188) (xy 52.005671 -160.687329) (xy 52.013145 -160.782349) (xy 52.013612 -160.830006)
			(xy 52.013509 -160.852379) (xy 52.011856 -160.897094) (xy 52.01031 -160.919414) (xy 52.01031 -160.919668)
			(xy 52.010063 -160.928551) (xy 52.014939 -160.945628) (xy 52.025303 -160.960049) (xy 52.032408 -160.965388)
			(xy 52.10556 -161.014664) (xy 52.113141 -161.019381) (xy 52.130424 -161.023806) (xy 52.148176 -161.022038)
			(xy 52.15636 -161.018474) (xy 52.156614 -161.01822) (xy 52.206696 -160.994237) (xy 52.309828 -160.953049)
			(xy 52.415788 -160.919811) (xy 52.523967 -160.894713) (xy 52.633739 -160.877899) (xy 52.74447 -160.869468)
			(xy 52.855522 -160.869468) (xy 52.966253 -160.877899) (xy 53.076025 -160.894713) (xy 53.184204 -160.919811)
			(xy 53.290164 -160.953049) (xy 53.393296 -160.994237) (xy 53.443378 -161.01822) (xy 53.443632 -161.018474)
			(xy 53.451831 -161.022014) (xy 53.469582 -161.023818) (xy 53.486874 -161.019416) (xy 53.494432 -161.014664)
			(xy 53.567584 -160.965388) (xy 53.574788 -160.960147) (xy 53.585215 -160.945714) (xy 53.590029 -160.928571)
			(xy 53.589682 -160.919668) (xy 53.589682 -160.919414) (xy 53.588137 -160.897094) (xy 53.586483 -160.852379)
			(xy 53.58638 -160.830006) (xy 53.58685 -160.782349) (xy 53.594318 -160.687329) (xy 53.609216 -160.593187)
			(xy 53.631453 -160.500504) (xy 53.660891 -160.409851) (xy 53.69735 -160.321786) (xy 53.740604 -160.236853)
			(xy 53.790387 -160.155574) (xy 53.846391 -160.07845) (xy 53.908273 -160.005957) (xy 53.975651 -159.938541)
			(xy 54.011576 -159.907224) (xy 54.019598 -159.899652) (xy 54.028814 -159.879634) (xy 54.029356 -159.868616)
			(xy 54.029356 -159.7914) (xy 54.028832 -159.780379) (xy 54.019604 -159.760362) (xy 54.011576 -159.752792)
			(xy 53.973961 -159.719958) (xy 53.903637 -159.649067) (xy 53.839375 -159.572639) (xy 53.78161 -159.491189)
			(xy 53.730732 -159.405269) (xy 53.687085 -159.315459) (xy 53.650964 -159.222367) (xy 53.622613 -159.126622)
			(xy 53.602224 -159.028872) (xy 53.589935 -158.929776) (xy 53.585829 -158.830006) (xy 53.589934 -158.730237)
			(xy 53.602222 -158.631141) (xy 53.62261 -158.533391) (xy 53.650959 -158.437645) (xy 53.68708 -158.344553)
			(xy 53.730726 -158.254743) (xy 53.781603 -158.168822) (xy 53.839368 -158.087371) (xy 53.903628 -158.010942)
			(xy 53.973951 -157.940051) (xy 54.011576 -157.907228) (xy 54.019596 -157.899654) (xy 54.028813 -157.879638)
			(xy 54.029356 -157.86862) (xy 54.029356 -157.791404) (xy 54.02883 -157.780383) (xy 54.019604 -157.760366)
			(xy 54.011576 -157.752796) (xy 53.975641 -157.721491) (xy 53.908271 -157.654068) (xy 53.846396 -157.58157)
			(xy 53.790396 -157.504443) (xy 53.740617 -157.423162) (xy 53.697365 -157.338228) (xy 53.660907 -157.250164)
			(xy 53.631467 -157.159512) (xy 53.609227 -157.06683) (xy 53.594323 -156.97269) (xy 53.586847 -156.87767)
			(xy 53.58638 -156.830014) (xy 53.586866 -156.779835) (xy 53.595151 -156.67982) (xy 53.611667 -156.580831)
			(xy 53.636299 -156.483544) (xy 53.668881 -156.388622) (xy 53.709189 -156.296715) (xy 53.756949 -156.208451)
			(xy 53.811833 -156.124431) (xy 53.873468 -156.04523) (xy 53.941431 -155.971389) (xy 54.01526 -155.903411)
			(xy 54.09445 -155.841762) (xy 54.17846 -155.786862) (xy 54.266716 -155.739087) (xy 54.358615 -155.698762)
			(xy 54.453531 -155.666163) (xy 54.550814 -155.641512) (xy 54.6498 -155.624979) (xy 54.749813 -155.616675)
			(xy 54.799992 -155.616148) (xy 54.847654 -155.616616) (xy 54.942685 -155.624102) (xy 55.036835 -155.63902)
			(xy 55.129524 -155.661278) (xy 55.220182 -155.69074) (xy 55.308249 -155.727223) (xy 55.393182 -155.770502)
			(xy 55.474458 -155.820312) (xy 55.551576 -155.876344) (xy 55.62406 -155.938254) (xy 55.691464 -156.005659)
			(xy 55.722774 -156.041598) (xy 55.730359 -156.049607) (xy 55.750366 -156.058833) (xy 55.761382 -156.059378)
			(xy 55.838598 -156.059378) (xy 55.849618 -156.058846) (xy 55.869635 -156.049623) (xy 55.877206 -156.041598)
			(xy 55.908518 -156.005662) (xy 55.975931 -155.93827) (xy 56.048421 -155.876371) (xy 56.125542 -155.820347)
			(xy 56.206819 -155.770544) (xy 56.291751 -155.727267) (xy 56.379815 -155.690784) (xy 56.470469 -155.66132)
			(xy 56.563154 -155.639055) (xy 56.6573 -155.624127) (xy 56.752327 -155.616627) (xy 56.799988 -155.616148)
			(xy 56.850154 -155.616717) (xy 56.950144 -155.625) (xy 57.049108 -155.641511) (xy 57.146371 -155.666137)
			(xy 57.241269 -155.698709) (xy 57.333153 -155.739005) (xy 57.421396 -155.786751) (xy 57.505396 -155.841619)
			(xy 57.584579 -155.903236) (xy 57.658404 -155.97118) (xy 57.726366 -156.044988) (xy 57.788003 -156.124155)
			(xy 57.842893 -156.208141) (xy 57.89066 -156.296372) (xy 57.93098 -156.388246) (xy 57.963576 -156.483136)
			(xy 57.988226 -156.580393) (xy 58.004762 -156.679353) (xy 58.01307 -156.77934) (xy 58.0136 -156.829506)
			(xy 58.0136 -156.830014) (xy 58.013117 -156.87767) (xy 58.005648 -156.97269) (xy 57.990749 -157.06683)
			(xy 57.968513 -157.159512) (xy 57.939075 -157.250165) (xy 57.902617 -157.338229) (xy 57.859365 -157.423163)
			(xy 57.809584 -157.504442) (xy 57.753582 -157.581567) (xy 57.691703 -157.654061) (xy 57.624328 -157.721478)
			(xy 57.588404 -157.752796) (xy 57.580385 -157.760372) (xy 57.571164 -157.780386) (xy 57.570624 -157.791404)
			(xy 57.570624 -157.86862) (xy 57.571143 -157.879641) (xy 57.580375 -157.899658) (xy 57.588404 -157.907228)
			(xy 57.626037 -157.940041) (xy 57.696356 -158.010935) (xy 57.760614 -158.087367) (xy 57.818375 -158.168819)
			(xy 57.86925 -158.254741) (xy 57.912894 -158.344552) (xy 57.949012 -158.437645) (xy 57.97736 -158.533391)
			(xy 57.997746 -158.631142) (xy 58.010033 -158.730237) (xy 58.014138 -158.830006) (xy 61.785988 -158.830006)
			(xy 61.790092 -158.730238) (xy 61.802379 -158.631144) (xy 61.822766 -158.533394) (xy 61.851114 -158.437649)
			(xy 61.887232 -158.344557) (xy 61.930876 -158.254747) (xy 61.981751 -158.168826) (xy 62.039512 -158.087375)
			(xy 62.10377 -158.010945) (xy 62.174089 -157.940052) (xy 62.211712 -157.907228) (xy 62.219722 -157.899645)
			(xy 62.228947 -157.879636) (xy 62.229492 -157.86862) (xy 62.229492 -157.791404) (xy 62.228954 -157.780385)
			(xy 62.219735 -157.760368) (xy 62.211712 -157.752796) (xy 62.175785 -157.721482) (xy 62.108414 -157.654061)
			(xy 62.046537 -157.581565) (xy 61.990536 -157.504439) (xy 61.940756 -157.423159) (xy 61.897503 -157.338226)
			(xy 61.861045 -157.250162) (xy 61.831604 -157.15951) (xy 61.809363 -157.066829) (xy 61.794459 -156.972689)
			(xy 61.786983 -156.87767) (xy 61.786516 -156.830014) (xy 61.787065 -156.779837) (xy 61.79535 -156.679825)
			(xy 61.811865 -156.580839) (xy 61.836496 -156.483555) (xy 61.869075 -156.388636) (xy 61.909381 -156.296732)
			(xy 61.957137 -156.20847) (xy 62.012018 -156.124451) (xy 62.073649 -156.045252) (xy 62.141609 -155.971411)
			(xy 62.215433 -155.903434) (xy 62.294619 -155.841785) (xy 62.378624 -155.786884) (xy 62.466875 -155.739107)
			(xy 62.55877 -155.698779) (xy 62.653681 -155.666178) (xy 62.750959 -155.641524) (xy 62.849941 -155.624986)
			(xy 62.949951 -155.616677) (xy 63.000128 -155.616148) (xy 63.047791 -155.61659) (xy 63.142822 -155.624079)
			(xy 63.236972 -155.639) (xy 63.329662 -155.661261) (xy 63.42032 -155.690725) (xy 63.508387 -155.72721)
			(xy 63.59332 -155.770492) (xy 63.674596 -155.820304) (xy 63.751713 -155.876339) (xy 63.824197 -155.938251)
			(xy 63.891601 -156.005658) (xy 63.92291 -156.041598) (xy 63.93048 -156.049623) (xy 63.950499 -156.058841)
			(xy 63.961518 -156.059378) (xy 64.038734 -156.059378) (xy 64.049756 -156.058866) (xy 64.069773 -156.049629)
			(xy 64.077342 -156.041598) (xy 64.108634 -156.005645) (xy 64.176049 -155.938253) (xy 64.248542 -155.876355)
			(xy 64.325665 -155.820332) (xy 64.406944 -155.77053) (xy 64.491878 -155.727255) (xy 64.579944 -155.690774)
			(xy 64.6706 -155.661311) (xy 64.763287 -155.639048) (xy 64.857434 -155.624123) (xy 64.952462 -155.616626)
			(xy 65.000124 -155.616148) (xy 65.050291 -155.616683) (xy 65.150281 -155.624969) (xy 65.249246 -155.641482)
			(xy 65.346509 -155.666111) (xy 65.441407 -155.698685) (xy 65.533292 -155.738984) (xy 65.621535 -155.786732)
			(xy 65.705535 -155.841602) (xy 65.784717 -155.903221) (xy 65.858542 -155.971167) (xy 65.926504 -156.044977)
			(xy 65.988141 -156.124145) (xy 66.04303 -156.208133) (xy 66.090797 -156.296366) (xy 66.131116 -156.388241)
			(xy 66.163712 -156.483132) (xy 66.188362 -156.58039) (xy 66.204898 -156.679351) (xy 66.213206 -156.77934)
			(xy 66.213736 -156.829506) (xy 66.213736 -156.830014) (xy 66.213275 -156.877671) (xy 66.205806 -156.972691)
			(xy 66.190906 -157.066833) (xy 66.168668 -157.159516) (xy 66.139228 -157.250169) (xy 66.102769 -157.338234)
			(xy 66.059514 -157.423167) (xy 66.009731 -157.504446) (xy 65.953726 -157.58157) (xy 65.891843 -157.654063)
			(xy 65.824465 -157.721479) (xy 65.78854 -157.752796) (xy 65.780512 -157.760363) (xy 65.771299 -157.780384)
			(xy 65.77076 -157.791404) (xy 65.77076 -157.86862) (xy 65.771299 -157.879638) (xy 65.780519 -157.899654)
			(xy 65.78854 -157.907228) (xy 65.826175 -157.94004) (xy 65.896498 -158.010933) (xy 65.960758 -158.087363)
			(xy 66.018523 -158.168815) (xy 66.0694 -158.254736) (xy 66.113046 -158.344548) (xy 66.149166 -158.437641)
			(xy 66.177516 -158.533388) (xy 66.197904 -158.631139) (xy 66.210191 -158.730236) (xy 66.214296 -158.830006)
			(xy 67.78598 -158.830006) (xy 67.790084 -158.730238) (xy 67.802371 -158.631144) (xy 67.822758 -158.533394)
			(xy 67.851106 -158.43765) (xy 67.887223 -158.344558) (xy 67.930867 -158.254748) (xy 67.981741 -158.168827)
			(xy 68.039502 -158.087376) (xy 68.103758 -158.010946) (xy 68.174077 -157.940052) (xy 68.2117 -157.907228)
			(xy 68.219709 -157.899643) (xy 68.228935 -157.879636) (xy 68.22948 -157.86862) (xy 68.22948 -157.791404)
			(xy 68.228946 -157.780384) (xy 68.219725 -157.760368) (xy 68.2117 -157.752796) (xy 68.17577 -157.721485)
			(xy 68.108399 -157.654063) (xy 68.046523 -157.581566) (xy 67.990523 -157.50444) (xy 67.940743 -157.42316)
			(xy 67.897491 -157.338227) (xy 67.861032 -157.250163) (xy 67.831592 -157.159511) (xy 67.809351 -157.066829)
			(xy 67.794447 -156.972689) (xy 67.786971 -156.87767) (xy 67.786504 -156.830014) (xy 67.787065 -156.779837)
			(xy 67.79535 -156.679826) (xy 67.811864 -156.580841) (xy 67.836495 -156.483557) (xy 67.869074 -156.388639)
			(xy 67.90938 -156.296735) (xy 67.957135 -156.208473) (xy 68.012016 -156.124455) (xy 68.073646 -156.045256)
			(xy 68.141605 -155.971415) (xy 68.215428 -155.903438) (xy 68.294613 -155.841789) (xy 68.378617 -155.786888)
			(xy 68.466867 -155.73911) (xy 68.558761 -155.698783) (xy 68.653671 -155.66618) (xy 68.750949 -155.641526)
			(xy 68.84993 -155.624987) (xy 68.949939 -155.616678) (xy 69.000116 -155.616148) (xy 69.047779 -155.616599)
			(xy 69.142809 -155.624087) (xy 69.23696 -155.639006) (xy 69.32965 -155.661267) (xy 69.420307 -155.69073)
			(xy 69.508374 -155.727214) (xy 69.593307 -155.770496) (xy 69.674583 -155.820307) (xy 69.751701 -155.87634)
			(xy 69.824185 -155.938252) (xy 69.891588 -156.005658) (xy 69.922898 -156.041598) (xy 69.930473 -156.049618)
			(xy 69.950488 -156.058838) (xy 69.961506 -156.059378) (xy 70.038722 -156.059378) (xy 70.049743 -156.058859)
			(xy 70.06976 -156.049627) (xy 70.07733 -156.041598) (xy 70.108628 -156.005651) (xy 70.176043 -155.938258)
			(xy 70.248535 -155.87636) (xy 70.325657 -155.820337) (xy 70.406936 -155.770534) (xy 70.491869 -155.727259)
			(xy 70.579934 -155.690777) (xy 70.67059 -155.661314) (xy 70.763276 -155.639051) (xy 70.857423 -155.624124)
			(xy 70.952451 -155.616626) (xy 71.000112 -155.616148) (xy 71.050278 -155.616694) (xy 71.150268 -155.624979)
			(xy 71.249233 -155.641492) (xy 71.346496 -155.666119) (xy 71.441394 -155.698693) (xy 71.533279 -155.738991)
			(xy 71.621522 -155.786738) (xy 71.705522 -155.841608) (xy 71.784704 -155.903226) (xy 71.858529 -155.971171)
			(xy 71.926492 -156.04498) (xy 71.988128 -156.124149) (xy 72.043017 -156.208136) (xy 72.090785 -156.296368)
			(xy 72.131104 -156.388243) (xy 72.1637 -156.483133) (xy 72.18835 -156.580391) (xy 72.204886 -156.679352)
			(xy 72.213194 -156.77934) (xy 72.213724 -156.829506) (xy 72.213724 -156.830014) (xy 72.213267 -156.877671)
			(xy 72.205798 -156.972692) (xy 72.190898 -157.066833) (xy 72.16866 -157.159517) (xy 72.13922 -157.25017)
			(xy 72.10276 -157.338235) (xy 72.059505 -157.423168) (xy 72.009721 -157.504447) (xy 71.953715 -157.581571)
			(xy 71.891832 -157.654064) (xy 71.824454 -157.721479) (xy 71.788528 -157.752796) (xy 71.780497 -157.760361)
			(xy 71.771286 -157.780384) (xy 71.770748 -157.791404) (xy 71.770748 -157.86862) (xy 71.77126 -157.879642)
			(xy 71.780496 -157.89966) (xy 71.788528 -157.907228) (xy 71.826961 -157.940728) (xy 71.898668 -158.013216)
			(xy 71.964043 -158.091463) (xy 72.022625 -158.174917) (xy 72.074 -158.26299) (xy 72.096376 -158.308802)
			(xy 72.100948 -158.318454) (xy 72.11695 -158.332424) (xy 72.199246 -158.357316) (xy 72.209509 -158.35998)
			(xy 72.230544 -158.357501) (xy 72.239886 -158.35249) (xy 72.285848 -158.325685) (xy 72.380951 -158.27795)
			(xy 72.479225 -158.237137) (xy 72.580165 -158.203457) (xy 72.683255 -158.17708) (xy 72.787967 -158.158142)
			(xy 72.893765 -158.146741) (xy 73.000108 -158.142934) (xy 73.106451 -158.146741) (xy 73.212249 -158.158142)
			(xy 73.316961 -158.17708) (xy 73.420051 -158.203457) (xy 73.520991 -158.237137) (xy 73.619265 -158.27795)
			(xy 73.714368 -158.325685) (xy 73.76033 -158.35249) (xy 73.769716 -158.357372) (xy 73.790702 -158.359866)
			(xy 73.80097 -158.357316) (xy 73.883266 -158.332424) (xy 73.899268 -158.318454) (xy 73.90384 -158.308802)
			(xy 73.92622 -158.262993) (xy 73.97759 -158.174915) (xy 74.036169 -158.09146) (xy 74.101545 -158.013214)
			(xy 74.173257 -157.940731) (xy 74.211688 -157.907228) (xy 74.219695 -157.899641) (xy 74.228923 -157.879635)
			(xy 74.229468 -157.86862) (xy 74.229468 -157.791404) (xy 74.228938 -157.780384) (xy 74.219714 -157.760367)
			(xy 74.211688 -157.752796) (xy 74.175756 -157.721488) (xy 74.108385 -157.654066) (xy 74.046509 -157.581568)
			(xy 73.990509 -157.504442) (xy 73.94073 -157.423161) (xy 73.897478 -157.338227) (xy 73.861019 -157.250163)
			(xy 73.831579 -157.159511) (xy 73.809339 -157.06683) (xy 73.794435 -156.972689) (xy 73.786959 -156.87767)
			(xy 73.786492 -156.830014) (xy 73.787065 -156.779838) (xy 73.79535 -156.679827) (xy 73.811864 -156.580842)
			(xy 73.836495 -156.483559) (xy 73.869073 -156.388642) (xy 73.909378 -156.296738) (xy 73.957133 -156.208477)
			(xy 74.012013 -156.124459) (xy 74.073642 -156.04526) (xy 74.1416 -155.97142) (xy 74.215423 -155.903443)
			(xy 74.294607 -155.841793) (xy 74.37861 -155.786892) (xy 74.46686 -155.739114) (xy 74.558753 -155.698786)
			(xy 74.653662 -155.666183) (xy 74.750939 -155.641528) (xy 74.84992 -155.624989) (xy 74.949928 -155.616678)
			(xy 75.000104 -155.616148) (xy 75.047766 -155.616608) (xy 75.142797 -155.624094) (xy 75.236947 -155.639013)
			(xy 75.329637 -155.661272) (xy 75.420295 -155.690735) (xy 75.508361 -155.727219) (xy 75.593295 -155.770499)
			(xy 75.674571 -155.820309) (xy 75.751688 -155.876342) (xy 75.824173 -155.938253) (xy 75.891576 -156.005659)
			(xy 75.922886 -156.041598) (xy 75.930466 -156.049613) (xy 75.950477 -156.058836) (xy 75.961494 -156.059378)
			(xy 76.03871 -156.059378) (xy 76.049731 -156.058852) (xy 76.069747 -156.049625) (xy 76.077318 -156.041598)
			(xy 76.108623 -156.005656) (xy 76.176037 -155.938264) (xy 76.248528 -155.876365) (xy 76.32565 -155.820342)
			(xy 76.406927 -155.770539) (xy 76.49186 -155.727263) (xy 76.579925 -155.690781) (xy 76.670579 -155.661317)
			(xy 76.763265 -155.639053) (xy 76.857412 -155.624125) (xy 76.952439 -155.616627) (xy 77.0001 -155.616148)
			(xy 77.050266 -155.616706) (xy 77.150256 -155.62499) (xy 77.24922 -155.641502) (xy 77.346484 -155.666128)
			(xy 77.441381 -155.698701) (xy 77.533266 -155.738998) (xy 77.621509 -155.786744) (xy 77.705509 -155.841614)
			(xy 77.784692 -155.903231) (xy 77.858516 -155.971176) (xy 77.926479 -156.044984) (xy 77.988116 -156.124152)
			(xy 78.043005 -156.208138) (xy 78.090773 -156.29637) (xy 78.131092 -156.388245) (xy 78.163688 -156.483134)
			(xy 78.188338 -156.580392) (xy 78.204874 -156.679352) (xy 78.213182 -156.77934) (xy 78.213712 -156.829506)
			(xy 78.213712 -156.830014) (xy 78.213225 -156.87767) (xy 78.205756 -156.972689) (xy 78.190857 -157.06683)
			(xy 78.168621 -157.159512) (xy 78.139183 -157.250164) (xy 78.102726 -157.338228) (xy 78.059475 -157.423162)
			(xy 78.009694 -157.504441) (xy 77.953692 -157.581566) (xy 77.891814 -157.65406) (xy 77.82444 -157.721478)
			(xy 77.788516 -157.752796) (xy 77.780499 -157.760374) (xy 77.771277 -157.780386) (xy 77.770736 -157.791404)
			(xy 77.770736 -157.86862) (xy 77.771252 -157.879642) (xy 77.780486 -157.899659) (xy 77.788516 -157.907228)
			(xy 77.826149 -157.940041) (xy 77.896467 -158.010936) (xy 77.960724 -158.087368) (xy 78.018485 -158.16882)
			(xy 78.069359 -158.254742) (xy 78.113003 -158.344553) (xy 78.14912 -158.437646) (xy 78.177468 -158.533392)
			(xy 78.197854 -158.631142) (xy 78.210141 -158.730237) (xy 78.214246 -158.830007) (xy 78.21014 -158.929776)
			(xy 78.197852 -159.028871) (xy 78.177465 -159.126621) (xy 78.149116 -159.222366) (xy 78.112997 -159.315459)
			(xy 78.069353 -159.405269) (xy 78.018478 -159.491191) (xy 77.960716 -159.572642) (xy 77.896459 -159.649074)
			(xy 77.826139 -159.719967) (xy 77.788516 -159.752792) (xy 77.780501 -159.760372) (xy 77.771278 -159.780383)
			(xy 77.770736 -159.7914) (xy 77.770736 -159.868616) (xy 77.771254 -159.879638) (xy 77.780486 -159.899655)
			(xy 77.788516 -159.907224) (xy 77.824459 -159.93852) (xy 77.891829 -160.005944) (xy 77.953704 -160.078442)
			(xy 78.009704 -160.15557) (xy 78.059482 -160.236852) (xy 78.102733 -160.321787) (xy 78.139191 -160.409853)
			(xy 78.16863 -160.500506) (xy 78.190869 -160.593188) (xy 78.205771 -160.687329) (xy 78.213245 -160.782349)
			(xy 78.213712 -160.830006) (xy 78.213154 -160.880183) (xy 78.204867 -160.980193) (xy 78.188352 -161.079178)
			(xy 78.16372 -161.176461) (xy 78.13114 -161.271379) (xy 78.090834 -161.363282) (xy 78.043078 -161.451544)
			(xy 77.988197 -161.535561) (xy 77.926567 -161.61476) (xy 77.858608 -161.6886) (xy 77.784785 -161.756577)
			(xy 77.7056 -161.818226) (xy 77.621596 -161.873127) (xy 77.533346 -161.920905) (xy 77.441453 -161.961233)
			(xy 77.346543 -161.993836) (xy 77.249266 -162.018492) (xy 77.150285 -162.035031) (xy 77.050276 -162.043342)
			(xy 77.0001 -162.043872) (xy 76.952438 -162.043402) (xy 76.857408 -162.035916) (xy 76.763258 -162.020998)
			(xy 76.670569 -161.998739) (xy 76.579911 -161.969278) (xy 76.491844 -161.932795) (xy 76.406911 -161.889516)
			(xy 76.325635 -161.839706) (xy 76.248517 -161.783675) (xy 76.176032 -161.721766) (xy 76.108628 -161.654361)
			(xy 76.077318 -161.618422) (xy 76.069749 -161.610397) (xy 76.049729 -161.601183) (xy 76.03871 -161.600642)
			(xy 75.961494 -161.600642) (xy 75.950473 -161.601163) (xy 75.930456 -161.610393) (xy 75.922886 -161.618422)
			(xy 75.891584 -161.654366) (xy 75.824169 -161.721758) (xy 75.751678 -161.783656) (xy 75.674555 -161.839679)
			(xy 75.593277 -161.889481) (xy 75.508344 -161.932757) (xy 75.420279 -161.969239) (xy 75.329625 -161.998703)
			(xy 75.236939 -162.020967) (xy 75.142792 -162.035894) (xy 75.047765 -162.043393) (xy 75.000104 -162.043872)
			(xy 74.950123 -162.043374) (xy 74.8505 -162.035138) (xy 74.751892 -162.018736) (xy 74.654967 -161.994281)
			(xy 74.560381 -161.961938) (xy 74.468775 -161.921925) (xy 74.380771 -161.874515) (xy 74.296963 -161.820029)
			(xy 74.21792 -161.758834) (xy 74.144177 -161.691347) (xy 74.076234 -161.618024) (xy 74.014551 -161.539362)
			(xy 73.959545 -161.455893) (xy 73.911591 -161.368184) (xy 73.871011 -161.276829) (xy 73.838082 -161.182445)
			(xy 73.813027 -161.085673) (xy 73.804018 -161.036508) (xy 73.801427 -161.024877) (xy 73.787397 -161.005661)
			(xy 73.777094 -160.999678) (xy 73.693528 -160.957514) (xy 73.669906 -160.95726) (xy 73.658984 -160.962594)
			(xy 73.611709 -160.985464) (xy 73.514509 -161.025256) (xy 73.414743 -161.058087) (xy 73.312908 -161.083794)
			(xy 73.209512 -161.102248) (xy 73.105072 -161.113358) (xy 73.000108 -161.117067) (xy 72.895144 -161.113358)
			(xy 72.790704 -161.102248) (xy 72.687308 -161.083794) (xy 72.585473 -161.058087) (xy 72.485707 -161.025256)
			(xy 72.388507 -160.985464) (xy 72.341232 -160.962594) (xy 72.330331 -160.957905) (xy 72.306624 -160.958056)
			(xy 72.295766 -160.962848) (xy 72.223122 -160.999678) (xy 72.212846 -161.005698) (xy 72.198797 -161.024888)
			(xy 72.196198 -161.036508) (xy 72.187209 -161.085679) (xy 72.162169 -161.18246) (xy 72.129253 -161.276853)
			(xy 72.088683 -161.368219) (xy 72.040735 -161.455937) (xy 71.985733 -161.539413) (xy 71.924051 -161.618083)
			(xy 71.856106 -161.691411) (xy 71.78236 -161.758901) (xy 71.703311 -161.820096) (xy 71.619496 -161.874581)
			(xy 71.531484 -161.921986) (xy 71.439869 -161.961991) (xy 71.345275 -161.994323) (xy 71.248341 -162.018765)
			(xy 71.149725 -162.035149) (xy 71.050096 -162.043365) (xy 71.000112 -162.043872) (xy 70.95245 -162.043394)
			(xy 70.85742 -162.035909) (xy 70.76327 -162.020991) (xy 70.670581 -161.998734) (xy 70.579924 -161.969273)
			(xy 70.491857 -161.932791) (xy 70.406924 -161.889512) (xy 70.325648 -161.839704) (xy 70.248529 -161.783673)
			(xy 70.176045 -161.721764) (xy 70.10864 -161.65436) (xy 70.07733 -161.618422) (xy 70.069756 -161.610402)
			(xy 70.04974 -161.601185) (xy 70.038722 -161.600642) (xy 69.961506 -161.600642) (xy 69.950486 -161.60117)
			(xy 69.930468 -161.610395) (xy 69.922898 -161.618422) (xy 69.891589 -161.65436) (xy 69.824175 -161.721752)
			(xy 69.751684 -161.78365) (xy 69.674563 -161.839674) (xy 69.593286 -161.889477) (xy 69.508353 -161.932753)
			(xy 69.420289 -161.969235) (xy 69.329635 -161.9987) (xy 69.23695 -162.020965) (xy 69.142804 -162.035893)
			(xy 69.047777 -162.043393) (xy 69.000116 -162.043872) (xy 68.949948 -162.043379) (xy 68.849954 -162.035095)
			(xy 68.750986 -162.018583) (xy 68.653719 -161.993956) (xy 68.558818 -161.961382) (xy 68.466931 -161.921082)
			(xy 68.378685 -161.873333) (xy 68.294683 -161.818461) (xy 68.215498 -161.756839) (xy 68.141672 -161.68889)
			(xy 68.073709 -161.615077) (xy 68.012073 -161.535905) (xy 67.957185 -161.451913) (xy 67.909419 -161.363676)
			(xy 67.869102 -161.271796) (xy 67.836509 -161.176901) (xy 67.811864 -161.079639) (xy 67.795333 -160.980674)
			(xy 67.787031 -160.880682) (xy 67.786504 -160.830514) (xy 67.786504 -160.830006) (xy 67.787 -160.78235)
			(xy 67.794468 -160.687331) (xy 67.809365 -160.593191) (xy 67.8316 -160.500509) (xy 67.861037 -160.409856)
			(xy 67.897493 -160.321792) (xy 67.940744 -160.236858) (xy 67.990524 -160.155579) (xy 68.046525 -160.078454)
			(xy 68.108403 -160.00596) (xy 68.175777 -159.938542) (xy 68.2117 -159.907224) (xy 68.21971 -159.89964)
			(xy 68.228936 -159.879632) (xy 68.22948 -159.868616) (xy 68.22948 -159.7914) (xy 68.228948 -159.78038)
			(xy 68.219725 -159.760363) (xy 68.2117 -159.752792) (xy 68.174087 -159.719957) (xy 68.103767 -159.649064)
			(xy 68.039509 -159.572634) (xy 67.981748 -159.491184) (xy 67.930873 -159.405263) (xy 67.887228 -159.315454)
			(xy 67.85111 -159.222362) (xy 67.822761 -159.126618) (xy 67.802374 -159.028869) (xy 67.790086 -158.929775)
			(xy 67.78598 -158.830006) (xy 66.214296 -158.830006) (xy 66.21019 -158.929777) (xy 66.197902 -159.028873)
			(xy 66.177513 -159.126625) (xy 66.149162 -159.222371) (xy 66.113041 -159.315464) (xy 66.069394 -159.405275)
			(xy 66.018516 -159.491196) (xy 65.96075 -159.572647) (xy 65.896489 -159.649077) (xy 65.826165 -159.719969)
			(xy 65.78854 -159.752792) (xy 65.780513 -159.76036) (xy 65.771299 -159.780381) (xy 65.77076 -159.7914)
			(xy 65.77076 -159.868616) (xy 65.771302 -159.879634) (xy 65.78052 -159.89965) (xy 65.78854 -159.907224)
			(xy 65.824488 -159.938515) (xy 65.891857 -160.005939) (xy 65.953732 -160.078439) (xy 66.009731 -160.155567)
			(xy 66.059509 -160.23685) (xy 66.102759 -160.321786) (xy 66.139216 -160.409851) (xy 66.168654 -160.500505)
			(xy 66.190893 -160.593188) (xy 66.205795 -160.687329) (xy 66.213269 -160.782349) (xy 66.213736 -160.830006)
			(xy 66.213254 -160.880185) (xy 66.204967 -160.980199) (xy 66.18845 -161.079188) (xy 66.163816 -161.176475)
			(xy 66.131233 -161.271396) (xy 66.090925 -161.363302) (xy 66.043165 -161.451566) (xy 65.98828 -161.535585)
			(xy 65.926645 -161.614786) (xy 65.858681 -161.688627) (xy 65.784852 -161.756604) (xy 65.705663 -161.818253)
			(xy 65.621653 -161.873153) (xy 65.533398 -161.920929) (xy 65.441499 -161.961254) (xy 65.346584 -161.993854)
			(xy 65.249301 -162.018505) (xy 65.150316 -162.03504) (xy 65.050303 -162.043345) (xy 65.000124 -162.043872)
			(xy 64.952462 -162.043385) (xy 64.857433 -162.035901) (xy 64.763283 -162.020984) (xy 64.670594 -161.998728)
			(xy 64.579937 -161.969268) (xy 64.49187 -161.932787) (xy 64.406937 -161.889509) (xy 64.32566 -161.839701)
			(xy 64.248542 -161.783671) (xy 64.176057 -161.721763) (xy 64.108652 -161.65436) (xy 64.077342 -161.618422)
			(xy 64.069763 -161.610408) (xy 64.049751 -161.601187) (xy 64.038734 -161.600642) (xy 63.961518 -161.600642)
			(xy 63.950498 -161.601177) (xy 63.930481 -161.610397) (xy 63.92291 -161.618422) (xy 63.891594 -161.654354)
			(xy 63.824181 -161.721746) (xy 63.751691 -161.783645) (xy 63.674571 -161.839668) (xy 63.593294 -161.889472)
			(xy 63.508362 -161.932748) (xy 63.420299 -161.969232) (xy 63.329645 -161.998697) (xy 63.23696 -162.020963)
			(xy 63.142815 -162.035892) (xy 63.047789 -162.043392) (xy 63.000128 -162.043872) (xy 62.94996 -162.043367)
			(xy 62.849967 -162.035085) (xy 62.750999 -162.018574) (xy 62.653732 -161.993947) (xy 62.558831 -161.961374)
			(xy 62.466944 -161.921075) (xy 62.378698 -161.873327) (xy 62.294695 -161.818455) (xy 62.215511 -161.756835)
			(xy 62.141685 -161.688886) (xy 62.073722 -161.615074) (xy 62.012086 -161.535902) (xy 61.957197 -161.45191)
			(xy 61.909431 -161.363674) (xy 61.869114 -161.271795) (xy 61.836522 -161.1769) (xy 61.811876 -161.079638)
			(xy 61.795345 -160.980673) (xy 61.787043 -160.880682) (xy 61.786516 -160.830514) (xy 61.786516 -160.830006)
			(xy 61.787008 -160.78235) (xy 61.794476 -160.687331) (xy 61.809373 -160.59319) (xy 61.831609 -160.500508)
			(xy 61.861045 -160.409855) (xy 61.897502 -160.321791) (xy 61.940753 -160.236858) (xy 61.990533 -160.155578)
			(xy 62.046535 -160.078454) (xy 62.108414 -160.005959) (xy 62.175788 -159.938542) (xy 62.211712 -159.907224)
			(xy 62.219724 -159.899642) (xy 62.228948 -159.879632) (xy 62.229492 -159.868616) (xy 62.229492 -159.7914)
			(xy 62.228956 -159.780381) (xy 62.219736 -159.760364) (xy 62.211712 -159.752792) (xy 62.174098 -159.719957)
			(xy 62.103778 -159.649065) (xy 62.03952 -159.572635) (xy 61.981758 -159.491185) (xy 61.930882 -159.405264)
			(xy 61.887237 -159.315455) (xy 61.851118 -159.222363) (xy 61.822769 -159.126619) (xy 61.802382 -159.028869)
			(xy 61.790093 -158.929775) (xy 61.785988 -158.830006) (xy 58.014138 -158.830006) (xy 58.014138 -158.830007)
			(xy 58.010032 -158.929776) (xy 57.997744 -159.028871) (xy 57.977357 -159.126622) (xy 57.949007 -159.222367)
			(xy 57.912888 -159.315459) (xy 57.869244 -159.40527) (xy 57.818368 -159.491192) (xy 57.760606 -159.572643)
			(xy 57.696348 -159.649074) (xy 57.626027 -159.719968) (xy 57.588404 -159.752792) (xy 57.580387 -159.76037)
			(xy 57.571165 -159.780382) (xy 57.570624 -159.7914) (xy 57.570624 -159.868616) (xy 57.571146 -159.879637)
			(xy 57.580376 -159.899654) (xy 57.588404 -159.907224) (xy 57.624344 -159.938523) (xy 57.691715 -160.005946)
			(xy 57.753591 -160.078444) (xy 57.80959 -160.155572) (xy 57.859369 -160.236853) (xy 57.902621 -160.321788)
			(xy 57.939078 -160.409853) (xy 57.968517 -160.500506) (xy 57.990757 -160.593189) (xy 58.005659 -160.68733)
			(xy 58.013133 -160.782349) (xy 58.0136 -160.830006) (xy 58.013054 -160.880183) (xy 58.004767 -160.980194)
			(xy 57.988252 -161.07918) (xy 57.963619 -161.176464) (xy 57.931039 -161.271382) (xy 57.890733 -161.363285)
			(xy 57.842976 -161.451547) (xy 57.788095 -161.535565) (xy 57.726464 -161.614764) (xy 57.658504 -161.688604)
			(xy 57.584679 -161.756581) (xy 57.505494 -161.818231) (xy 57.42149 -161.873131) (xy 57.333239 -161.920909)
			(xy 57.241344 -161.961236) (xy 57.146434 -161.993839) (xy 57.049156 -162.018494) (xy 56.950174 -162.035032)
			(xy 56.850165 -162.043342) (xy 56.799988 -162.043872) (xy 56.752326 -162.043411) (xy 56.657295 -162.035924)
			(xy 56.563145 -162.021005) (xy 56.470456 -161.998745) (xy 56.379798 -161.969283) (xy 56.291731 -161.932799)
			(xy 56.206798 -161.889519) (xy 56.125522 -161.839709) (xy 56.048404 -161.783676) (xy 55.97592 -161.721767)
			(xy 55.908516 -161.654361) (xy 55.877206 -161.618422) (xy 55.869641 -161.610391) (xy 55.849618 -161.60118)
			(xy 55.838598 -161.600642) (xy 55.761382 -161.600642) (xy 55.75036 -161.601157) (xy 55.730343 -161.610391)
			(xy 55.722774 -161.618422) (xy 55.691478 -161.654372) (xy 55.624063 -161.721763) (xy 55.551571 -161.783661)
			(xy 55.474448 -161.839684) (xy 55.393169 -161.889486) (xy 55.308235 -161.932761) (xy 55.22017 -161.969242)
			(xy 55.129515 -161.998706) (xy 55.036828 -162.020969) (xy 54.942681 -162.035896) (xy 54.847653 -162.043394)
			(xy 54.799992 -162.043872) (xy 54.745712 -162.043259) (xy 54.637587 -162.033538) (xy 54.530764 -162.014191)
			(xy 54.426097 -161.985373) (xy 54.37505 -161.96691) (xy 54.362096 -161.962084) (xy 54.33568 -161.966656)
			(xy 54.246526 -162.040316) (xy 54.237128 -162.06597) (xy 54.239414 -162.079432) (xy 54.248227 -162.132911)
			(xy 54.25886 -162.240785) (xy 54.26147 -162.34915) (xy 54.256041 -162.457411) (xy 54.242604 -162.564971)
			(xy 54.221232 -162.67124) (xy 54.192043 -162.775633) (xy 54.155197 -162.877575) (xy 54.110898 -162.976507)
			(xy 54.059389 -163.071883) (xy 54.000952 -163.163179) (xy 53.935911 -163.249894) (xy 53.864621 -163.331549)
			(xy 53.787476 -163.407697) (xy 53.7049 -163.477918) (xy 53.617346 -163.541825) (xy 53.525297 -163.599069)
			(xy 53.429259 -163.649333) (xy 53.329759 -163.692341) (xy 53.227346 -163.727856) (xy 53.122582 -163.755684)
			(xy 53.016044 -163.775672) (xy 52.908318 -163.787708) (xy 52.799996 -163.791727) (xy 52.691674 -163.787708)
			(xy 52.583948 -163.775672) (xy 52.47741 -163.755684) (xy 52.372646 -163.727856) (xy 52.270233 -163.692341)
			(xy 52.170733 -163.649333) (xy 52.074695 -163.599069) (xy 51.982646 -163.541825) (xy 51.895092 -163.477918)
			(xy 51.812516 -163.407697) (xy 51.735371 -163.331549) (xy 51.664081 -163.249894) (xy 51.59904 -163.163179)
			(xy 51.540603 -163.071883) (xy 51.489094 -162.976507) (xy 51.444795 -162.877575) (xy 51.407949 -162.775633)
			(xy 51.37876 -162.67124) (xy 51.357388 -162.564971) (xy 51.343951 -162.457411) (xy 51.338522 -162.34915)
			(xy 51.341132 -162.240785) (xy 51.351765 -162.132911) (xy 51.360578 -162.079432) (xy 51.362864 -162.06597)
			(xy 51.353466 -162.040316) (xy 51.264312 -161.966656) (xy 51.237896 -161.962084) (xy 51.224942 -161.96691)
			(xy 51.173891 -161.985361) (xy 51.069222 -162.01416) (xy 50.962401 -162.033507) (xy 50.854279 -162.043245)
			(xy 50.8 -162.043872) (xy 50.752338 -162.043402) (xy 50.657308 -162.035916) (xy 50.563158 -162.020998)
			(xy 50.470469 -161.998739) (xy 50.379811 -161.969278) (xy 50.291744 -161.932795) (xy 50.206811 -161.889516)
			(xy 50.125535 -161.839706) (xy 50.048417 -161.783675) (xy 49.975932 -161.721766) (xy 49.908528 -161.654361)
			(xy 49.877218 -161.618422) (xy 49.869649 -161.610397) (xy 49.849629 -161.601183) (xy 49.83861 -161.600642)
			(xy 49.761394 -161.600642) (xy 49.750373 -161.601163) (xy 49.730356 -161.610393) (xy 49.722786 -161.618422)
			(xy 49.691484 -161.654366) (xy 49.624069 -161.721758) (xy 49.551578 -161.783656) (xy 49.474455 -161.839679)
			(xy 49.393177 -161.889481) (xy 49.308244 -161.932757) (xy 49.220179 -161.969239) (xy 49.129525 -161.998703)
			(xy 49.036839 -162.020967) (xy 48.942692 -162.035894) (xy 48.847665 -162.043393) (xy 48.800004 -162.043872)
			(xy 48.749836 -162.04339) (xy 48.649842 -162.035106) (xy 48.550873 -162.018593) (xy 48.453607 -161.993965)
			(xy 48.358705 -161.961389) (xy 48.266818 -161.921089) (xy 48.178572 -161.873339) (xy 48.09457 -161.818466)
			(xy 48.015385 -161.756844) (xy 47.94156 -161.688895) (xy 47.873597 -161.615081) (xy 47.811961 -161.535908)
			(xy 47.757072 -161.451916) (xy 47.709307 -161.363678) (xy 47.66899 -161.271798) (xy 47.636397 -161.176903)
			(xy 47.611752 -161.07964) (xy 47.595221 -160.980675) (xy 47.586919 -160.880682) (xy 47.586392 -160.830514)
			(xy 47.586392 -160.830006) (xy 47.586892 -160.78235) (xy 47.59436 -160.687331) (xy 47.609257 -160.593191)
			(xy 47.631492 -160.500509) (xy 47.660928 -160.409857) (xy 47.697384 -160.321793) (xy 47.740635 -160.236859)
			(xy 47.790414 -160.15558) (xy 47.846414 -160.078455) (xy 47.908292 -160.00596) (xy 47.975665 -159.938542)
			(xy 48.011588 -159.907224) (xy 48.019597 -159.899639) (xy 48.028824 -159.879632) (xy 48.029368 -159.868616)
			(xy 48.029368 -159.7914) (xy 48.02884 -159.78038) (xy 48.019615 -159.760363) (xy 48.011588 -159.752792)
			(xy 47.973975 -159.719956) (xy 47.903656 -159.649064) (xy 47.839399 -159.572633) (xy 47.781638 -159.491183)
			(xy 47.730764 -159.405262) (xy 47.68712 -159.315453) (xy 47.651001 -159.222361) (xy 47.622653 -159.126618)
			(xy 47.602266 -159.028868) (xy 47.589978 -158.929775) (xy 47.585872 -158.830006) (xy 38.088824 -158.830006)
			(xy 38.088824 -158.83001) (xy 38.088378 -158.877673) (xy 38.080891 -158.972704) (xy 38.065971 -159.066855)
			(xy 38.043711 -159.159545) (xy 38.014248 -159.250203) (xy 37.977763 -159.33827) (xy 37.934481 -159.423203)
			(xy 37.884669 -159.504479) (xy 37.828634 -159.581596) (xy 37.766722 -159.65408) (xy 37.699314 -159.721483)
			(xy 37.663374 -159.752792) (xy 37.655352 -159.760365) (xy 37.646134 -159.780381) (xy 37.645594 -159.7914)
			(xy 37.645594 -159.868616) (xy 37.646125 -159.879636) (xy 37.655349 -159.899652) (xy 37.663374 -159.907224)
			(xy 37.699313 -159.938533) (xy 37.766706 -160.005945) (xy 37.828605 -160.078436) (xy 37.884629 -160.155557)
			(xy 37.934433 -160.236834) (xy 37.977709 -160.321767) (xy 38.014192 -160.409831) (xy 38.043656 -160.500486)
			(xy 38.06592 -160.593171) (xy 38.080847 -160.687318) (xy 38.088345 -160.782345) (xy 38.088824 -160.830006)
			(xy 38.088376 -160.877669) (xy 38.080889 -160.9727) (xy 38.065969 -161.066851) (xy 38.043709 -161.159541)
			(xy 38.014246 -161.250199) (xy 37.977761 -161.338266) (xy 37.93448 -161.423199) (xy 37.884668 -161.504475)
			(xy 37.828634 -161.581592) (xy 37.766722 -161.654076) (xy 37.699314 -161.721479) (xy 37.663374 -161.752788)
			(xy 37.655354 -161.760363) (xy 37.646135 -161.780378) (xy 37.645594 -161.791396) (xy 37.645594 -161.868612)
			(xy 37.646127 -161.879631) (xy 37.65535 -161.899648) (xy 37.663374 -161.90722) (xy 37.699311 -161.938531)
			(xy 37.766704 -162.005943) (xy 37.828603 -162.078433) (xy 37.884627 -162.155554) (xy 37.934431 -162.236831)
			(xy 37.977708 -162.321764) (xy 38.01419 -162.409828) (xy 38.043655 -162.500482) (xy 38.065919 -162.593168)
			(xy 38.080847 -162.687314) (xy 38.088345 -162.782341) (xy 38.088824 -162.830002) (xy 38.088373 -162.877665)
			(xy 38.080886 -162.972696) (xy 38.065967 -163.066846) (xy 38.043707 -163.159536) (xy 38.014244 -163.250194)
			(xy 37.97776 -163.338261) (xy 37.934478 -163.423195) (xy 37.884667 -163.504471) (xy 37.828633 -163.581588)
			(xy 37.766721 -163.654072) (xy 37.699314 -163.721475) (xy 37.663374 -163.752784) (xy 37.655356 -163.76036)
			(xy 37.646136 -163.780374) (xy 37.645594 -163.791392) (xy 37.645594 -163.868608) (xy 37.646129 -163.879627)
			(xy 37.655351 -163.899644) (xy 37.663374 -163.907216) (xy 37.699309 -163.938529) (xy 37.766702 -164.005941)
			(xy 37.828602 -164.078431) (xy 37.884626 -164.155552) (xy 37.93443 -164.236829) (xy 37.977706 -164.321761)
			(xy 38.014189 -164.409825) (xy 38.043654 -164.500479) (xy 38.065919 -164.593164) (xy 38.080846 -164.68731)
			(xy 38.088345 -164.782337) (xy 38.088824 -164.829998) (xy 38.08837 -164.877661) (xy 38.080883 -164.972691)
			(xy 38.065965 -165.066842) (xy 38.043705 -165.159532) (xy 38.014243 -165.25019) (xy 37.977758 -165.338257)
			(xy 37.934477 -165.42319) (xy 37.884666 -165.504466) (xy 37.828632 -165.581584) (xy 37.766721 -165.654068)
			(xy 37.699314 -165.721471) (xy 37.663374 -165.75278) (xy 37.655358 -165.760358) (xy 37.646136 -165.780371)
			(xy 37.645594 -165.791388) (xy 37.645594 -165.868604) (xy 37.646131 -165.879623) (xy 37.655351 -165.899639)
			(xy 37.663374 -165.907212) (xy 37.699307 -165.938527) (xy 37.7667 -166.005939) (xy 37.8286 -166.078429)
			(xy 37.884624 -166.155549) (xy 37.934428 -166.236826) (xy 37.977705 -166.321758) (xy 38.014188 -166.409822)
			(xy 38.043653 -166.500475) (xy 38.065918 -166.593161) (xy 38.080846 -166.687307) (xy 38.088345 -166.782333)
			(xy 38.088824 -166.829994) (xy 38.088367 -166.877657) (xy 38.080881 -166.972687) (xy 38.065962 -167.066838)
			(xy 38.043703 -167.159528) (xy 38.014241 -167.250186) (xy 37.977757 -167.338253) (xy 37.934476 -167.423186)
			(xy 37.884665 -167.504462) (xy 37.828632 -167.58158) (xy 37.766721 -167.654063) (xy 37.736366 -167.684417)
			(xy 65.5137 -167.684417) (xy 65.5137 -167.575771) (xy 65.521631 -167.467414) (xy 65.53745 -167.359925)
			(xy 65.561073 -167.253878) (xy 65.592374 -167.149838) (xy 65.631186 -167.04836) (xy 65.677301 -166.949986)
			(xy 65.730475 -166.855241) (xy 65.790423 -166.76463) (xy 65.856825 -166.678636) (xy 65.929327 -166.597719)
			(xy 66.007542 -166.522311) (xy 66.091053 -166.452812) (xy 66.179414 -166.389595) (xy 66.272154 -166.332997)
			(xy 66.368778 -166.283319) (xy 66.46877 -166.240827) (xy 66.571598 -166.205747) (xy 66.676712 -166.178267)
			(xy 66.783551 -166.158532) (xy 66.891546 -166.146649) (xy 67.00012 -166.142682) (xy 67.108694 -166.146649)
			(xy 67.216689 -166.158532) (xy 67.323528 -166.178267) (xy 67.428642 -166.205747) (xy 67.53147 -166.240827)
			(xy 67.631462 -166.283319) (xy 67.728086 -166.332997) (xy 67.820826 -166.389595) (xy 67.909187 -166.452812)
			(xy 67.992698 -166.522311) (xy 68.070913 -166.597719) (xy 68.143415 -166.678636) (xy 68.209817 -166.76463)
			(xy 68.269765 -166.855241) (xy 68.322939 -166.949986) (xy 68.369054 -167.04836) (xy 68.407866 -167.149838)
			(xy 68.439167 -167.253878) (xy 68.46279 -167.359925) (xy 68.478609 -167.467414) (xy 68.48654 -167.575771)
			(xy 68.487036 -167.630094) (xy 68.48654 -167.684417) (xy 68.478609 -167.792774) (xy 68.46279 -167.900263)
			(xy 68.439167 -168.00631) (xy 68.407866 -168.11035) (xy 68.369054 -168.211828) (xy 68.322939 -168.310202)
			(xy 68.269765 -168.404947) (xy 68.209817 -168.495558) (xy 68.143415 -168.581552) (xy 68.070913 -168.662469)
			(xy 67.992698 -168.737877) (xy 67.909187 -168.807376) (xy 67.820826 -168.870593) (xy 67.728086 -168.927191)
			(xy 67.631462 -168.976869) (xy 67.53147 -169.019361) (xy 67.428642 -169.054441) (xy 67.323528 -169.081921)
			(xy 67.216689 -169.101656) (xy 67.108694 -169.113539) (xy 67.00012 -169.117507) (xy 66.891546 -169.113539)
			(xy 66.783551 -169.101656) (xy 66.676712 -169.081921) (xy 66.571598 -169.054441) (xy 66.46877 -169.019361)
			(xy 66.368778 -168.976869) (xy 66.272154 -168.927191) (xy 66.179414 -168.870593) (xy 66.091053 -168.807376)
			(xy 66.007542 -168.737877) (xy 65.929327 -168.662469) (xy 65.856825 -168.581552) (xy 65.790423 -168.495558)
			(xy 65.730475 -168.404947) (xy 65.677301 -168.310202) (xy 65.631186 -168.211828) (xy 65.592374 -168.11035)
			(xy 65.561073 -168.00631) (xy 65.53745 -167.900263) (xy 65.521631 -167.792774) (xy 65.5137 -167.684417)
			(xy 37.736366 -167.684417) (xy 37.699314 -167.721467) (xy 37.663374 -167.752776) (xy 37.655359 -167.760356)
			(xy 37.646137 -167.780367) (xy 37.645594 -167.791384) (xy 37.645594 -167.8686) (xy 37.646134 -167.879619)
			(xy 37.655352 -167.899635) (xy 37.663374 -167.907208) (xy 37.699305 -167.938525) (xy 37.766698 -168.005937)
			(xy 37.828598 -168.078427) (xy 37.884622 -168.155547) (xy 37.934426 -168.236823) (xy 37.977703 -168.321755)
			(xy 38.014187 -168.409818) (xy 38.043652 -168.500472) (xy 38.065917 -168.593157) (xy 38.080845 -168.687303)
			(xy 38.088345 -168.782329) (xy 38.088824 -168.82999) (xy 38.088352 -168.880176) (xy 38.080064 -168.980205)
			(xy 38.063544 -169.079208) (xy 38.038904 -169.176509) (xy 38.006313 -169.271442) (xy 37.965994 -169.36336)
			(xy 37.918222 -169.451634) (xy 37.863323 -169.535662) (xy 37.801672 -169.614869) (xy 37.733691 -169.688714)
			(xy 37.659844 -169.756693) (xy 37.580636 -169.818341) (xy 37.496607 -169.873238) (xy 37.408331 -169.921008)
			(xy 37.316412 -169.961325) (xy 37.221478 -169.993913) (xy 37.124177 -170.01855) (xy 37.025173 -170.035068)
			(xy 36.925144 -170.043353) (xy 36.874958 -170.043856) (xy 36.827296 -170.04335) (xy 36.732267 -170.035868)
			(xy 36.638118 -170.020954) (xy 36.545429 -169.9987) (xy 36.454772 -169.969242) (xy 36.366705 -169.932763)
			(xy 36.281772 -169.889487) (xy 36.200495 -169.839681) (xy 36.123377 -169.783652) (xy 36.050891 -169.721746)
			(xy 35.983486 -169.654343) (xy 35.952176 -169.618406) (xy 35.944611 -169.610375) (xy 35.924589 -169.601161)
			(xy 35.913568 -169.600626) (xy 35.836352 -169.600626) (xy 35.825335 -169.601184) (xy 35.805318 -169.610389)
			(xy 35.797744 -169.618406) (xy 35.766406 -169.654318) (xy 35.698996 -169.721711) (xy 35.626508 -169.783611)
			(xy 35.54939 -169.839636) (xy 35.468116 -169.889441) (xy 35.383187 -169.93272) (xy 35.295125 -169.969205)
			(xy 35.204474 -169.998672) (xy 35.111791 -170.02094) (xy 35.017647 -170.035872) (xy 34.922622 -170.043375)
			(xy 34.874962 -170.043856) (xy 34.824777 -170.043384) (xy 34.724749 -170.035093) (xy 34.625748 -170.018569)
			(xy 34.52845 -169.993927) (xy 34.433518 -169.961334) (xy 34.341603 -169.921014) (xy 34.253331 -169.87324)
			(xy 34.169305 -169.818341) (xy 34.0901 -169.75669) (xy 34.016256 -169.68871) (xy 33.948279 -169.614863)
			(xy 33.886631 -169.535656) (xy 33.831735 -169.451628) (xy 33.783965 -169.363354) (xy 33.743648 -169.271437)
			(xy 33.711059 -169.176504) (xy 33.686421 -169.079205) (xy 33.669902 -168.980203) (xy 33.661614 -168.880175)
			(xy 33.661096 -168.82999) (xy 32.074156 -168.82999) (xy 32.126179 -168.923115) (xy 32.226147 -169.085474)
			(xy 32.332915 -169.243443) (xy 32.446292 -169.396739) (xy 32.566073 -169.545084) (xy 32.692041 -169.688213)
			(xy 32.823971 -169.825866) (xy 32.961624 -169.957796) (xy 33.104753 -170.083765) (xy 33.253098 -170.203545)
			(xy 33.406394 -170.316922) (xy 33.564363 -170.423691) (xy 33.726721 -170.523659) (xy 33.893176 -170.616647)
			(xy 34.063427 -170.702486) (xy 34.237168 -170.781022) (xy 34.414086 -170.852113) (xy 34.593862 -170.915632)
			(xy 34.776171 -170.971463) (xy 34.960685 -171.019507) (xy 35.147073 -171.059677) (xy 35.334997 -171.0919)
			(xy 35.52412 -171.116118) (xy 35.7141 -171.132288) (xy 35.904595 -171.14038) (xy 35.999928 -171.140882)
		)
		(stroke
			(width 0)
			(type solid)
		)
		(fill yes)
		(layer "In3.Cu")
		(net "GND")
	)
	(gr_circle
		(center 34.874962 -168.82999)
		(end 36.088066 -168.82999)
		(stroke
			(width 0.2)
			(type default)
		)
		(fill no)
		(layer "In3.Cu")
	)
	(gr_circle
		(center 34.874962 -166.829994)
		(end 36.088066 -166.829994)
		(stroke
			(width 0.2)
			(type default)
		)
		(fill no)
		(layer "In3.Cu")
	)
	(gr_circle
		(center 34.874962 -164.829998)
		(end 36.088066 -164.829998)
		(stroke
			(width 0.2)
			(type default)
		)
		(fill no)
		(layer "In3.Cu")
	)
	(gr_circle
		(center 34.874962 -162.830002)
		(end 36.088066 -162.830002)
		(stroke
			(width 0.2)
			(type default)
		)
		(fill no)
		(layer "In3.Cu")
	)
	(gr_circle
		(center 34.874962 -160.830006)
		(end 36.088066 -160.830006)
		(stroke
			(width 0.2)
			(type default)
		)
		(fill no)
		(layer "In3.Cu")
	)
	(gr_circle
		(center 34.874962 -158.83001)
		(end 36.088066 -158.83001)
		(stroke
			(width 0.2)
			(type default)
		)
		(fill no)
		(layer "In3.Cu")
	)
	(gr_circle
		(center 34.874962 -156.830014)
		(end 36.088066 -156.830014)
		(stroke
			(width 0.2)
			(type default)
		)
		(fill no)
		(layer "In3.Cu")
	)
	(gr_circle
		(center 34.874962 -154.830018)
		(end 36.088066 -154.830018)
		(stroke
			(width 0.2)
			(type default)
		)
		(fill no)
		(layer "In3.Cu")
	)
	(gr_circle
		(center 34.874962 -152.830022)
		(end 36.088066 -152.830022)
		(stroke
			(width 0.2)
			(type default)
		)
		(fill no)
		(layer "In3.Cu")
	)
	(gr_circle
		(center 35.985958 -167.566594)
		(end 37.199062 -167.566594)
		(stroke
			(width 0.2)
			(type default)
		)
		(fill no)
		(layer "In3.Cu")
	)
	(gr_circle
		(center 35.985958 -165.566598)
		(end 37.199062 -165.566598)
		(stroke
			(width 0.2)
			(type default)
		)
		(fill no)
		(layer "In3.Cu")
	)
	(gr_circle
		(center 35.985958 -163.566602)
		(end 37.199062 -163.566602)
		(stroke
			(width 0.2)
			(type default)
		)
		(fill no)
		(layer "In3.Cu")
	)
	(gr_circle
		(center 35.985958 -161.566606)
		(end 37.199062 -161.566606)
		(stroke
			(width 0.2)
			(type default)
		)
		(fill no)
		(layer "In3.Cu")
	)
	(gr_circle
		(center 35.985958 -159.56661)
		(end 37.199062 -159.56661)
		(stroke
			(width 0.2)
			(type default)
		)
		(fill no)
		(layer "In3.Cu")
	)
	(gr_circle
		(center 35.985958 -157.566614)
		(end 37.199062 -157.566614)
		(stroke
			(width 0.2)
			(type default)
		)
		(fill no)
		(layer "In3.Cu")
	)
	(gr_circle
		(center 35.985958 -155.566618)
		(end 37.199062 -155.566618)
		(stroke
			(width 0.2)
			(type default)
		)
		(fill no)
		(layer "In3.Cu")
	)
	(gr_circle
		(center 35.985958 -153.566622)
		(end 37.199062 -153.566622)
		(stroke
			(width 0.2)
			(type default)
		)
		(fill no)
		(layer "In3.Cu")
	)
	(gr_circle
		(center 36.874958 -168.82999)
		(end 38.088062 -168.82999)
		(stroke
			(width 0.2)
			(type default)
		)
		(fill no)
		(layer "In3.Cu")
	)
	(gr_circle
		(center 36.874958 -166.829994)
		(end 38.088062 -166.829994)
		(stroke
			(width 0.2)
			(type default)
		)
		(fill no)
		(layer "In3.Cu")
	)
	(gr_circle
		(center 36.874958 -164.829998)
		(end 38.088062 -164.829998)
		(stroke
			(width 0.2)
			(type default)
		)
		(fill no)
		(layer "In3.Cu")
	)
	(gr_circle
		(center 36.874958 -162.830002)
		(end 38.088062 -162.830002)
		(stroke
			(width 0.2)
			(type default)
		)
		(fill no)
		(layer "In3.Cu")
	)
	(gr_circle
		(center 36.874958 -160.830006)
		(end 38.088062 -160.830006)
		(stroke
			(width 0.2)
			(type default)
		)
		(fill no)
		(layer "In3.Cu")
	)
	(gr_circle
		(center 36.874958 -158.83001)
		(end 38.088062 -158.83001)
		(stroke
			(width 0.2)
			(type default)
		)
		(fill no)
		(layer "In3.Cu")
	)
	(gr_circle
		(center 36.874958 -156.830014)
		(end 38.088062 -156.830014)
		(stroke
			(width 0.2)
			(type default)
		)
		(fill no)
		(layer "In3.Cu")
	)
	(gr_circle
		(center 36.874958 -154.830018)
		(end 38.088062 -154.830018)
		(stroke
			(width 0.2)
			(type default)
		)
		(fill no)
		(layer "In3.Cu")
	)
	(gr_circle
		(center 36.874958 -152.830022)
		(end 38.088062 -152.830022)
		(stroke
			(width 0.2)
			(type default)
		)
		(fill no)
		(layer "In3.Cu")
	)
	(gr_circle
		(center 42.36339 -139.7)
		(end 43.88739 -139.7)
		(stroke
			(width 0.2)
			(type default)
		)
		(fill no)
		(layer "In3.Cu")
	)
	(gr_circle
		(center 42.36339 -119.38)
		(end 43.88739 -119.38)
		(stroke
			(width 0.2)
			(type default)
		)
		(fill no)
		(layer "In3.Cu")
	)
	(gr_circle
		(center 42.36339 -99.06)
		(end 43.88739 -99.06)
		(stroke
			(width 0.2)
			(type default)
		)
		(fill no)
		(layer "In3.Cu")
	)
	(gr_circle
		(center 42.36339 -78.74)
		(end 43.88739 -78.74)
		(stroke
			(width 0.2)
			(type default)
		)
		(fill no)
		(layer "In3.Cu")
	)
	(gr_circle
		(center 42.36339 -58.42)
		(end 43.88739 -58.42)
		(stroke
			(width 0.2)
			(type default)
		)
		(fill no)
		(layer "In3.Cu")
	)
	(gr_circle
		(center 48.800004 -160.830006)
		(end 50.013108 -160.830006)
		(stroke
			(width 0.2)
			(type default)
		)
		(fill no)
		(layer "In3.Cu")
	)
	(gr_circle
		(center 48.800004 -158.83001)
		(end 50.013108 -158.83001)
		(stroke
			(width 0.2)
			(type default)
		)
		(fill no)
		(layer "In3.Cu")
	)
	(gr_circle
		(center 48.800004 -156.830014)
		(end 50.013108 -156.830014)
		(stroke
			(width 0.2)
			(type default)
		)
		(fill no)
		(layer "In3.Cu")
	)
	(gr_circle
		(center 49.9491 -159.99841)
		(end 51.162204 -159.99841)
		(stroke
			(width 0.2)
			(type default)
		)
		(fill no)
		(layer "In3.Cu")
	)
	(gr_circle
		(center 49.9491 -157.998414)
		(end 51.162204 -157.998414)
		(stroke
			(width 0.2)
			(type default)
		)
		(fill no)
		(layer "In3.Cu")
	)
	(gr_circle
		(center 50.8 -160.830006)
		(end 52.013104 -160.830006)
		(stroke
			(width 0.2)
			(type default)
		)
		(fill no)
		(layer "In3.Cu")
	)
	(gr_circle
		(center 50.8 -158.83001)
		(end 52.013104 -158.83001)
		(stroke
			(width 0.2)
			(type default)
		)
		(fill no)
		(layer "In3.Cu")
	)
	(gr_circle
		(center 50.8 -156.830014)
		(end 52.013104 -156.830014)
		(stroke
			(width 0.2)
			(type default)
		)
		(fill no)
		(layer "In3.Cu")
	)
	(gr_circle
		(center 54.799992 -160.830006)
		(end 56.013096 -160.830006)
		(stroke
			(width 0.2)
			(type default)
		)
		(fill no)
		(layer "In3.Cu")
	)
	(gr_circle
		(center 54.799992 -158.83001)
		(end 56.013096 -158.83001)
		(stroke
			(width 0.2)
			(type default)
		)
		(fill no)
		(layer "In3.Cu")
	)
	(gr_circle
		(center 54.799992 -156.830014)
		(end 56.013096 -156.830014)
		(stroke
			(width 0.2)
			(type default)
		)
		(fill no)
		(layer "In3.Cu")
	)
	(gr_circle
		(center 55.5625 -159.84601)
		(end 56.775604 -159.84601)
		(stroke
			(width 0.2)
			(type default)
		)
		(fill no)
		(layer "In3.Cu")
	)
	(gr_circle
		(center 55.5625 -157.846014)
		(end 56.775604 -157.846014)
		(stroke
			(width 0.2)
			(type default)
		)
		(fill no)
		(layer "In3.Cu")
	)
	(gr_circle
		(center 56.799988 -160.830006)
		(end 58.013092 -160.830006)
		(stroke
			(width 0.2)
			(type default)
		)
		(fill no)
		(layer "In3.Cu")
	)
	(gr_circle
		(center 56.799988 -158.83001)
		(end 58.013092 -158.83001)
		(stroke
			(width 0.2)
			(type default)
		)
		(fill no)
		(layer "In3.Cu")
	)
	(gr_circle
		(center 56.799988 -156.830014)
		(end 58.013092 -156.830014)
		(stroke
			(width 0.2)
			(type default)
		)
		(fill no)
		(layer "In3.Cu")
	)
	(gr_circle
		(center 61.92139 -139.7)
		(end 63.44539 -139.7)
		(stroke
			(width 0.2)
			(type default)
		)
		(fill no)
		(layer "In3.Cu")
	)
	(gr_circle
		(center 61.92139 -119.38)
		(end 63.44539 -119.38)
		(stroke
			(width 0.2)
			(type default)
		)
		(fill no)
		(layer "In3.Cu")
	)
	(gr_circle
		(center 61.92139 -99.06)
		(end 63.44539 -99.06)
		(stroke
			(width 0.2)
			(type default)
		)
		(fill no)
		(layer "In3.Cu")
	)
	(gr_circle
		(center 61.92139 -78.74)
		(end 63.44539 -78.74)
		(stroke
			(width 0.2)
			(type default)
		)
		(fill no)
		(layer "In3.Cu")
	)
	(gr_circle
		(center 61.92139 -58.42)
		(end 63.44539 -58.42)
		(stroke
			(width 0.2)
			(type default)
		)
		(fill no)
		(layer "In3.Cu")
	)
	(gr_circle
		(center 63.000128 -160.830006)
		(end 64.213232 -160.830006)
		(stroke
			(width 0.2)
			(type default)
		)
		(fill no)
		(layer "In3.Cu")
	)
	(gr_circle
		(center 63.000128 -158.83001)
		(end 64.213232 -158.83001)
		(stroke
			(width 0.2)
			(type default)
		)
		(fill no)
		(layer "In3.Cu")
	)
	(gr_circle
		(center 63.000128 -156.830014)
		(end 64.213232 -156.830014)
		(stroke
			(width 0.2)
			(type default)
		)
		(fill no)
		(layer "In3.Cu")
	)
	(gr_circle
		(center 63.719964 -2.590038)
		(end 64.933068 -2.590038)
		(stroke
			(width 0.2)
			(type default)
		)
		(fill no)
		(layer "In3.Cu")
	)
	(gr_circle
		(center 63.9699 -159.89681)
		(end 65.183004 -159.89681)
		(stroke
			(width 0.2)
			(type default)
		)
		(fill no)
		(layer "In3.Cu")
	)
	(gr_circle
		(center 63.9699 -157.896814)
		(end 65.183004 -157.896814)
		(stroke
			(width 0.2)
			(type default)
		)
		(fill no)
		(layer "In3.Cu")
	)
	(gr_circle
		(center 65.000124 -160.830006)
		(end 66.213228 -160.830006)
		(stroke
			(width 0.2)
			(type default)
		)
		(fill no)
		(layer "In3.Cu")
	)
	(gr_circle
		(center 65.000124 -158.83001)
		(end 66.213228 -158.83001)
		(stroke
			(width 0.2)
			(type default)
		)
		(fill no)
		(layer "In3.Cu")
	)
	(gr_circle
		(center 65.000124 -156.830014)
		(end 66.213228 -156.830014)
		(stroke
			(width 0.2)
			(type default)
		)
		(fill no)
		(layer "In3.Cu")
	)
	(gr_circle
		(center 66.259964 -2.590038)
		(end 67.473068 -2.590038)
		(stroke
			(width 0.2)
			(type default)
		)
		(fill no)
		(layer "In3.Cu")
	)
	(gr_circle
		(center 69.000116 -160.830006)
		(end 70.21322 -160.830006)
		(stroke
			(width 0.2)
			(type default)
		)
		(fill no)
		(layer "In3.Cu")
	)
	(gr_circle
		(center 69.000116 -158.83001)
		(end 70.21322 -158.83001)
		(stroke
			(width 0.2)
			(type default)
		)
		(fill no)
		(layer "In3.Cu")
	)
	(gr_circle
		(center 69.000116 -156.830014)
		(end 70.21322 -156.830014)
		(stroke
			(width 0.2)
			(type default)
		)
		(fill no)
		(layer "In3.Cu")
	)
	(gr_circle
		(center 69.8881 -159.79521)
		(end 71.101204 -159.79521)
		(stroke
			(width 0.2)
			(type default)
		)
		(fill no)
		(layer "In3.Cu")
	)
	(gr_circle
		(center 69.8881 -157.795214)
		(end 71.101204 -157.795214)
		(stroke
			(width 0.2)
			(type default)
		)
		(fill no)
		(layer "In3.Cu")
	)
	(gr_circle
		(center 71.000112 -160.830006)
		(end 72.213216 -160.830006)
		(stroke
			(width 0.2)
			(type default)
		)
		(fill no)
		(layer "In3.Cu")
	)
	(gr_circle
		(center 71.000112 -158.83001)
		(end 72.213216 -158.83001)
		(stroke
			(width 0.2)
			(type default)
		)
		(fill no)
		(layer "In3.Cu")
	)
	(gr_circle
		(center 71.000112 -156.830014)
		(end 72.213216 -156.830014)
		(stroke
			(width 0.2)
			(type default)
		)
		(fill no)
		(layer "In3.Cu")
	)
	(gr_circle
		(center 75.000104 -160.830006)
		(end 76.213208 -160.830006)
		(stroke
			(width 0.2)
			(type default)
		)
		(fill no)
		(layer "In3.Cu")
	)
	(gr_circle
		(center 75.000104 -158.83001)
		(end 76.213208 -158.83001)
		(stroke
			(width 0.2)
			(type default)
		)
		(fill no)
		(layer "In3.Cu")
	)
	(gr_circle
		(center 75.000104 -156.830014)
		(end 76.213208 -156.830014)
		(stroke
			(width 0.2)
			(type default)
		)
		(fill no)
		(layer "In3.Cu")
	)
	(gr_circle
		(center 75.8571 -159.74441)
		(end 77.070204 -159.74441)
		(stroke
			(width 0.2)
			(type default)
		)
		(fill no)
		(layer "In3.Cu")
	)
	(gr_circle
		(center 75.8571 -157.744414)
		(end 77.070204 -157.744414)
		(stroke
			(width 0.2)
			(type default)
		)
		(fill no)
		(layer "In3.Cu")
	)
	(gr_circle
		(center 77.0001 -160.830006)
		(end 78.213204 -160.830006)
		(stroke
			(width 0.2)
			(type default)
		)
		(fill no)
		(layer "In3.Cu")
	)
	(gr_circle
		(center 77.0001 -158.83001)
		(end 78.213204 -158.83001)
		(stroke
			(width 0.2)
			(type default)
		)
		(fill no)
		(layer "In3.Cu")
	)
	(gr_circle
		(center 77.0001 -156.830014)
		(end 78.213204 -156.830014)
		(stroke
			(width 0.2)
			(type default)
		)
		(fill no)
		(layer "In3.Cu")
	)
	(gr_circle
		(center 82.677 -5.334)
		(end 83.566 -5.334)
		(stroke
			(width 0.2)
			(type default)
		)
		(fill no)
		(layer "In3.Cu")
	)
	(gr_circle
		(center 82.677 -4.572)
		(end 83.566 -4.572)
		(stroke
			(width 0.2)
			(type default)
		)
		(fill no)
		(layer "In3.Cu")
	)
	(gr_circle
		(center 82.677 -3.81)
		(end 83.566 -3.81)
		(stroke
			(width 0.2)
			(type default)
		)
		(fill no)
		(layer "In3.Cu")
	)
	(gr_circle
		(center 83.439 -5.334)
		(end 84.328 -5.334)
		(stroke
			(width 0.2)
			(type default)
		)
		(fill no)
		(layer "In3.Cu")
	)
	(gr_circle
		(center 83.439 -4.572)
		(end 84.328 -4.572)
		(stroke
			(width 0.2)
			(type default)
		)
		(fill no)
		(layer "In3.Cu")
	)
	(gr_circle
		(center 83.439 -3.81)
		(end 84.328 -3.81)
		(stroke
			(width 0.2)
			(type default)
		)
		(fill no)
		(layer "In3.Cu")
	)
	(gr_circle
		(center 84.201 -5.334)
		(end 85.09 -5.334)
		(stroke
			(width 0.2)
			(type default)
		)
		(fill no)
		(layer "In3.Cu")
	)
	(gr_circle
		(center 84.201 -4.572)
		(end 85.09 -4.572)
		(stroke
			(width 0.2)
			(type default)
		)
		(fill no)
		(layer "In3.Cu")
	)
	(gr_circle
		(center 84.201 -3.81)
		(end 85.09 -3.81)
		(stroke
			(width 0.2)
			(type default)
		)
		(fill no)
		(layer "In3.Cu")
	)
	(gr_circle
		(center 84.963 -5.334)
		(end 85.852 -5.334)
		(stroke
			(width 0.2)
			(type default)
		)
		(fill no)
		(layer "In3.Cu")
	)
	(gr_circle
		(center 84.963 -4.572)
		(end 85.852 -4.572)
		(stroke
			(width 0.2)
			(type default)
		)
		(fill no)
		(layer "In3.Cu")
	)
	(gr_circle
		(center 84.963 -3.81)
		(end 85.852 -3.81)
		(stroke
			(width 0.2)
			(type default)
		)
		(fill no)
		(layer "In3.Cu")
	)
	(gr_circle
		(center 85.725 -5.334)
		(end 86.614 -5.334)
		(stroke
			(width 0.2)
			(type default)
		)
		(fill no)
		(layer "In3.Cu")
	)
	(gr_circle
		(center 85.725 -4.572)
		(end 86.614 -4.572)
		(stroke
			(width 0.2)
			(type default)
		)
		(fill no)
		(layer "In3.Cu")
	)
	(gr_circle
		(center 85.725 -3.81)
		(end 86.614 -3.81)
		(stroke
			(width 0.2)
			(type default)
		)
		(fill no)
		(layer "In3.Cu")
	)
	(gr_circle
		(center 86.487 -5.334)
		(end 87.376 -5.334)
		(stroke
			(width 0.2)
			(type default)
		)
		(fill no)
		(layer "In3.Cu")
	)
	(gr_circle
		(center 86.487 -4.572)
		(end 87.376 -4.572)
		(stroke
			(width 0.2)
			(type default)
		)
		(fill no)
		(layer "In3.Cu")
	)
	(gr_circle
		(center 86.487 -3.81)
		(end 87.376 -3.81)
		(stroke
			(width 0.2)
			(type default)
		)
		(fill no)
		(layer "In3.Cu")
	)
	(gr_circle
		(center 108.782358 -42.432224)
		(end 109.671358 -42.432224)
		(stroke
			(width 0.2)
			(type default)
		)
		(fill no)
		(layer "In3.Cu")
	)
	(gr_circle
		(center 109.374432 -53.692806)
		(end 110.263432 -53.692806)
		(stroke
			(width 0.2)
			(type default)
		)
		(fill no)
		(layer "In3.Cu")
	)
	(gr_circle
		(center 111.2774 -54.483)
		(end 112.1664 -54.483)
		(stroke
			(width 0.2)
			(type default)
		)
		(fill no)
		(layer "In3.Cu")
	)
	(gr_circle
		(center 111.2774 -43.18)
		(end 112.1664 -43.18)
		(stroke
			(width 0.2)
			(type default)
		)
		(fill no)
		(layer "In3.Cu")
	)
	(gr_circle
		(center 112.252252 -78.6638)
		(end 113.141252 -78.6638)
		(stroke
			(width 0.2)
			(type default)
		)
		(fill no)
		(layer "In3.Cu")
	)
	(gr_circle
		(center 112.252252 -67.3862)
		(end 113.141252 -67.3862)
		(stroke
			(width 0.2)
			(type default)
		)
		(fill no)
		(layer "In3.Cu")
	)
	(gr_circle
		(center 112.252252 -56.1086)
		(end 113.141252 -56.1086)
		(stroke
			(width 0.2)
			(type default)
		)
		(fill no)
		(layer "In3.Cu")
	)
	(gr_circle
		(center 112.252252 -44.831)
		(end 113.141252 -44.831)
		(stroke
			(width 0.2)
			(type default)
		)
		(fill no)
		(layer "In3.Cu")
	)
	(gr_circle
		(center 112.252252 -33.5534)
		(end 113.141252 -33.5534)
		(stroke
			(width 0.2)
			(type default)
		)
		(fill no)
		(layer "In3.Cu")
	)
	(gr_circle
		(center 112.252252 -22.2758)
		(end 113.141252 -22.2758)
		(stroke
			(width 0.2)
			(type default)
		)
		(fill no)
		(layer "In3.Cu")
	)
	(gr_circle
		(center 112.455452 -73.66)
		(end 113.344452 -73.66)
		(stroke
			(width 0.2)
			(type default)
		)
		(fill no)
		(layer "In3.Cu")
	)
	(gr_circle
		(center 112.455452 -72.898)
		(end 113.344452 -72.898)
		(stroke
			(width 0.2)
			(type default)
		)
		(fill no)
		(layer "In3.Cu")
	)
	(gr_circle
		(center 112.455452 -72.136)
		(end 113.344452 -72.136)
		(stroke
			(width 0.2)
			(type default)
		)
		(fill no)
		(layer "In3.Cu")
	)
	(gr_circle
		(center 112.455452 -71.374)
		(end 113.344452 -71.374)
		(stroke
			(width 0.2)
			(type default)
		)
		(fill no)
		(layer "In3.Cu")
	)
	(gr_circle
		(center 112.455452 -70.612)
		(end 113.344452 -70.612)
		(stroke
			(width 0.2)
			(type default)
		)
		(fill no)
		(layer "In3.Cu")
	)
	(gr_circle
		(center 112.455452 -62.3824)
		(end 113.344452 -62.3824)
		(stroke
			(width 0.2)
			(type default)
		)
		(fill no)
		(layer "In3.Cu")
	)
	(gr_circle
		(center 112.455452 -61.6204)
		(end 113.344452 -61.6204)
		(stroke
			(width 0.2)
			(type default)
		)
		(fill no)
		(layer "In3.Cu")
	)
	(gr_circle
		(center 112.455452 -60.8584)
		(end 113.344452 -60.8584)
		(stroke
			(width 0.2)
			(type default)
		)
		(fill no)
		(layer "In3.Cu")
	)
	(gr_circle
		(center 112.455452 -60.0964)
		(end 113.344452 -60.0964)
		(stroke
			(width 0.2)
			(type default)
		)
		(fill no)
		(layer "In3.Cu")
	)
	(gr_circle
		(center 112.455452 -59.3344)
		(end 113.344452 -59.3344)
		(stroke
			(width 0.2)
			(type default)
		)
		(fill no)
		(layer "In3.Cu")
	)
	(gr_circle
		(center 112.455452 -51.1048)
		(end 113.344452 -51.1048)
		(stroke
			(width 0.2)
			(type default)
		)
		(fill no)
		(layer "In3.Cu")
	)
	(gr_circle
		(center 112.455452 -50.3428)
		(end 113.344452 -50.3428)
		(stroke
			(width 0.2)
			(type default)
		)
		(fill no)
		(layer "In3.Cu")
	)
	(gr_circle
		(center 112.455452 -49.5808)
		(end 113.344452 -49.5808)
		(stroke
			(width 0.2)
			(type default)
		)
		(fill no)
		(layer "In3.Cu")
	)
	(gr_circle
		(center 112.455452 -48.8188)
		(end 113.344452 -48.8188)
		(stroke
			(width 0.2)
			(type default)
		)
		(fill no)
		(layer "In3.Cu")
	)
	(gr_circle
		(center 112.455452 -48.0568)
		(end 113.344452 -48.0568)
		(stroke
			(width 0.2)
			(type default)
		)
		(fill no)
		(layer "In3.Cu")
	)
	(gr_circle
		(center 112.455452 -39.8272)
		(end 113.344452 -39.8272)
		(stroke
			(width 0.2)
			(type default)
		)
		(fill no)
		(layer "In3.Cu")
	)
	(gr_circle
		(center 112.455452 -39.0652)
		(end 113.344452 -39.0652)
		(stroke
			(width 0.2)
			(type default)
		)
		(fill no)
		(layer "In3.Cu")
	)
	(gr_circle
		(center 112.455452 -38.3032)
		(end 113.344452 -38.3032)
		(stroke
			(width 0.2)
			(type default)
		)
		(fill no)
		(layer "In3.Cu")
	)
	(gr_circle
		(center 112.455452 -37.5412)
		(end 113.344452 -37.5412)
		(stroke
			(width 0.2)
			(type default)
		)
		(fill no)
		(layer "In3.Cu")
	)
	(gr_circle
		(center 112.455452 -36.7792)
		(end 113.344452 -36.7792)
		(stroke
			(width 0.2)
			(type default)
		)
		(fill no)
		(layer "In3.Cu")
	)
	(gr_circle
		(center 112.455452 -28.5496)
		(end 113.344452 -28.5496)
		(stroke
			(width 0.2)
			(type default)
		)
		(fill no)
		(layer "In3.Cu")
	)
	(gr_circle
		(center 112.455452 -27.7876)
		(end 113.344452 -27.7876)
		(stroke
			(width 0.2)
			(type default)
		)
		(fill no)
		(layer "In3.Cu")
	)
	(gr_circle
		(center 112.455452 -27.0256)
		(end 113.344452 -27.0256)
		(stroke
			(width 0.2)
			(type default)
		)
		(fill no)
		(layer "In3.Cu")
	)
	(gr_circle
		(center 112.455452 -26.2636)
		(end 113.344452 -26.2636)
		(stroke
			(width 0.2)
			(type default)
		)
		(fill no)
		(layer "In3.Cu")
	)
	(gr_circle
		(center 112.455452 -25.5016)
		(end 113.344452 -25.5016)
		(stroke
			(width 0.2)
			(type default)
		)
		(fill no)
		(layer "In3.Cu")
	)
	(gr_circle
		(center 112.455452 -17.272)
		(end 113.344452 -17.272)
		(stroke
			(width 0.2)
			(type default)
		)
		(fill no)
		(layer "In3.Cu")
	)
	(gr_circle
		(center 112.455452 -16.51)
		(end 113.344452 -16.51)
		(stroke
			(width 0.2)
			(type default)
		)
		(fill no)
		(layer "In3.Cu")
	)
	(gr_circle
		(center 112.455452 -15.748)
		(end 113.344452 -15.748)
		(stroke
			(width 0.2)
			(type default)
		)
		(fill no)
		(layer "In3.Cu")
	)
	(gr_circle
		(center 112.455452 -14.986)
		(end 113.344452 -14.986)
		(stroke
			(width 0.2)
			(type default)
		)
		(fill no)
		(layer "In3.Cu")
	)
	(gr_circle
		(center 112.455452 -14.224)
		(end 113.344452 -14.224)
		(stroke
			(width 0.2)
			(type default)
		)
		(fill no)
		(layer "In3.Cu")
	)
	(gr_circle
		(center 113.217452 -73.66)
		(end 114.106452 -73.66)
		(stroke
			(width 0.2)
			(type default)
		)
		(fill no)
		(layer "In3.Cu")
	)
	(gr_circle
		(center 113.217452 -72.898)
		(end 114.106452 -72.898)
		(stroke
			(width 0.2)
			(type default)
		)
		(fill no)
		(layer "In3.Cu")
	)
	(gr_circle
		(center 113.217452 -72.136)
		(end 114.106452 -72.136)
		(stroke
			(width 0.2)
			(type default)
		)
		(fill no)
		(layer "In3.Cu")
	)
	(gr_circle
		(center 113.217452 -71.374)
		(end 114.106452 -71.374)
		(stroke
			(width 0.2)
			(type default)
		)
		(fill no)
		(layer "In3.Cu")
	)
	(gr_circle
		(center 113.217452 -70.612)
		(end 114.106452 -70.612)
		(stroke
			(width 0.2)
			(type default)
		)
		(fill no)
		(layer "In3.Cu")
	)
	(gr_circle
		(center 113.217452 -62.3824)
		(end 114.106452 -62.3824)
		(stroke
			(width 0.2)
			(type default)
		)
		(fill no)
		(layer "In3.Cu")
	)
	(gr_circle
		(center 113.217452 -61.6204)
		(end 114.106452 -61.6204)
		(stroke
			(width 0.2)
			(type default)
		)
		(fill no)
		(layer "In3.Cu")
	)
	(gr_circle
		(center 113.217452 -60.8584)
		(end 114.106452 -60.8584)
		(stroke
			(width 0.2)
			(type default)
		)
		(fill no)
		(layer "In3.Cu")
	)
	(gr_circle
		(center 113.217452 -60.0964)
		(end 114.106452 -60.0964)
		(stroke
			(width 0.2)
			(type default)
		)
		(fill no)
		(layer "In3.Cu")
	)
	(gr_circle
		(center 113.217452 -59.3344)
		(end 114.106452 -59.3344)
		(stroke
			(width 0.2)
			(type default)
		)
		(fill no)
		(layer "In3.Cu")
	)
	(gr_circle
		(center 113.217452 -51.1048)
		(end 114.106452 -51.1048)
		(stroke
			(width 0.2)
			(type default)
		)
		(fill no)
		(layer "In3.Cu")
	)
	(gr_circle
		(center 113.217452 -50.3428)
		(end 114.106452 -50.3428)
		(stroke
			(width 0.2)
			(type default)
		)
		(fill no)
		(layer "In3.Cu")
	)
	(gr_circle
		(center 113.217452 -49.5808)
		(end 114.106452 -49.5808)
		(stroke
			(width 0.2)
			(type default)
		)
		(fill no)
		(layer "In3.Cu")
	)
	(gr_circle
		(center 113.217452 -48.8188)
		(end 114.106452 -48.8188)
		(stroke
			(width 0.2)
			(type default)
		)
		(fill no)
		(layer "In3.Cu")
	)
	(gr_circle
		(center 113.217452 -48.0568)
		(end 114.106452 -48.0568)
		(stroke
			(width 0.2)
			(type default)
		)
		(fill no)
		(layer "In3.Cu")
	)
	(gr_circle
		(center 113.217452 -39.8272)
		(end 114.106452 -39.8272)
		(stroke
			(width 0.2)
			(type default)
		)
		(fill no)
		(layer "In3.Cu")
	)
	(gr_circle
		(center 113.217452 -39.0652)
		(end 114.106452 -39.0652)
		(stroke
			(width 0.2)
			(type default)
		)
		(fill no)
		(layer "In3.Cu")
	)
	(gr_circle
		(center 113.217452 -38.3032)
		(end 114.106452 -38.3032)
		(stroke
			(width 0.2)
			(type default)
		)
		(fill no)
		(layer "In3.Cu")
	)
	(gr_circle
		(center 113.217452 -37.5412)
		(end 114.106452 -37.5412)
		(stroke
			(width 0.2)
			(type default)
		)
		(fill no)
		(layer "In3.Cu")
	)
	(gr_circle
		(center 113.217452 -36.7792)
		(end 114.106452 -36.7792)
		(stroke
			(width 0.2)
			(type default)
		)
		(fill no)
		(layer "In3.Cu")
	)
	(gr_circle
		(center 113.217452 -28.5496)
		(end 114.106452 -28.5496)
		(stroke
			(width 0.2)
			(type default)
		)
		(fill no)
		(layer "In3.Cu")
	)
	(gr_circle
		(center 113.217452 -27.7876)
		(end 114.106452 -27.7876)
		(stroke
			(width 0.2)
			(type default)
		)
		(fill no)
		(layer "In3.Cu")
	)
	(gr_circle
		(center 113.217452 -27.0256)
		(end 114.106452 -27.0256)
		(stroke
			(width 0.2)
			(type default)
		)
		(fill no)
		(layer "In3.Cu")
	)
	(gr_circle
		(center 113.217452 -26.2636)
		(end 114.106452 -26.2636)
		(stroke
			(width 0.2)
			(type default)
		)
		(fill no)
		(layer "In3.Cu")
	)
	(gr_circle
		(center 113.217452 -25.5016)
		(end 114.106452 -25.5016)
		(stroke
			(width 0.2)
			(type default)
		)
		(fill no)
		(layer "In3.Cu")
	)
	(gr_circle
		(center 113.217452 -17.272)
		(end 114.106452 -17.272)
		(stroke
			(width 0.2)
			(type default)
		)
		(fill no)
		(layer "In3.Cu")
	)
	(gr_circle
		(center 113.217452 -16.51)
		(end 114.106452 -16.51)
		(stroke
			(width 0.2)
			(type default)
		)
		(fill no)
		(layer "In3.Cu")
	)
	(gr_circle
		(center 113.217452 -15.748)
		(end 114.106452 -15.748)
		(stroke
			(width 0.2)
			(type default)
		)
		(fill no)
		(layer "In3.Cu")
	)
	(gr_circle
		(center 113.217452 -14.986)
		(end 114.106452 -14.986)
		(stroke
			(width 0.2)
			(type default)
		)
		(fill no)
		(layer "In3.Cu")
	)
	(gr_circle
		(center 113.217452 -14.224)
		(end 114.106452 -14.224)
		(stroke
			(width 0.2)
			(type default)
		)
		(fill no)
		(layer "In3.Cu")
	)
	(gr_circle
		(center 113.979452 -73.66)
		(end 114.868452 -73.66)
		(stroke
			(width 0.2)
			(type default)
		)
		(fill no)
		(layer "In3.Cu")
	)
	(gr_circle
		(center 113.979452 -72.898)
		(end 114.868452 -72.898)
		(stroke
			(width 0.2)
			(type default)
		)
		(fill no)
		(layer "In3.Cu")
	)
	(gr_circle
		(center 113.979452 -72.136)
		(end 114.868452 -72.136)
		(stroke
			(width 0.2)
			(type default)
		)
		(fill no)
		(layer "In3.Cu")
	)
	(gr_circle
		(center 113.979452 -71.374)
		(end 114.868452 -71.374)
		(stroke
			(width 0.2)
			(type default)
		)
		(fill no)
		(layer "In3.Cu")
	)
	(gr_circle
		(center 113.979452 -70.612)
		(end 114.868452 -70.612)
		(stroke
			(width 0.2)
			(type default)
		)
		(fill no)
		(layer "In3.Cu")
	)
	(gr_circle
		(center 113.979452 -62.3824)
		(end 114.868452 -62.3824)
		(stroke
			(width 0.2)
			(type default)
		)
		(fill no)
		(layer "In3.Cu")
	)
	(gr_circle
		(center 113.979452 -61.6204)
		(end 114.868452 -61.6204)
		(stroke
			(width 0.2)
			(type default)
		)
		(fill no)
		(layer "In3.Cu")
	)
	(gr_circle
		(center 113.979452 -60.8584)
		(end 114.868452 -60.8584)
		(stroke
			(width 0.2)
			(type default)
		)
		(fill no)
		(layer "In3.Cu")
	)
	(gr_circle
		(center 113.979452 -60.0964)
		(end 114.868452 -60.0964)
		(stroke
			(width 0.2)
			(type default)
		)
		(fill no)
		(layer "In3.Cu")
	)
	(gr_circle
		(center 113.979452 -59.3344)
		(end 114.868452 -59.3344)
		(stroke
			(width 0.2)
			(type default)
		)
		(fill no)
		(layer "In3.Cu")
	)
	(gr_circle
		(center 113.979452 -51.1048)
		(end 114.868452 -51.1048)
		(stroke
			(width 0.2)
			(type default)
		)
		(fill no)
		(layer "In3.Cu")
	)
	(gr_circle
		(center 113.979452 -50.3428)
		(end 114.868452 -50.3428)
		(stroke
			(width 0.2)
			(type default)
		)
		(fill no)
		(layer "In3.Cu")
	)
	(gr_circle
		(center 113.979452 -49.5808)
		(end 114.868452 -49.5808)
		(stroke
			(width 0.2)
			(type default)
		)
		(fill no)
		(layer "In3.Cu")
	)
	(gr_circle
		(center 113.979452 -48.8188)
		(end 114.868452 -48.8188)
		(stroke
			(width 0.2)
			(type default)
		)
		(fill no)
		(layer "In3.Cu")
	)
	(gr_circle
		(center 113.979452 -48.0568)
		(end 114.868452 -48.0568)
		(stroke
			(width 0.2)
			(type default)
		)
		(fill no)
		(layer "In3.Cu")
	)
	(gr_circle
		(center 113.979452 -39.8272)
		(end 114.868452 -39.8272)
		(stroke
			(width 0.2)
			(type default)
		)
		(fill no)
		(layer "In3.Cu")
	)
	(gr_circle
		(center 113.979452 -39.0652)
		(end 114.868452 -39.0652)
		(stroke
			(width 0.2)
			(type default)
		)
		(fill no)
		(layer "In3.Cu")
	)
	(gr_circle
		(center 113.979452 -38.3032)
		(end 114.868452 -38.3032)
		(stroke
			(width 0.2)
			(type default)
		)
		(fill no)
		(layer "In3.Cu")
	)
	(gr_circle
		(center 113.979452 -37.5412)
		(end 114.868452 -37.5412)
		(stroke
			(width 0.2)
			(type default)
		)
		(fill no)
		(layer "In3.Cu")
	)
	(gr_circle
		(center 113.979452 -36.7792)
		(end 114.868452 -36.7792)
		(stroke
			(width 0.2)
			(type default)
		)
		(fill no)
		(layer "In3.Cu")
	)
	(gr_circle
		(center 113.979452 -28.5496)
		(end 114.868452 -28.5496)
		(stroke
			(width 0.2)
			(type default)
		)
		(fill no)
		(layer "In3.Cu")
	)
	(gr_circle
		(center 113.979452 -27.7876)
		(end 114.868452 -27.7876)
		(stroke
			(width 0.2)
			(type default)
		)
		(fill no)
		(layer "In3.Cu")
	)
	(gr_circle
		(center 113.979452 -27.0256)
		(end 114.868452 -27.0256)
		(stroke
			(width 0.2)
			(type default)
		)
		(fill no)
		(layer "In3.Cu")
	)
	(gr_circle
		(center 113.979452 -26.2636)
		(end 114.868452 -26.2636)
		(stroke
			(width 0.2)
			(type default)
		)
		(fill no)
		(layer "In3.Cu")
	)
	(gr_circle
		(center 113.979452 -25.5016)
		(end 114.868452 -25.5016)
		(stroke
			(width 0.2)
			(type default)
		)
		(fill no)
		(layer "In3.Cu")
	)
	(gr_circle
		(center 113.979452 -17.272)
		(end 114.868452 -17.272)
		(stroke
			(width 0.2)
			(type default)
		)
		(fill no)
		(layer "In3.Cu")
	)
	(gr_circle
		(center 113.979452 -16.51)
		(end 114.868452 -16.51)
		(stroke
			(width 0.2)
			(type default)
		)
		(fill no)
		(layer "In3.Cu")
	)
	(gr_circle
		(center 113.979452 -15.748)
		(end 114.868452 -15.748)
		(stroke
			(width 0.2)
			(type default)
		)
		(fill no)
		(layer "In3.Cu")
	)
	(gr_circle
		(center 113.979452 -14.986)
		(end 114.868452 -14.986)
		(stroke
			(width 0.2)
			(type default)
		)
		(fill no)
		(layer "In3.Cu")
	)
	(gr_circle
		(center 113.979452 -14.224)
		(end 114.868452 -14.224)
		(stroke
			(width 0.2)
			(type default)
		)
		(fill no)
		(layer "In3.Cu")
	)
	(gr_circle
		(center 114.741452 -73.66)
		(end 115.630452 -73.66)
		(stroke
			(width 0.2)
			(type default)
		)
		(fill no)
		(layer "In3.Cu")
	)
	(gr_circle
		(center 114.741452 -72.898)
		(end 115.630452 -72.898)
		(stroke
			(width 0.2)
			(type default)
		)
		(fill no)
		(layer "In3.Cu")
	)
	(gr_circle
		(center 114.741452 -72.136)
		(end 115.630452 -72.136)
		(stroke
			(width 0.2)
			(type default)
		)
		(fill no)
		(layer "In3.Cu")
	)
	(gr_circle
		(center 114.741452 -71.374)
		(end 115.630452 -71.374)
		(stroke
			(width 0.2)
			(type default)
		)
		(fill no)
		(layer "In3.Cu")
	)
	(gr_circle
		(center 114.741452 -70.612)
		(end 115.630452 -70.612)
		(stroke
			(width 0.2)
			(type default)
		)
		(fill no)
		(layer "In3.Cu")
	)
	(gr_circle
		(center 114.741452 -62.3824)
		(end 115.630452 -62.3824)
		(stroke
			(width 0.2)
			(type default)
		)
		(fill no)
		(layer "In3.Cu")
	)
	(gr_circle
		(center 114.741452 -61.6204)
		(end 115.630452 -61.6204)
		(stroke
			(width 0.2)
			(type default)
		)
		(fill no)
		(layer "In3.Cu")
	)
	(gr_circle
		(center 114.741452 -60.8584)
		(end 115.630452 -60.8584)
		(stroke
			(width 0.2)
			(type default)
		)
		(fill no)
		(layer "In3.Cu")
	)
	(gr_circle
		(center 114.741452 -60.0964)
		(end 115.630452 -60.0964)
		(stroke
			(width 0.2)
			(type default)
		)
		(fill no)
		(layer "In3.Cu")
	)
	(gr_circle
		(center 114.741452 -59.3344)
		(end 115.630452 -59.3344)
		(stroke
			(width 0.2)
			(type default)
		)
		(fill no)
		(layer "In3.Cu")
	)
	(gr_circle
		(center 114.741452 -51.1048)
		(end 115.630452 -51.1048)
		(stroke
			(width 0.2)
			(type default)
		)
		(fill no)
		(layer "In3.Cu")
	)
	(gr_circle
		(center 114.741452 -50.3428)
		(end 115.630452 -50.3428)
		(stroke
			(width 0.2)
			(type default)
		)
		(fill no)
		(layer "In3.Cu")
	)
	(gr_circle
		(center 114.741452 -49.5808)
		(end 115.630452 -49.5808)
		(stroke
			(width 0.2)
			(type default)
		)
		(fill no)
		(layer "In3.Cu")
	)
	(gr_circle
		(center 114.741452 -48.8188)
		(end 115.630452 -48.8188)
		(stroke
			(width 0.2)
			(type default)
		)
		(fill no)
		(layer "In3.Cu")
	)
	(gr_circle
		(center 114.741452 -48.0568)
		(end 115.630452 -48.0568)
		(stroke
			(width 0.2)
			(type default)
		)
		(fill no)
		(layer "In3.Cu")
	)
	(gr_circle
		(center 114.741452 -39.8272)
		(end 115.630452 -39.8272)
		(stroke
			(width 0.2)
			(type default)
		)
		(fill no)
		(layer "In3.Cu")
	)
	(gr_circle
		(center 114.741452 -39.0652)
		(end 115.630452 -39.0652)
		(stroke
			(width 0.2)
			(type default)
		)
		(fill no)
		(layer "In3.Cu")
	)
	(gr_circle
		(center 114.741452 -38.3032)
		(end 115.630452 -38.3032)
		(stroke
			(width 0.2)
			(type default)
		)
		(fill no)
		(layer "In3.Cu")
	)
	(gr_circle
		(center 114.741452 -37.5412)
		(end 115.630452 -37.5412)
		(stroke
			(width 0.2)
			(type default)
		)
		(fill no)
		(layer "In3.Cu")
	)
	(gr_circle
		(center 114.741452 -36.7792)
		(end 115.630452 -36.7792)
		(stroke
			(width 0.2)
			(type default)
		)
		(fill no)
		(layer "In3.Cu")
	)
	(gr_circle
		(center 114.741452 -28.5496)
		(end 115.630452 -28.5496)
		(stroke
			(width 0.2)
			(type default)
		)
		(fill no)
		(layer "In3.Cu")
	)
	(gr_circle
		(center 114.741452 -27.7876)
		(end 115.630452 -27.7876)
		(stroke
			(width 0.2)
			(type default)
		)
		(fill no)
		(layer "In3.Cu")
	)
	(gr_circle
		(center 114.741452 -27.0256)
		(end 115.630452 -27.0256)
		(stroke
			(width 0.2)
			(type default)
		)
		(fill no)
		(layer "In3.Cu")
	)
	(gr_circle
		(center 114.741452 -26.2636)
		(end 115.630452 -26.2636)
		(stroke
			(width 0.2)
			(type default)
		)
		(fill no)
		(layer "In3.Cu")
	)
	(gr_circle
		(center 114.741452 -25.5016)
		(end 115.630452 -25.5016)
		(stroke
			(width 0.2)
			(type default)
		)
		(fill no)
		(layer "In3.Cu")
	)
	(gr_circle
		(center 114.741452 -17.272)
		(end 115.630452 -17.272)
		(stroke
			(width 0.2)
			(type default)
		)
		(fill no)
		(layer "In3.Cu")
	)
	(gr_circle
		(center 114.741452 -16.51)
		(end 115.630452 -16.51)
		(stroke
			(width 0.2)
			(type default)
		)
		(fill no)
		(layer "In3.Cu")
	)
	(gr_circle
		(center 114.741452 -15.748)
		(end 115.630452 -15.748)
		(stroke
			(width 0.2)
			(type default)
		)
		(fill no)
		(layer "In3.Cu")
	)
	(gr_circle
		(center 114.741452 -14.986)
		(end 115.630452 -14.986)
		(stroke
			(width 0.2)
			(type default)
		)
		(fill no)
		(layer "In3.Cu")
	)
	(gr_circle
		(center 114.741452 -14.224)
		(end 115.630452 -14.224)
		(stroke
			(width 0.2)
			(type default)
		)
		(fill no)
		(layer "In3.Cu")
	)
	(gr_circle
		(center 115.503452 -73.66)
		(end 116.392452 -73.66)
		(stroke
			(width 0.2)
			(type default)
		)
		(fill no)
		(layer "In3.Cu")
	)
	(gr_circle
		(center 115.503452 -72.898)
		(end 116.392452 -72.898)
		(stroke
			(width 0.2)
			(type default)
		)
		(fill no)
		(layer "In3.Cu")
	)
	(gr_circle
		(center 115.503452 -72.136)
		(end 116.392452 -72.136)
		(stroke
			(width 0.2)
			(type default)
		)
		(fill no)
		(layer "In3.Cu")
	)
	(gr_circle
		(center 115.503452 -71.374)
		(end 116.392452 -71.374)
		(stroke
			(width 0.2)
			(type default)
		)
		(fill no)
		(layer "In3.Cu")
	)
	(gr_circle
		(center 115.503452 -70.612)
		(end 116.392452 -70.612)
		(stroke
			(width 0.2)
			(type default)
		)
		(fill no)
		(layer "In3.Cu")
	)
	(gr_circle
		(center 115.503452 -62.3824)
		(end 116.392452 -62.3824)
		(stroke
			(width 0.2)
			(type default)
		)
		(fill no)
		(layer "In3.Cu")
	)
	(gr_circle
		(center 115.503452 -61.6204)
		(end 116.392452 -61.6204)
		(stroke
			(width 0.2)
			(type default)
		)
		(fill no)
		(layer "In3.Cu")
	)
	(gr_circle
		(center 115.503452 -60.8584)
		(end 116.392452 -60.8584)
		(stroke
			(width 0.2)
			(type default)
		)
		(fill no)
		(layer "In3.Cu")
	)
	(gr_circle
		(center 115.503452 -60.0964)
		(end 116.392452 -60.0964)
		(stroke
			(width 0.2)
			(type default)
		)
		(fill no)
		(layer "In3.Cu")
	)
	(gr_circle
		(center 115.503452 -59.3344)
		(end 116.392452 -59.3344)
		(stroke
			(width 0.2)
			(type default)
		)
		(fill no)
		(layer "In3.Cu")
	)
	(gr_circle
		(center 115.503452 -51.1048)
		(end 116.392452 -51.1048)
		(stroke
			(width 0.2)
			(type default)
		)
		(fill no)
		(layer "In3.Cu")
	)
	(gr_circle
		(center 115.503452 -50.3428)
		(end 116.392452 -50.3428)
		(stroke
			(width 0.2)
			(type default)
		)
		(fill no)
		(layer "In3.Cu")
	)
	(gr_circle
		(center 115.503452 -49.5808)
		(end 116.392452 -49.5808)
		(stroke
			(width 0.2)
			(type default)
		)
		(fill no)
		(layer "In3.Cu")
	)
	(gr_circle
		(center 115.503452 -48.8188)
		(end 116.392452 -48.8188)
		(stroke
			(width 0.2)
			(type default)
		)
		(fill no)
		(layer "In3.Cu")
	)
	(gr_circle
		(center 115.503452 -48.0568)
		(end 116.392452 -48.0568)
		(stroke
			(width 0.2)
			(type default)
		)
		(fill no)
		(layer "In3.Cu")
	)
	(gr_circle
		(center 115.503452 -39.8272)
		(end 116.392452 -39.8272)
		(stroke
			(width 0.2)
			(type default)
		)
		(fill no)
		(layer "In3.Cu")
	)
	(gr_circle
		(center 115.503452 -39.0652)
		(end 116.392452 -39.0652)
		(stroke
			(width 0.2)
			(type default)
		)
		(fill no)
		(layer "In3.Cu")
	)
	(gr_circle
		(center 115.503452 -38.3032)
		(end 116.392452 -38.3032)
		(stroke
			(width 0.2)
			(type default)
		)
		(fill no)
		(layer "In3.Cu")
	)
	(gr_circle
		(center 115.503452 -37.5412)
		(end 116.392452 -37.5412)
		(stroke
			(width 0.2)
			(type default)
		)
		(fill no)
		(layer "In3.Cu")
	)
	(gr_circle
		(center 115.503452 -36.7792)
		(end 116.392452 -36.7792)
		(stroke
			(width 0.2)
			(type default)
		)
		(fill no)
		(layer "In3.Cu")
	)
	(gr_circle
		(center 115.503452 -28.5496)
		(end 116.392452 -28.5496)
		(stroke
			(width 0.2)
			(type default)
		)
		(fill no)
		(layer "In3.Cu")
	)
	(gr_circle
		(center 115.503452 -27.7876)
		(end 116.392452 -27.7876)
		(stroke
			(width 0.2)
			(type default)
		)
		(fill no)
		(layer "In3.Cu")
	)
	(gr_circle
		(center 115.503452 -27.0256)
		(end 116.392452 -27.0256)
		(stroke
			(width 0.2)
			(type default)
		)
		(fill no)
		(layer "In3.Cu")
	)
	(gr_circle
		(center 115.503452 -26.2636)
		(end 116.392452 -26.2636)
		(stroke
			(width 0.2)
			(type default)
		)
		(fill no)
		(layer "In3.Cu")
	)
	(gr_circle
		(center 115.503452 -25.5016)
		(end 116.392452 -25.5016)
		(stroke
			(width 0.2)
			(type default)
		)
		(fill no)
		(layer "In3.Cu")
	)
	(gr_circle
		(center 115.503452 -17.272)
		(end 116.392452 -17.272)
		(stroke
			(width 0.2)
			(type default)
		)
		(fill no)
		(layer "In3.Cu")
	)
	(gr_circle
		(center 115.503452 -16.51)
		(end 116.392452 -16.51)
		(stroke
			(width 0.2)
			(type default)
		)
		(fill no)
		(layer "In3.Cu")
	)
	(gr_circle
		(center 115.503452 -15.748)
		(end 116.392452 -15.748)
		(stroke
			(width 0.2)
			(type default)
		)
		(fill no)
		(layer "In3.Cu")
	)
	(gr_circle
		(center 115.503452 -14.986)
		(end 116.392452 -14.986)
		(stroke
			(width 0.2)
			(type default)
		)
		(fill no)
		(layer "In3.Cu")
	)
	(gr_circle
		(center 115.503452 -14.224)
		(end 116.392452 -14.224)
		(stroke
			(width 0.2)
			(type default)
		)
		(fill no)
		(layer "In3.Cu")
	)
	(gr_line
		(start 122.8344 -79.883)
		(end 123.4694 -80.518)
		(stroke
			(width 1.016)
			(type default)
		)
		(layer "In3.Cu")
	)
	(gr_line
		(start 122.8344 -46.863)
		(end 122.8344 -79.883)
		(stroke
			(width 1.016)
			(type default)
		)
		(layer "In3.Cu")
	)
	(gr_line
		(start 122.8344 -46.863)
		(end 122.8344 -13.081)
		(stroke
			(width 1.016)
			(type default)
		)
		(layer "In3.Cu")
	)
	(gr_line
		(start 122.8344 -13.081)
		(end 123.4694 -12.446)
		(stroke
			(width 1.016)
			(type default)
		)
		(layer "In3.Cu")
	)
	(gr_line
		(start 123.3424 -46.355)
		(end 122.8344 -46.863)
		(stroke
			(width 1.016)
			(type default)
		)
		(layer "In3.Cu")
	)
	(gr_line
		(start 123.3424 -46.355)
		(end 122.8344 -45.847)
		(stroke
			(width 1.016)
			(type default)
		)
		(layer "In3.Cu")
	)
	(gr_line
		(start 123.4694 -80.518)
		(end 136.23925 -80.518)
		(stroke
			(width 1.016)
			(type default)
		)
		(layer "In3.Cu")
	)
	(gr_line
		(start 136.23925 -80.518)
		(end 136.86663 -79.89062)
		(stroke
			(width 1.016)
			(type default)
		)
		(layer "In3.Cu")
	)
	(gr_line
		(start 136.86663 -79.89062)
		(end 136.86663 -68.303902)
		(stroke
			(width 1.016)
			(type default)
		)
		(layer "In3.Cu")
	)
	(gr_line
		(start 136.86663 -68.303902)
		(end 137.855706 -67.314826)
		(stroke
			(width 1.016)
			(type default)
		)
		(layer "In3.Cu")
	)
	(gr_line
		(start 137.855706 -67.314826)
		(end 148.668232 -67.314826)
		(stroke
			(width 1.016)
			(type default)
		)
		(layer "In3.Cu")
	)
	(gr_line
		(start 138.049 -38.862)
		(end 139.1666 -39.9796)
		(stroke
			(width 1.016)
			(type default)
		)
		(layer "In3.Cu")
	)
	(gr_line
		(start 138.049 -33.8328)
		(end 138.049 -38.862)
		(stroke
			(width 1.016)
			(type default)
		)
		(layer "In3.Cu")
	)
	(gr_line
		(start 138.2268 -38.2524)
		(end 147.066 -38.2524)
		(stroke
			(width 1.016)
			(type default)
		)
		(layer "In3.Cu")
	)
	(gr_line
		(start 138.2268 -37.6682)
		(end 147.066 -37.6682)
		(stroke
			(width 1.016)
			(type default)
		)
		(layer "In3.Cu")
	)
	(gr_line
		(start 138.2522 -37.0586)
		(end 147.0914 -37.0586)
		(stroke
			(width 1.016)
			(type default)
		)
		(layer "In3.Cu")
	)
	(gr_line
		(start 138.2522 -34.8742)
		(end 147.0914 -34.8742)
		(stroke
			(width 1.016)
			(type default)
		)
		(layer "In3.Cu")
	)
	(gr_line
		(start 138.2776 -36.3474)
		(end 147.1168 -36.3474)
		(stroke
			(width 1.016)
			(type default)
		)
		(layer "In3.Cu")
	)
	(gr_line
		(start 138.303 -35.6616)
		(end 147.1422 -35.6616)
		(stroke
			(width 1.016)
			(type default)
		)
		(layer "In3.Cu")
	)
	(gr_line
		(start 138.34872 -33.53308)
		(end 138.049 -33.8328)
		(stroke
			(width 1.016)
			(type default)
		)
		(layer "In3.Cu")
	)
	(gr_line
		(start 138.3538 -34.2392)
		(end 147.193 -34.2392)
		(stroke
			(width 1.016)
			(type default)
		)
		(layer "In3.Cu")
	)
	(gr_line
		(start 138.3792 -38.7604)
		(end 147.2184 -38.7604)
		(stroke
			(width 1.016)
			(type default)
		)
		(layer "In3.Cu")
	)
	(gr_line
		(start 138.6078 -34.2646)
		(end 138.6078 -39.2938)
		(stroke
			(width 1.016)
			(type default)
		)
		(layer "In3.Cu")
	)
	(gr_line
		(start 139.0904 -34.5694)
		(end 139.0904 -39.5986)
		(stroke
			(width 1.016)
			(type default)
		)
		(layer "In3.Cu")
	)
	(gr_line
		(start 139.1666 -39.9796)
		(end 141.7066 -39.9796)
		(stroke
			(width 1.016)
			(type default)
		)
		(layer "In3.Cu")
	)
	(gr_line
		(start 141.7066 -39.9796)
		(end 142.6464 -40.9194)
		(stroke
			(width 1.016)
			(type default)
		)
		(layer "In3.Cu")
	)
	(gr_line
		(start 141.8844 -12.446)
		(end 142.6464 -13.208)
		(stroke
			(width 1.016)
			(type default)
		)
		(layer "In3.Cu")
	)
	(gr_line
		(start 142.3924 -46.355)
		(end 123.3424 -46.355)
		(stroke
			(width 1.016)
			(type default)
		)
		(layer "In3.Cu")
	)
	(gr_line
		(start 142.3924 -46.355)
		(end 142.6464 -46.609)
		(stroke
			(width 1.016)
			(type default)
		)
		(layer "In3.Cu")
	)
	(gr_line
		(start 142.621 -32.6644)
		(end 141.5034 -33.782)
		(stroke
			(width 1.016)
			(type default)
		)
		(layer "In3.Cu")
	)
	(gr_line
		(start 142.621 -32.6644)
		(end 143.7386 -33.782)
		(stroke
			(width 1.016)
			(type default)
		)
		(layer "In3.Cu")
	)
	(gr_line
		(start 142.6464 -47.498)
		(end 141.5288 -46.3804)
		(stroke
			(width 1.016)
			(type default)
		)
		(layer "In3.Cu")
	)
	(gr_line
		(start 142.6464 -45.1612)
		(end 141.5288 -46.2788)
		(stroke
			(width 1.016)
			(type default)
		)
		(layer "In3.Cu")
	)
	(gr_line
		(start 142.6464 -33.909)
		(end 142.6464 -67.437)
		(stroke
			(width 1.016)
			(type default)
		)
		(layer "In3.Cu")
	)
	(gr_line
		(start 142.6464 -33.53308)
		(end 138.34872 -33.53308)
		(stroke
			(width 1.016)
			(type default)
		)
		(layer "In3.Cu")
	)
	(gr_line
		(start 142.6464 -33.53308)
		(end 147.35048 -33.53308)
		(stroke
			(width 1.016)
			(type default)
		)
		(layer "In3.Cu")
	)
	(gr_line
		(start 142.6464 -13.208)
		(end 142.6464 -33.53308)
		(stroke
			(width 1.016)
			(type default)
		)
		(layer "In3.Cu")
	)
	(gr_line
		(start 143.4084 -12.446)
		(end 142.6464 -13.208)
		(stroke
			(width 1.016)
			(type default)
		)
		(layer "In3.Cu")
	)
	(gr_circle
		(center 143.533114 -76.858368)
		(end 144.422114 -76.858368)
		(stroke
			(width 0.2)
			(type default)
		)
		(fill no)
		(layer "In3.Cu")
	)
	(gr_line
		(start 143.5862 -39.9796)
		(end 142.6464 -40.9194)
		(stroke
			(width 1.016)
			(type default)
		)
		(layer "In3.Cu")
	)
	(gr_line
		(start 144.4244 -39.3192)
		(end 139.3952 -39.3192)
		(stroke
			(width 1.016)
			(type default)
		)
		(layer "In3.Cu")
	)
	(gr_circle
		(center 144.892522 -76.886308)
		(end 145.781522 -76.886308)
		(stroke
			(width 0.2)
			(type default)
		)
		(fill no)
		(layer "In3.Cu")
	)
	(gr_line
		(start 145.5928 -39.8272)
		(end 140.5636 -39.8272)
		(stroke
			(width 1.016)
			(type default)
		)
		(layer "In3.Cu")
	)
	(gr_line
		(start 146.05 -34.544)
		(end 146.05 -39.5732)
		(stroke
			(width 1.016)
			(type default)
		)
		(layer "In3.Cu")
	)
	(gr_line
		(start 146.2024 -39.4208)
		(end 141.1732 -39.4208)
		(stroke
			(width 1.016)
			(type default)
		)
		(layer "In3.Cu")
	)
	(gr_line
		(start 146.2532 -39.9796)
		(end 143.5862 -39.9796)
		(stroke
			(width 1.016)
			(type default)
		)
		(layer "In3.Cu")
	)
	(gr_line
		(start 146.6596 -34.1884)
		(end 146.6596 -39.2176)
		(stroke
			(width 1.016)
			(type default)
		)
		(layer "In3.Cu")
	)
	(gr_line
		(start 147.2692 -33.8582)
		(end 147.2692 -38.8874)
		(stroke
			(width 1.016)
			(type default)
		)
		(layer "In3.Cu")
	)
	(gr_line
		(start 147.35048 -33.53308)
		(end 147.8534 -34.036)
		(stroke
			(width 1.016)
			(type default)
		)
		(layer "In3.Cu")
	)
	(gr_line
		(start 147.8534 -38.3794)
		(end 146.2532 -39.9796)
		(stroke
			(width 1.016)
			(type default)
		)
		(layer "In3.Cu")
	)
	(gr_line
		(start 147.8534 -34.036)
		(end 147.8534 -38.3794)
		(stroke
			(width 1.016)
			(type default)
		)
		(layer "In3.Cu")
	)
	(gr_line
		(start 148.668232 -67.314826)
		(end 160.61309 -55.369968)
		(stroke
			(width 1.016)
			(type default)
		)
		(layer "In3.Cu")
	)
	(gr_circle
		(center 150.033736 -79.7052)
		(end 150.922736 -79.7052)
		(stroke
			(width 0.2)
			(type default)
		)
		(fill no)
		(layer "In3.Cu")
	)
	(gr_circle
		(center 150.033736 -78.9432)
		(end 150.922736 -78.9432)
		(stroke
			(width 0.2)
			(type default)
		)
		(fill no)
		(layer "In3.Cu")
	)
	(gr_circle
		(center 150.801832 -60.917582)
		(end 151.690832 -60.917582)
		(stroke
			(width 0.2)
			(type default)
		)
		(fill no)
		(layer "In3.Cu")
	)
	(gr_circle
		(center 151.563832 -60.917582)
		(end 152.452832 -60.917582)
		(stroke
			(width 0.2)
			(type default)
		)
		(fill no)
		(layer "In3.Cu")
	)
	(gr_line
		(start 156.980382 -12.446)
		(end 123.4694 -12.446)
		(stroke
			(width 1.016)
			(type default)
		)
		(layer "In3.Cu")
	)
	(gr_circle
		(center 158.369 -96.266)
		(end 159.258 -96.266)
		(stroke
			(width 0.2)
			(type default)
		)
		(fill no)
		(layer "In3.Cu")
	)
	(gr_circle
		(center 160.575244 -86.084918)
		(end 161.464244 -86.084918)
		(stroke
			(width 0.2)
			(type default)
		)
		(fill no)
		(layer "In3.Cu")
	)
	(gr_line
		(start 160.61309 -55.369968)
		(end 175.611282 -55.369968)
		(stroke
			(width 1.016)
			(type default)
		)
		(layer "In3.Cu")
	)
	(gr_line
		(start 160.6804 -27.182318)
		(end 161.946082 -28.448)
		(stroke
			(width 1.016)
			(type default)
		)
		(layer "In3.Cu")
	)
	(gr_line
		(start 160.6804 -16.146018)
		(end 156.980382 -12.446)
		(stroke
			(width 1.016)
			(type default)
		)
		(layer "In3.Cu")
	)
	(gr_line
		(start 160.6804 -16.146018)
		(end 160.6804 -27.182318)
		(stroke
			(width 1.016)
			(type default)
		)
		(layer "In3.Cu")
	)
	(gr_line
		(start 161.946082 -28.448)
		(end 209.1944 -28.448)
		(stroke
			(width 1.016)
			(type default)
		)
		(layer "In3.Cu")
	)
	(gr_circle
		(center 166.5224 -60.3758)
		(end 167.4114 -60.3758)
		(stroke
			(width 0.2)
			(type default)
		)
		(fill no)
		(layer "In3.Cu")
	)
	(gr_circle
		(center 167.2844 -60.3758)
		(end 168.1734 -60.3758)
		(stroke
			(width 0.2)
			(type default)
		)
		(fill no)
		(layer "In3.Cu")
	)
	(gr_line
		(start 172.174662 -50.696622)
		(end 172.174662 -43.570398)
		(stroke
			(width 1.016)
			(type default)
		)
		(layer "In3.Cu")
	)
	(gr_line
		(start 172.174662 -43.570398)
		(end 173.915832 -41.829228)
		(stroke
			(width 1.016)
			(type default)
		)
		(layer "In3.Cu")
	)
	(gr_line
		(start 172.583348 -51.105308)
		(end 172.174662 -50.696622)
		(stroke
			(width 1.016)
			(type default)
		)
		(layer "In3.Cu")
	)
	(gr_line
		(start 173.915832 -41.829228)
		(end 191.747394 -41.829228)
		(stroke
			(width 1.016)
			(type default)
		)
		(layer "In3.Cu")
	)
	(gr_line
		(start 173.980348 -51.105308)
		(end 172.583348 -51.105308)
		(stroke
			(width 1.016)
			(type default)
		)
		(layer "In3.Cu")
	)
	(gr_circle
		(center 174.9044 -82.296)
		(end 175.7934 -82.296)
		(stroke
			(width 0.2)
			(type default)
		)
		(fill no)
		(layer "In3.Cu")
	)
	(gr_line
		(start 175.611282 -55.369968)
		(end 176.302162 -54.679088)
		(stroke
			(width 1.016)
			(type default)
		)
		(layer "In3.Cu")
	)
	(gr_circle
		(center 175.6664 -82.296)
		(end 176.5554 -82.296)
		(stroke
			(width 0.2)
			(type default)
		)
		(fill no)
		(layer "In3.Cu")
	)
	(gr_line
		(start 176.302162 -54.679088)
		(end 176.302162 -53.427122)
		(stroke
			(width 1.016)
			(type default)
		)
		(layer "In3.Cu")
	)
	(gr_line
		(start 176.302162 -53.427122)
		(end 173.980348 -51.105308)
		(stroke
			(width 1.016)
			(type default)
		)
		(layer "In3.Cu")
	)
	(gr_circle
		(center 177.1904 -82.296)
		(end 178.0794 -82.296)
		(stroke
			(width 0.2)
			(type default)
		)
		(fill no)
		(layer "In3.Cu")
	)
	(gr_circle
		(center 177.9524 -82.296)
		(end 178.8414 -82.296)
		(stroke
			(width 0.2)
			(type default)
		)
		(fill no)
		(layer "In3.Cu")
	)
	(gr_circle
		(center 178.87696 -46.99)
		(end 179.76596 -46.99)
		(stroke
			(width 0.2)
			(type default)
		)
		(fill no)
		(layer "In3.Cu")
	)
	(gr_line
		(start 182.1434 -50.894996)
		(end 182.1434 -50.419)
		(stroke
			(width 1.016)
			(type default)
		)
		(layer "In3.Cu")
	)
	(gr_line
		(start 182.1434 -50.419)
		(end 182.1434 -47.879)
		(stroke
			(width 1.016)
			(type default)
		)
		(layer "In3.Cu")
	)
	(gr_line
		(start 182.1434 -47.879)
		(end 182.1434 -46.609)
		(stroke
			(width 1.016)
			(type default)
		)
		(layer "In3.Cu")
	)
	(gr_line
		(start 182.1434 -46.609)
		(end 185.8264 -42.926)
		(stroke
			(width 1.016)
			(type default)
		)
		(layer "In3.Cu")
	)
	(gr_circle
		(center 182.215536 -69.4436)
		(end 183.104536 -69.4436)
		(stroke
			(width 0.2)
			(type default)
		)
		(fill no)
		(layer "In3.Cu")
	)
	(gr_line
		(start 182.815484 -51.56708)
		(end 182.1434 -50.894996)
		(stroke
			(width 1.016)
			(type default)
		)
		(layer "In3.Cu")
	)
	(gr_circle
		(center 184.8104 -68.58)
		(end 185.6994 -68.58)
		(stroke
			(width 0.2)
			(type default)
		)
		(fill no)
		(layer "In3.Cu")
	)
	(gr_circle
		(center 185.5724 -68.58)
		(end 186.4614 -68.58)
		(stroke
			(width 0.2)
			(type default)
		)
		(fill no)
		(layer "In3.Cu")
	)
	(gr_line
		(start 185.8264 -42.926)
		(end 189.847982 -42.926)
		(stroke
			(width 1.016)
			(type default)
		)
		(layer "In3.Cu")
	)
	(gr_line
		(start 189.847982 -42.926)
		(end 193.576448 -46.654466)
		(stroke
			(width 1.016)
			(type default)
		)
		(layer "In3.Cu")
	)
	(gr_line
		(start 191.747394 -41.829228)
		(end 197.797166 -47.879)
		(stroke
			(width 1.016)
			(type default)
		)
		(layer "In3.Cu")
	)
	(gr_line
		(start 193.031618 -51.56708)
		(end 182.815484 -51.56708)
		(stroke
			(width 1.016)
			(type default)
		)
		(layer "In3.Cu")
	)
	(gr_line
		(start 193.576448 -51.02225)
		(end 193.031618 -51.56708)
		(stroke
			(width 1.016)
			(type default)
		)
		(layer "In3.Cu")
	)
	(gr_line
		(start 193.576448 -47.879)
		(end 193.576448 -51.02225)
		(stroke
			(width 1.016)
			(type default)
		)
		(layer "In3.Cu")
	)
	(gr_line
		(start 193.576448 -46.654466)
		(end 193.576448 -47.879)
		(stroke
			(width 1.016)
			(type default)
		)
		(layer "In3.Cu")
	)
	(gr_line
		(start 197.797166 -47.879)
		(end 210.0834 -47.879)
		(stroke
			(width 1.016)
			(type default)
		)
		(layer "In3.Cu")
	)
	(gr_circle
		(center 208.810098 -51.049936)
		(end 210.20913 -51.049936)
		(stroke
			(width 0.2)
			(type default)
		)
		(fill no)
		(layer "In3.Cu")
	)
	(gr_line
		(start 209.1944 -28.448)
		(end 210.9724 -30.226)
		(stroke
			(width 1.016)
			(type default)
		)
		(layer "In3.Cu")
	)
	(gr_line
		(start 210.9724 -46.99)
		(end 210.0834 -47.879)
		(stroke
			(width 1.016)
			(type default)
		)
		(layer "In3.Cu")
	)
	(gr_line
		(start 210.9724 -30.226)
		(end 210.9724 -46.99)
		(stroke
			(width 1.016)
			(type default)
		)
		(layer "In3.Cu")
	)
	(gr_line
		(start 229.362 -46.99)
		(end 230.251 -47.879)
		(stroke
			(width 1.016)
			(type default)
		)
		(layer "In3.Cu")
	)
	(gr_line
		(start 229.362 -30.226)
		(end 229.362 -46.99)
		(stroke
			(width 1.016)
			(type default)
		)
		(layer "In3.Cu")
	)
	(gr_line
		(start 230.251 -47.879)
		(end 242.963954 -47.879)
		(stroke
			(width 1.016)
			(type default)
		)
		(layer "In3.Cu")
	)
	(gr_line
		(start 231.14 -28.448)
		(end 229.362 -30.226)
		(stroke
			(width 1.016)
			(type default)
		)
		(layer "In3.Cu")
	)
	(gr_circle
		(center 238.810038 -51.049936)
		(end 240.20907 -51.049936)
		(stroke
			(width 0.2)
			(type default)
		)
		(fill no)
		(layer "In3.Cu")
	)
	(gr_line
		(start 242.963954 -47.879)
		(end 248.993406 -41.849548)
		(stroke
			(width 1.016)
			(type default)
		)
		(layer "In3.Cu")
	)
	(gr_line
		(start 246.757952 -51.02225)
		(end 247.302782 -51.56708)
		(stroke
			(width 1.016)
			(type default)
		)
		(layer "In3.Cu")
	)
	(gr_line
		(start 246.757952 -47.879)
		(end 246.757952 -51.02225)
		(stroke
			(width 1.016)
			(type default)
		)
		(layer "In3.Cu")
	)
	(gr_line
		(start 246.757952 -46.654466)
		(end 246.757952 -47.879)
		(stroke
			(width 1.016)
			(type default)
		)
		(layer "In3.Cu")
	)
	(gr_line
		(start 246.757952 -46.654466)
		(end 250.867418 -42.545)
		(stroke
			(width 1.016)
			(type default)
		)
		(layer "In3.Cu")
	)
	(gr_line
		(start 247.302782 -51.56708)
		(end 257.518916 -51.56708)
		(stroke
			(width 1.016)
			(type default)
		)
		(layer "In3.Cu")
	)
	(gr_line
		(start 248.993406 -41.849548)
		(end 255.891538 -41.849548)
		(stroke
			(width 1.016)
			(type default)
		)
		(layer "In3.Cu")
	)
	(gr_line
		(start 250.486418 -42.926)
		(end 246.757952 -46.654466)
		(stroke
			(width 1.016)
			(type default)
		)
		(layer "In3.Cu")
	)
	(gr_line
		(start 250.867418 -42.545)
		(end 256.07899 -42.545)
		(stroke
			(width 1.016)
			(type default)
		)
		(layer "In3.Cu")
	)
	(gr_line
		(start 254.508 -42.926)
		(end 250.486418 -42.926)
		(stroke
			(width 1.016)
			(type default)
		)
		(layer "In3.Cu")
	)
	(gr_line
		(start 254.508 -42.926)
		(end 258.191 -46.609)
		(stroke
			(width 1.016)
			(type default)
		)
		(layer "In3.Cu")
	)
	(gr_line
		(start 255.383538 -41.849548)
		(end 258.11099 -44.577)
		(stroke
			(width 1.016)
			(type default)
		)
		(layer "In3.Cu")
	)
	(gr_line
		(start 255.397 -42.926)
		(end 250.486418 -42.926)
		(stroke
			(width 1.016)
			(type default)
		)
		(layer "In3.Cu")
	)
	(gr_line
		(start 255.891538 -41.849548)
		(end 258.61899 -44.577)
		(stroke
			(width 1.016)
			(type default)
		)
		(layer "In3.Cu")
	)
	(gr_line
		(start 257.518916 -51.56708)
		(end 258.191 -50.894996)
		(stroke
			(width 1.016)
			(type default)
		)
		(layer "In3.Cu")
	)
	(gr_line
		(start 257.556 -45.085)
		(end 255.397 -42.926)
		(stroke
			(width 1.016)
			(type default)
		)
		(layer "In3.Cu")
	)
	(gr_line
		(start 257.823716 -45.426884)
		(end 258.4958 -44.7548)
		(stroke
			(width 1.016)
			(type default)
		)
		(layer "In3.Cu")
	)
	(gr_line
		(start 258.191 -50.894996)
		(end 258.191 -50.419)
		(stroke
			(width 1.016)
			(type default)
		)
		(layer "In3.Cu")
	)
	(gr_line
		(start 258.191 -50.419)
		(end 258.191 -47.879)
		(stroke
			(width 1.016)
			(type default)
		)
		(layer "In3.Cu")
	)
	(gr_line
		(start 258.191 -47.879)
		(end 258.191 -46.609)
		(stroke
			(width 1.016)
			(type default)
		)
		(layer "In3.Cu")
	)
	(gr_line
		(start 258.191 -46.609)
		(end 254.508 -42.926)
		(stroke
			(width 1.016)
			(type default)
		)
		(layer "In3.Cu")
	)
	(gr_line
		(start 258.191 -46.609)
		(end 258.191 -45.72)
		(stroke
			(width 1.016)
			(type default)
		)
		(layer "In3.Cu")
	)
	(gr_line
		(start 258.191 -45.72)
		(end 257.556 -45.085)
		(stroke
			(width 1.016)
			(type default)
		)
		(layer "In3.Cu")
	)
	(gr_line
		(start 258.230116 -45.452284)
		(end 258.9022 -44.7802)
		(stroke
			(width 1.016)
			(type default)
		)
		(layer "In3.Cu")
	)
	(gr_line
		(start 258.61899 -44.577)
		(end 268.097 -44.577)
		(stroke
			(width 1.016)
			(type default)
		)
		(layer "In3.Cu")
	)
	(gr_circle
		(center 260.2484 -46.99)
		(end 261.1374 -46.99)
		(stroke
			(width 0.2)
			(type default)
		)
		(fill no)
		(layer "In3.Cu")
	)
	(gr_circle
		(center 261.493 -71.5772)
		(end 262.382 -71.5772)
		(stroke
			(width 0.2)
			(type default)
		)
		(fill no)
		(layer "In3.Cu")
	)
	(gr_line
		(start 261.6708 -44.577)
		(end 256.3368 -44.577)
		(stroke
			(width 1.016)
			(type default)
		)
		(layer "In3.Cu")
	)
	(gr_circle
		(center 262.255 -71.5772)
		(end 263.144 -71.5772)
		(stroke
			(width 0.2)
			(type default)
		)
		(fill no)
		(layer "In3.Cu")
	)
	(gr_circle
		(center 265.4046 -70.7644)
		(end 266.2936 -70.7644)
		(stroke
			(width 0.2)
			(type default)
		)
		(fill no)
		(layer "In3.Cu")
	)
	(gr_line
		(start 268.097 -44.577)
		(end 282.2448 -58.7248)
		(stroke
			(width 1.016)
			(type default)
		)
		(layer "In3.Cu")
	)
	(gr_circle
		(center 269.6464 -57.912)
		(end 270.5354 -57.912)
		(stroke
			(width 0.2)
			(type default)
		)
		(fill no)
		(layer "In3.Cu")
	)
	(gr_circle
		(center 270.0782 -86.233)
		(end 270.9672 -86.233)
		(stroke
			(width 0.2)
			(type default)
		)
		(fill no)
		(layer "In3.Cu")
	)
	(gr_circle
		(center 270.4084 -57.912)
		(end 271.2974 -57.912)
		(stroke
			(width 0.2)
			(type default)
		)
		(fill no)
		(layer "In3.Cu")
	)
	(gr_circle
		(center 270.7132 -86.233)
		(end 271.6022 -86.233)
		(stroke
			(width 0.2)
			(type default)
		)
		(fill no)
		(layer "In3.Cu")
	)
	(gr_circle
		(center 271.9324 -57.912)
		(end 272.8214 -57.912)
		(stroke
			(width 0.2)
			(type default)
		)
		(fill no)
		(layer "In3.Cu")
	)
	(gr_circle
		(center 272.1102 -86.233)
		(end 272.9992 -86.233)
		(stroke
			(width 0.2)
			(type default)
		)
		(fill no)
		(layer "In3.Cu")
	)
	(gr_circle
		(center 272.6944 -57.912)
		(end 273.5834 -57.912)
		(stroke
			(width 0.2)
			(type default)
		)
		(fill no)
		(layer "In3.Cu")
	)
	(gr_circle
		(center 272.7452 -86.233)
		(end 273.6342 -86.233)
		(stroke
			(width 0.2)
			(type default)
		)
		(fill no)
		(layer "In3.Cu")
	)
	(gr_circle
		(center 274.1422 -86.233)
		(end 275.0312 -86.233)
		(stroke
			(width 0.2)
			(type default)
		)
		(fill no)
		(layer "In3.Cu")
	)
	(gr_circle
		(center 274.7772 -86.233)
		(end 275.6662 -86.233)
		(stroke
			(width 0.2)
			(type default)
		)
		(fill no)
		(layer "In3.Cu")
	)
	(gr_circle
		(center 276.0472 -86.233)
		(end 276.9362 -86.233)
		(stroke
			(width 0.2)
			(type default)
		)
		(fill no)
		(layer "In3.Cu")
	)
	(gr_circle
		(center 276.6822 -86.233)
		(end 277.5712 -86.233)
		(stroke
			(width 0.2)
			(type default)
		)
		(fill no)
		(layer "In3.Cu")
	)
	(gr_line
		(start 278.388318 -28.448)
		(end 231.14 -28.448)
		(stroke
			(width 1.016)
			(type default)
		)
		(layer "In3.Cu")
	)
	(gr_line
		(start 279.654 -27.182318)
		(end 278.388318 -28.448)
		(stroke
			(width 1.016)
			(type default)
		)
		(layer "In3.Cu")
	)
	(gr_line
		(start 279.654 -16.146018)
		(end 279.654 -27.182318)
		(stroke
			(width 1.016)
			(type default)
		)
		(layer "In3.Cu")
	)
	(gr_circle
		(center 280.329894 -78.1558)
		(end 281.218894 -78.1558)
		(stroke
			(width 0.2)
			(type default)
		)
		(fill no)
		(layer "In3.Cu")
	)
	(gr_circle
		(center 281.091894 -78.1558)
		(end 281.980894 -78.1558)
		(stroke
			(width 0.2)
			(type default)
		)
		(fill no)
		(layer "In3.Cu")
	)
	(gr_line
		(start 282.2448 -58.7248)
		(end 293.4208 -58.7248)
		(stroke
			(width 1.016)
			(type default)
		)
		(layer "In3.Cu")
	)
	(gr_line
		(start 283.354018 -12.446)
		(end 279.654 -16.146018)
		(stroke
			(width 1.016)
			(type default)
		)
		(layer "In3.Cu")
	)
	(gr_line
		(start 293.4208 -58.7248)
		(end 296.7228 -62.0268)
		(stroke
			(width 1.016)
			(type default)
		)
		(layer "In3.Cu")
	)
	(gr_line
		(start 296.7228 -65.7098)
		(end 298.35729 -67.34429)
		(stroke
			(width 1.016)
			(type default)
		)
		(layer "In3.Cu")
	)
	(gr_line
		(start 296.7228 -62.0268)
		(end 296.7228 -65.7098)
		(stroke
			(width 1.016)
			(type default)
		)
		(layer "In3.Cu")
	)
	(gr_circle
		(center 297.9928 -80.391)
		(end 298.8818 -80.391)
		(stroke
			(width 0.2)
			(type default)
		)
		(fill no)
		(layer "In3.Cu")
	)
	(gr_circle
		(center 298.069 -75.819)
		(end 298.958 -75.819)
		(stroke
			(width 0.2)
			(type default)
		)
		(fill no)
		(layer "In3.Cu")
	)
	(gr_line
		(start 298.35729 -67.34429)
		(end 309.808372 -67.34429)
		(stroke
			(width 1.016)
			(type default)
		)
		(layer "In3.Cu")
	)
	(gr_circle
		(center 298.7548 -80.391)
		(end 299.6438 -80.391)
		(stroke
			(width 0.2)
			(type default)
		)
		(fill no)
		(layer "In3.Cu")
	)
	(gr_line
		(start 299.168312 -38.996112)
		(end 300.6852 -40.513)
		(stroke
			(width 1.016)
			(type default)
		)
		(layer "In3.Cu")
	)
	(gr_line
		(start 299.168312 -33.576768)
		(end 299.168312 -38.996112)
		(stroke
			(width 1.016)
			(type default)
		)
		(layer "In3.Cu")
	)
	(gr_line
		(start 299.265086 -33.479994)
		(end 299.168312 -33.576768)
		(stroke
			(width 1.016)
			(type default)
		)
		(layer "In3.Cu")
	)
	(gr_line
		(start 300.446694 -34.461958)
		(end 300.126654 -34.781998)
		(stroke
			(width 2.54)
			(type default)
		)
		(layer "In3.Cu")
	)
	(gr_line
		(start 300.6852 -40.513)
		(end 303.4792 -40.513)
		(stroke
			(width 1.016)
			(type default)
		)
		(layer "In3.Cu")
	)
	(gr_line
		(start 302.078136 -36.06165)
		(end 301.822104 -36.317682)
		(stroke
			(width 2.54)
			(type default)
		)
		(layer "In3.Cu")
	)
	(gr_line
		(start 303.101756 -37.821108)
		(end 303.069752 -37.853112)
		(stroke
			(width 2.54)
			(type default)
		)
		(layer "In3.Cu")
	)
	(gr_line
		(start 303.391316 -40.2844)
		(end 305.5366 -40.2844)
		(stroke
			(width 1.016)
			(type default)
		)
		(layer "In3.Cu")
	)
	(gr_line
		(start 303.4792 -40.513)
		(end 304.8 -41.8338)
		(stroke
			(width 1.016)
			(type default)
		)
		(layer "In3.Cu")
	)
	(gr_line
		(start 304.038 -12.446)
		(end 304.8 -13.208)
		(stroke
			(width 1.016)
			(type default)
		)
		(layer "In3.Cu")
	)
	(gr_circle
		(center 304.070258 -79.823056)
		(end 304.959258 -79.823056)
		(stroke
			(width 0.2)
			(type default)
		)
		(fill no)
		(layer "In3.Cu")
	)
	(gr_line
		(start 304.546 -39.053516)
		(end 304.546 -41.1988)
		(stroke
			(width 1.016)
			(type default)
		)
		(layer "In3.Cu")
	)
	(gr_line
		(start 304.779934 -32.938466)
		(end 303.7586 -33.9598)
		(stroke
			(width 1.016)
			(type default)
		)
		(layer "In3.Cu")
	)
	(gr_line
		(start 304.794666 -32.938466)
		(end 305.816 -33.9598)
		(stroke
			(width 1.016)
			(type default)
		)
		(layer "In3.Cu")
	)
	(gr_line
		(start 304.799238 -66.396362)
		(end 303.8856 -67.31)
		(stroke
			(width 1.016)
			(type default)
		)
		(layer "In3.Cu")
	)
	(gr_line
		(start 304.8 -67.065144)
		(end 305.079146 -67.34429)
		(stroke
			(width 1.016)
			(type default)
		)
		(layer "In3.Cu")
	)
	(gr_line
		(start 304.8 -47.4218)
		(end 304.8 -41.3258)
		(stroke
			(width 1.016)
			(type default)
		)
		(layer "In3.Cu")
	)
	(gr_line
		(start 304.8 -46.609)
		(end 304.8 -67.065144)
		(stroke
			(width 1.016)
			(type default)
		)
		(layer "In3.Cu")
	)
	(gr_line
		(start 304.8 -33.479994)
		(end 299.265086 -33.479994)
		(stroke
			(width 1.016)
			(type default)
		)
		(layer "In3.Cu")
	)
	(gr_line
		(start 304.8 -33.479994)
		(end 309.723028 -33.479994)
		(stroke
			(width 1.016)
			(type default)
		)
		(layer "In3.Cu")
	)
	(gr_line
		(start 304.8 -13.208)
		(end 304.8 -33.479994)
		(stroke
			(width 1.016)
			(type default)
		)
		(layer "In3.Cu")
	)
	(gr_line
		(start 304.826162 -66.370962)
		(end 305.7398 -67.2846)
		(stroke
			(width 1.016)
			(type default)
		)
		(layer "In3.Cu")
	)
	(gr_line
		(start 304.8508 -47.1678)
		(end 305.6636 -46.355)
		(stroke
			(width 1.016)
			(type default)
		)
		(layer "In3.Cu")
	)
	(gr_circle
		(center 305.063398 -81.003648)
		(end 305.952398 -81.003648)
		(stroke
			(width 0.2)
			(type default)
		)
		(fill no)
		(layer "In3.Cu")
	)
	(gr_line
		(start 305.562 -12.446)
		(end 304.8 -13.208)
		(stroke
			(width 1.016)
			(type default)
		)
		(layer "In3.Cu")
	)
	(gr_line
		(start 305.6128 -40.513)
		(end 304.8 -41.3258)
		(stroke
			(width 1.016)
			(type default)
		)
		(layer "In3.Cu")
	)
	(gr_line
		(start 305.6636 -46.2534)
		(end 304.8508 -45.4406)
		(stroke
			(width 1.016)
			(type default)
		)
		(layer "In3.Cu")
	)
	(gr_line
		(start 306.076858 -37.821108)
		(end 303.101756 -37.821108)
		(stroke
			(width 2.54)
			(type default)
		)
		(layer "In3.Cu")
	)
	(gr_line
		(start 306.17287 -37.91712)
		(end 306.076858 -37.821108)
		(stroke
			(width 2.54)
			(type default)
		)
		(layer "In3.Cu")
	)
	(gr_line
		(start 307.388514 -36.06165)
		(end 302.078136 -36.06165)
		(stroke
			(width 2.54)
			(type default)
		)
		(layer "In3.Cu")
	)
	(gr_line
		(start 307.836316 -36.509452)
		(end 307.388514 -36.06165)
		(stroke
			(width 2.54)
			(type default)
		)
		(layer "In3.Cu")
	)
	(gr_line
		(start 308.3052 -37.5412)
		(end 300.083728 -37.5412)
		(stroke
			(width 2.54)
			(type default)
		)
		(layer "In3.Cu")
	)
	(gr_line
		(start 308.3306 -36.068)
		(end 300.109128 -36.068)
		(stroke
			(width 2.54)
			(type default)
		)
		(layer "In3.Cu")
	)
	(gr_line
		(start 308.5592 -38.7858)
		(end 300.337728 -38.7858)
		(stroke
			(width 2.54)
			(type default)
		)
		(layer "In3.Cu")
	)
	(gr_line
		(start 308.668166 -34.461958)
		(end 300.446694 -34.461958)
		(stroke
			(width 2.54)
			(type default)
		)
		(layer "In3.Cu")
	)
	(gr_line
		(start 309.1688 -39.2938)
		(end 300.947328 -39.2938)
		(stroke
			(width 2.54)
			(type default)
		)
		(layer "In3.Cu")
	)
	(gr_line
		(start 309.2704 -40.513)
		(end 305.6128 -40.513)
		(stroke
			(width 1.016)
			(type default)
		)
		(layer "In3.Cu")
	)
	(gr_line
		(start 309.448962 -34.323528)
		(end 309.448962 -38.861238)
		(stroke
			(width 1.016)
			(type default)
		)
		(layer "In3.Cu")
	)
	(gr_line
		(start 309.627778 -35.42157)
		(end 308.668166 -34.461958)
		(stroke
			(width 2.54)
			(type default)
		)
		(layer "In3.Cu")
	)
	(gr_line
		(start 309.723028 -33.479994)
		(end 310.744362 -34.501328)
		(stroke
			(width 1.016)
			(type default)
		)
		(layer "In3.Cu")
	)
	(gr_line
		(start 309.804562 -34.425128)
		(end 309.804562 -38.962838)
		(stroke
			(width 1.016)
			(type default)
		)
		(layer "In3.Cu")
	)
	(gr_line
		(start 309.808372 -67.34429)
		(end 310.72201 -68.257928)
		(stroke
			(width 1.016)
			(type default)
		)
		(layer "In3.Cu")
	)
	(gr_line
		(start 310.236362 -34.501328)
		(end 310.236362 -39.039038)
		(stroke
			(width 1.016)
			(type default)
		)
		(layer "In3.Cu")
	)
	(gr_line
		(start 310.72201 -79.844646)
		(end 311.395364 -80.518)
		(stroke
			(width 1.016)
			(type default)
		)
		(layer "In3.Cu")
	)
	(gr_line
		(start 310.72201 -68.257928)
		(end 310.72201 -79.844646)
		(stroke
			(width 1.016)
			(type default)
		)
		(layer "In3.Cu")
	)
	(gr_line
		(start 310.744362 -39.039038)
		(end 309.2704 -40.513)
		(stroke
			(width 1.016)
			(type default)
		)
		(layer "In3.Cu")
	)
	(gr_line
		(start 310.744362 -34.501328)
		(end 310.744362 -39.039038)
		(stroke
			(width 1.016)
			(type default)
		)
		(layer "In3.Cu")
	)
	(gr_line
		(start 311.395364 -80.518)
		(end 323.977 -80.518)
		(stroke
			(width 1.016)
			(type default)
		)
		(layer "In3.Cu")
	)
	(gr_line
		(start 323.977 -80.518)
		(end 324.612 -79.883)
		(stroke
			(width 1.016)
			(type default)
		)
		(layer "In3.Cu")
	)
	(gr_line
		(start 323.977 -12.446)
		(end 283.354018 -12.446)
		(stroke
			(width 1.016)
			(type default)
		)
		(layer "In3.Cu")
	)
	(gr_line
		(start 324.104 -46.355)
		(end 305.0032 -46.355)
		(stroke
			(width 1.016)
			(type default)
		)
		(layer "In3.Cu")
	)
	(gr_line
		(start 324.104 -46.355)
		(end 324.612 -45.847)
		(stroke
			(width 1.016)
			(type default)
		)
		(layer "In3.Cu")
	)
	(gr_line
		(start 324.612 -79.883)
		(end 324.612 -46.863)
		(stroke
			(width 1.016)
			(type default)
		)
		(layer "In3.Cu")
	)
	(gr_line
		(start 324.612 -46.863)
		(end 324.104 -46.355)
		(stroke
			(width 1.016)
			(type default)
		)
		(layer "In3.Cu")
	)
	(gr_line
		(start 324.612 -46.863)
		(end 324.612 -13.081)
		(stroke
			(width 1.016)
			(type default)
		)
		(layer "In3.Cu")
	)
	(gr_line
		(start 324.612 -13.081)
		(end 323.977 -12.446)
		(stroke
			(width 1.016)
			(type default)
		)
		(layer "In3.Cu")
	)
	(gr_circle
		(center 332.1558 -79.4766)
		(end 333.0448 -79.4766)
		(stroke
			(width 0.2)
			(type default)
		)
		(fill no)
		(layer "In3.Cu")
	)
	(gr_circle
		(center 332.1558 -78.7146)
		(end 333.0448 -78.7146)
		(stroke
			(width 0.2)
			(type default)
		)
		(fill no)
		(layer "In3.Cu")
	)
	(gr_circle
		(center 332.1558 -77.9526)
		(end 333.0448 -77.9526)
		(stroke
			(width 0.2)
			(type default)
		)
		(fill no)
		(layer "In3.Cu")
	)
	(gr_circle
		(center 332.1558 -77.1906)
		(end 333.0448 -77.1906)
		(stroke
			(width 0.2)
			(type default)
		)
		(fill no)
		(layer "In3.Cu")
	)
	(gr_circle
		(center 332.1558 -76.4286)
		(end 333.0448 -76.4286)
		(stroke
			(width 0.2)
			(type default)
		)
		(fill no)
		(layer "In3.Cu")
	)
	(gr_circle
		(center 332.1558 -68.199)
		(end 333.0448 -68.199)
		(stroke
			(width 0.2)
			(type default)
		)
		(fill no)
		(layer "In3.Cu")
	)
	(gr_circle
		(center 332.1558 -67.437)
		(end 333.0448 -67.437)
		(stroke
			(width 0.2)
			(type default)
		)
		(fill no)
		(layer "In3.Cu")
	)
	(gr_circle
		(center 332.1558 -66.675)
		(end 333.0448 -66.675)
		(stroke
			(width 0.2)
			(type default)
		)
		(fill no)
		(layer "In3.Cu")
	)
	(gr_circle
		(center 332.1558 -65.913)
		(end 333.0448 -65.913)
		(stroke
			(width 0.2)
			(type default)
		)
		(fill no)
		(layer "In3.Cu")
	)
	(gr_circle
		(center 332.1558 -65.151)
		(end 333.0448 -65.151)
		(stroke
			(width 0.2)
			(type default)
		)
		(fill no)
		(layer "In3.Cu")
	)
	(gr_circle
		(center 332.1558 -56.9214)
		(end 333.0448 -56.9214)
		(stroke
			(width 0.2)
			(type default)
		)
		(fill no)
		(layer "In3.Cu")
	)
	(gr_circle
		(center 332.1558 -56.1594)
		(end 333.0448 -56.1594)
		(stroke
			(width 0.2)
			(type default)
		)
		(fill no)
		(layer "In3.Cu")
	)
	(gr_circle
		(center 332.1558 -55.3974)
		(end 333.0448 -55.3974)
		(stroke
			(width 0.2)
			(type default)
		)
		(fill no)
		(layer "In3.Cu")
	)
	(gr_circle
		(center 332.1558 -54.6354)
		(end 333.0448 -54.6354)
		(stroke
			(width 0.2)
			(type default)
		)
		(fill no)
		(layer "In3.Cu")
	)
	(gr_circle
		(center 332.1558 -53.8734)
		(end 333.0448 -53.8734)
		(stroke
			(width 0.2)
			(type default)
		)
		(fill no)
		(layer "In3.Cu")
	)
	(gr_circle
		(center 332.1558 -45.6438)
		(end 333.0448 -45.6438)
		(stroke
			(width 0.2)
			(type default)
		)
		(fill no)
		(layer "In3.Cu")
	)
	(gr_circle
		(center 332.1558 -44.8818)
		(end 333.0448 -44.8818)
		(stroke
			(width 0.2)
			(type default)
		)
		(fill no)
		(layer "In3.Cu")
	)
	(gr_circle
		(center 332.1558 -44.1198)
		(end 333.0448 -44.1198)
		(stroke
			(width 0.2)
			(type default)
		)
		(fill no)
		(layer "In3.Cu")
	)
	(gr_circle
		(center 332.1558 -43.3578)
		(end 333.0448 -43.3578)
		(stroke
			(width 0.2)
			(type default)
		)
		(fill no)
		(layer "In3.Cu")
	)
	(gr_circle
		(center 332.1558 -42.5958)
		(end 333.0448 -42.5958)
		(stroke
			(width 0.2)
			(type default)
		)
		(fill no)
		(layer "In3.Cu")
	)
	(gr_circle
		(center 332.1558 -34.3662)
		(end 333.0448 -34.3662)
		(stroke
			(width 0.2)
			(type default)
		)
		(fill no)
		(layer "In3.Cu")
	)
	(gr_circle
		(center 332.1558 -33.6042)
		(end 333.0448 -33.6042)
		(stroke
			(width 0.2)
			(type default)
		)
		(fill no)
		(layer "In3.Cu")
	)
	(gr_circle
		(center 332.1558 -32.8422)
		(end 333.0448 -32.8422)
		(stroke
			(width 0.2)
			(type default)
		)
		(fill no)
		(layer "In3.Cu")
	)
	(gr_circle
		(center 332.1558 -32.0802)
		(end 333.0448 -32.0802)
		(stroke
			(width 0.2)
			(type default)
		)
		(fill no)
		(layer "In3.Cu")
	)
	(gr_circle
		(center 332.1558 -31.3182)
		(end 333.0448 -31.3182)
		(stroke
			(width 0.2)
			(type default)
		)
		(fill no)
		(layer "In3.Cu")
	)
	(gr_circle
		(center 332.1558 -23.0886)
		(end 333.0448 -23.0886)
		(stroke
			(width 0.2)
			(type default)
		)
		(fill no)
		(layer "In3.Cu")
	)
	(gr_circle
		(center 332.1558 -22.3266)
		(end 333.0448 -22.3266)
		(stroke
			(width 0.2)
			(type default)
		)
		(fill no)
		(layer "In3.Cu")
	)
	(gr_circle
		(center 332.1558 -21.5646)
		(end 333.0448 -21.5646)
		(stroke
			(width 0.2)
			(type default)
		)
		(fill no)
		(layer "In3.Cu")
	)
	(gr_circle
		(center 332.1558 -20.8026)
		(end 333.0448 -20.8026)
		(stroke
			(width 0.2)
			(type default)
		)
		(fill no)
		(layer "In3.Cu")
	)
	(gr_circle
		(center 332.1558 -20.0406)
		(end 333.0448 -20.0406)
		(stroke
			(width 0.2)
			(type default)
		)
		(fill no)
		(layer "In3.Cu")
	)
	(gr_circle
		(center 332.9178 -79.4766)
		(end 333.8068 -79.4766)
		(stroke
			(width 0.2)
			(type default)
		)
		(fill no)
		(layer "In3.Cu")
	)
	(gr_circle
		(center 332.9178 -78.7146)
		(end 333.8068 -78.7146)
		(stroke
			(width 0.2)
			(type default)
		)
		(fill no)
		(layer "In3.Cu")
	)
	(gr_circle
		(center 332.9178 -77.9526)
		(end 333.8068 -77.9526)
		(stroke
			(width 0.2)
			(type default)
		)
		(fill no)
		(layer "In3.Cu")
	)
	(gr_circle
		(center 332.9178 -77.1906)
		(end 333.8068 -77.1906)
		(stroke
			(width 0.2)
			(type default)
		)
		(fill no)
		(layer "In3.Cu")
	)
	(gr_circle
		(center 332.9178 -76.4286)
		(end 333.8068 -76.4286)
		(stroke
			(width 0.2)
			(type default)
		)
		(fill no)
		(layer "In3.Cu")
	)
	(gr_circle
		(center 332.9178 -68.199)
		(end 333.8068 -68.199)
		(stroke
			(width 0.2)
			(type default)
		)
		(fill no)
		(layer "In3.Cu")
	)
	(gr_circle
		(center 332.9178 -67.437)
		(end 333.8068 -67.437)
		(stroke
			(width 0.2)
			(type default)
		)
		(fill no)
		(layer "In3.Cu")
	)
	(gr_circle
		(center 332.9178 -66.675)
		(end 333.8068 -66.675)
		(stroke
			(width 0.2)
			(type default)
		)
		(fill no)
		(layer "In3.Cu")
	)
	(gr_circle
		(center 332.9178 -65.913)
		(end 333.8068 -65.913)
		(stroke
			(width 0.2)
			(type default)
		)
		(fill no)
		(layer "In3.Cu")
	)
	(gr_circle
		(center 332.9178 -65.151)
		(end 333.8068 -65.151)
		(stroke
			(width 0.2)
			(type default)
		)
		(fill no)
		(layer "In3.Cu")
	)
	(gr_circle
		(center 332.9178 -56.9214)
		(end 333.8068 -56.9214)
		(stroke
			(width 0.2)
			(type default)
		)
		(fill no)
		(layer "In3.Cu")
	)
	(gr_circle
		(center 332.9178 -56.1594)
		(end 333.8068 -56.1594)
		(stroke
			(width 0.2)
			(type default)
		)
		(fill no)
		(layer "In3.Cu")
	)
	(gr_circle
		(center 332.9178 -55.3974)
		(end 333.8068 -55.3974)
		(stroke
			(width 0.2)
			(type default)
		)
		(fill no)
		(layer "In3.Cu")
	)
	(gr_circle
		(center 332.9178 -54.6354)
		(end 333.8068 -54.6354)
		(stroke
			(width 0.2)
			(type default)
		)
		(fill no)
		(layer "In3.Cu")
	)
	(gr_circle
		(center 332.9178 -53.8734)
		(end 333.8068 -53.8734)
		(stroke
			(width 0.2)
			(type default)
		)
		(fill no)
		(layer "In3.Cu")
	)
	(gr_circle
		(center 332.9178 -45.6438)
		(end 333.8068 -45.6438)
		(stroke
			(width 0.2)
			(type default)
		)
		(fill no)
		(layer "In3.Cu")
	)
	(gr_circle
		(center 332.9178 -44.8818)
		(end 333.8068 -44.8818)
		(stroke
			(width 0.2)
			(type default)
		)
		(fill no)
		(layer "In3.Cu")
	)
	(gr_circle
		(center 332.9178 -44.1198)
		(end 333.8068 -44.1198)
		(stroke
			(width 0.2)
			(type default)
		)
		(fill no)
		(layer "In3.Cu")
	)
	(gr_circle
		(center 332.9178 -43.3578)
		(end 333.8068 -43.3578)
		(stroke
			(width 0.2)
			(type default)
		)
		(fill no)
		(layer "In3.Cu")
	)
	(gr_circle
		(center 332.9178 -42.5958)
		(end 333.8068 -42.5958)
		(stroke
			(width 0.2)
			(type default)
		)
		(fill no)
		(layer "In3.Cu")
	)
	(gr_circle
		(center 332.9178 -34.3662)
		(end 333.8068 -34.3662)
		(stroke
			(width 0.2)
			(type default)
		)
		(fill no)
		(layer "In3.Cu")
	)
	(gr_circle
		(center 332.9178 -33.6042)
		(end 333.8068 -33.6042)
		(stroke
			(width 0.2)
			(type default)
		)
		(fill no)
		(layer "In3.Cu")
	)
	(gr_circle
		(center 332.9178 -32.8422)
		(end 333.8068 -32.8422)
		(stroke
			(width 0.2)
			(type default)
		)
		(fill no)
		(layer "In3.Cu")
	)
	(gr_circle
		(center 332.9178 -32.0802)
		(end 333.8068 -32.0802)
		(stroke
			(width 0.2)
			(type default)
		)
		(fill no)
		(layer "In3.Cu")
	)
	(gr_circle
		(center 332.9178 -31.3182)
		(end 333.8068 -31.3182)
		(stroke
			(width 0.2)
			(type default)
		)
		(fill no)
		(layer "In3.Cu")
	)
	(gr_circle
		(center 332.9178 -23.0886)
		(end 333.8068 -23.0886)
		(stroke
			(width 0.2)
			(type default)
		)
		(fill no)
		(layer "In3.Cu")
	)
	(gr_circle
		(center 332.9178 -22.3266)
		(end 333.8068 -22.3266)
		(stroke
			(width 0.2)
			(type default)
		)
		(fill no)
		(layer "In3.Cu")
	)
	(gr_circle
		(center 332.9178 -21.5646)
		(end 333.8068 -21.5646)
		(stroke
			(width 0.2)
			(type default)
		)
		(fill no)
		(layer "In3.Cu")
	)
	(gr_circle
		(center 332.9178 -20.8026)
		(end 333.8068 -20.8026)
		(stroke
			(width 0.2)
			(type default)
		)
		(fill no)
		(layer "In3.Cu")
	)
	(gr_circle
		(center 332.9178 -20.0406)
		(end 333.8068 -20.0406)
		(stroke
			(width 0.2)
			(type default)
		)
		(fill no)
		(layer "In3.Cu")
	)
	(gr_circle
		(center 333.6798 -78.7146)
		(end 334.5688 -78.7146)
		(stroke
			(width 0.2)
			(type default)
		)
		(fill no)
		(layer "In3.Cu")
	)
	(gr_circle
		(center 333.6798 -77.9526)
		(end 334.5688 -77.9526)
		(stroke
			(width 0.2)
			(type default)
		)
		(fill no)
		(layer "In3.Cu")
	)
	(gr_circle
		(center 333.6798 -77.1906)
		(end 334.5688 -77.1906)
		(stroke
			(width 0.2)
			(type default)
		)
		(fill no)
		(layer "In3.Cu")
	)
	(gr_circle
		(center 333.6798 -76.4286)
		(end 334.5688 -76.4286)
		(stroke
			(width 0.2)
			(type default)
		)
		(fill no)
		(layer "In3.Cu")
	)
	(gr_circle
		(center 333.6798 -68.199)
		(end 334.5688 -68.199)
		(stroke
			(width 0.2)
			(type default)
		)
		(fill no)
		(layer "In3.Cu")
	)
	(gr_circle
		(center 333.6798 -67.437)
		(end 334.5688 -67.437)
		(stroke
			(width 0.2)
			(type default)
		)
		(fill no)
		(layer "In3.Cu")
	)
	(gr_circle
		(center 333.6798 -66.675)
		(end 334.5688 -66.675)
		(stroke
			(width 0.2)
			(type default)
		)
		(fill no)
		(layer "In3.Cu")
	)
	(gr_circle
		(center 333.6798 -65.913)
		(end 334.5688 -65.913)
		(stroke
			(width 0.2)
			(type default)
		)
		(fill no)
		(layer "In3.Cu")
	)
	(gr_circle
		(center 333.6798 -65.151)
		(end 334.5688 -65.151)
		(stroke
			(width 0.2)
			(type default)
		)
		(fill no)
		(layer "In3.Cu")
	)
	(gr_circle
		(center 333.6798 -56.9214)
		(end 334.5688 -56.9214)
		(stroke
			(width 0.2)
			(type default)
		)
		(fill no)
		(layer "In3.Cu")
	)
	(gr_circle
		(center 333.6798 -56.1594)
		(end 334.5688 -56.1594)
		(stroke
			(width 0.2)
			(type default)
		)
		(fill no)
		(layer "In3.Cu")
	)
	(gr_circle
		(center 333.6798 -55.3974)
		(end 334.5688 -55.3974)
		(stroke
			(width 0.2)
			(type default)
		)
		(fill no)
		(layer "In3.Cu")
	)
	(gr_circle
		(center 333.6798 -54.6354)
		(end 334.5688 -54.6354)
		(stroke
			(width 0.2)
			(type default)
		)
		(fill no)
		(layer "In3.Cu")
	)
	(gr_circle
		(center 333.6798 -53.8734)
		(end 334.5688 -53.8734)
		(stroke
			(width 0.2)
			(type default)
		)
		(fill no)
		(layer "In3.Cu")
	)
	(gr_circle
		(center 333.6798 -45.6438)
		(end 334.5688 -45.6438)
		(stroke
			(width 0.2)
			(type default)
		)
		(fill no)
		(layer "In3.Cu")
	)
	(gr_circle
		(center 333.6798 -44.8818)
		(end 334.5688 -44.8818)
		(stroke
			(width 0.2)
			(type default)
		)
		(fill no)
		(layer "In3.Cu")
	)
	(gr_circle
		(center 333.6798 -44.1198)
		(end 334.5688 -44.1198)
		(stroke
			(width 0.2)
			(type default)
		)
		(fill no)
		(layer "In3.Cu")
	)
	(gr_circle
		(center 333.6798 -43.3578)
		(end 334.5688 -43.3578)
		(stroke
			(width 0.2)
			(type default)
		)
		(fill no)
		(layer "In3.Cu")
	)
	(gr_circle
		(center 333.6798 -42.5958)
		(end 334.5688 -42.5958)
		(stroke
			(width 0.2)
			(type default)
		)
		(fill no)
		(layer "In3.Cu")
	)
	(gr_circle
		(center 333.6798 -34.3662)
		(end 334.5688 -34.3662)
		(stroke
			(width 0.2)
			(type default)
		)
		(fill no)
		(layer "In3.Cu")
	)
	(gr_circle
		(center 333.6798 -33.6042)
		(end 334.5688 -33.6042)
		(stroke
			(width 0.2)
			(type default)
		)
		(fill no)
		(layer "In3.Cu")
	)
	(gr_circle
		(center 333.6798 -32.8422)
		(end 334.5688 -32.8422)
		(stroke
			(width 0.2)
			(type default)
		)
		(fill no)
		(layer "In3.Cu")
	)
	(gr_circle
		(center 333.6798 -32.0802)
		(end 334.5688 -32.0802)
		(stroke
			(width 0.2)
			(type default)
		)
		(fill no)
		(layer "In3.Cu")
	)
	(gr_circle
		(center 333.6798 -31.3182)
		(end 334.5688 -31.3182)
		(stroke
			(width 0.2)
			(type default)
		)
		(fill no)
		(layer "In3.Cu")
	)
	(gr_circle
		(center 333.6798 -23.0886)
		(end 334.5688 -23.0886)
		(stroke
			(width 0.2)
			(type default)
		)
		(fill no)
		(layer "In3.Cu")
	)
	(gr_circle
		(center 333.6798 -22.3266)
		(end 334.5688 -22.3266)
		(stroke
			(width 0.2)
			(type default)
		)
		(fill no)
		(layer "In3.Cu")
	)
	(gr_circle
		(center 333.6798 -21.5646)
		(end 334.5688 -21.5646)
		(stroke
			(width 0.2)
			(type default)
		)
		(fill no)
		(layer "In3.Cu")
	)
	(gr_circle
		(center 333.6798 -20.8026)
		(end 334.5688 -20.8026)
		(stroke
			(width 0.2)
			(type default)
		)
		(fill no)
		(layer "In3.Cu")
	)
	(gr_circle
		(center 333.6798 -20.0406)
		(end 334.5688 -20.0406)
		(stroke
			(width 0.2)
			(type default)
		)
		(fill no)
		(layer "In3.Cu")
	)
	(gr_circle
		(center 334.4418 -77.9526)
		(end 335.3308 -77.9526)
		(stroke
			(width 0.2)
			(type default)
		)
		(fill no)
		(layer "In3.Cu")
	)
	(gr_circle
		(center 334.4418 -77.1906)
		(end 335.3308 -77.1906)
		(stroke
			(width 0.2)
			(type default)
		)
		(fill no)
		(layer "In3.Cu")
	)
	(gr_circle
		(center 334.4418 -76.4286)
		(end 335.3308 -76.4286)
		(stroke
			(width 0.2)
			(type default)
		)
		(fill no)
		(layer "In3.Cu")
	)
	(gr_circle
		(center 334.4418 -68.199)
		(end 335.3308 -68.199)
		(stroke
			(width 0.2)
			(type default)
		)
		(fill no)
		(layer "In3.Cu")
	)
	(gr_circle
		(center 334.4418 -67.437)
		(end 335.3308 -67.437)
		(stroke
			(width 0.2)
			(type default)
		)
		(fill no)
		(layer "In3.Cu")
	)
	(gr_circle
		(center 334.4418 -66.675)
		(end 335.3308 -66.675)
		(stroke
			(width 0.2)
			(type default)
		)
		(fill no)
		(layer "In3.Cu")
	)
	(gr_circle
		(center 334.4418 -65.913)
		(end 335.3308 -65.913)
		(stroke
			(width 0.2)
			(type default)
		)
		(fill no)
		(layer "In3.Cu")
	)
	(gr_circle
		(center 334.4418 -65.151)
		(end 335.3308 -65.151)
		(stroke
			(width 0.2)
			(type default)
		)
		(fill no)
		(layer "In3.Cu")
	)
	(gr_circle
		(center 334.4418 -56.9214)
		(end 335.3308 -56.9214)
		(stroke
			(width 0.2)
			(type default)
		)
		(fill no)
		(layer "In3.Cu")
	)
	(gr_circle
		(center 334.4418 -56.1594)
		(end 335.3308 -56.1594)
		(stroke
			(width 0.2)
			(type default)
		)
		(fill no)
		(layer "In3.Cu")
	)
	(gr_circle
		(center 334.4418 -55.3974)
		(end 335.3308 -55.3974)
		(stroke
			(width 0.2)
			(type default)
		)
		(fill no)
		(layer "In3.Cu")
	)
	(gr_circle
		(center 334.4418 -54.6354)
		(end 335.3308 -54.6354)
		(stroke
			(width 0.2)
			(type default)
		)
		(fill no)
		(layer "In3.Cu")
	)
	(gr_circle
		(center 334.4418 -53.8734)
		(end 335.3308 -53.8734)
		(stroke
			(width 0.2)
			(type default)
		)
		(fill no)
		(layer "In3.Cu")
	)
	(gr_circle
		(center 334.4418 -44.8818)
		(end 335.3308 -44.8818)
		(stroke
			(width 0.2)
			(type default)
		)
		(fill no)
		(layer "In3.Cu")
	)
	(gr_circle
		(center 334.4418 -44.1198)
		(end 335.3308 -44.1198)
		(stroke
			(width 0.2)
			(type default)
		)
		(fill no)
		(layer "In3.Cu")
	)
	(gr_circle
		(center 334.4418 -43.3578)
		(end 335.3308 -43.3578)
		(stroke
			(width 0.2)
			(type default)
		)
		(fill no)
		(layer "In3.Cu")
	)
	(gr_circle
		(center 334.4418 -42.5958)
		(end 335.3308 -42.5958)
		(stroke
			(width 0.2)
			(type default)
		)
		(fill no)
		(layer "In3.Cu")
	)
	(gr_circle
		(center 334.4418 -34.3662)
		(end 335.3308 -34.3662)
		(stroke
			(width 0.2)
			(type default)
		)
		(fill no)
		(layer "In3.Cu")
	)
	(gr_circle
		(center 334.4418 -33.6042)
		(end 335.3308 -33.6042)
		(stroke
			(width 0.2)
			(type default)
		)
		(fill no)
		(layer "In3.Cu")
	)
	(gr_circle
		(center 334.4418 -32.8422)
		(end 335.3308 -32.8422)
		(stroke
			(width 0.2)
			(type default)
		)
		(fill no)
		(layer "In3.Cu")
	)
	(gr_circle
		(center 334.4418 -32.0802)
		(end 335.3308 -32.0802)
		(stroke
			(width 0.2)
			(type default)
		)
		(fill no)
		(layer "In3.Cu")
	)
	(gr_circle
		(center 334.4418 -31.3182)
		(end 335.3308 -31.3182)
		(stroke
			(width 0.2)
			(type default)
		)
		(fill no)
		(layer "In3.Cu")
	)
	(gr_circle
		(center 334.4418 -23.0886)
		(end 335.3308 -23.0886)
		(stroke
			(width 0.2)
			(type default)
		)
		(fill no)
		(layer "In3.Cu")
	)
	(gr_circle
		(center 334.4418 -22.3266)
		(end 335.3308 -22.3266)
		(stroke
			(width 0.2)
			(type default)
		)
		(fill no)
		(layer "In3.Cu")
	)
	(gr_circle
		(center 334.4418 -21.5646)
		(end 335.3308 -21.5646)
		(stroke
			(width 0.2)
			(type default)
		)
		(fill no)
		(layer "In3.Cu")
	)
	(gr_circle
		(center 334.4418 -20.8026)
		(end 335.3308 -20.8026)
		(stroke
			(width 0.2)
			(type default)
		)
		(fill no)
		(layer "In3.Cu")
	)
	(gr_circle
		(center 334.4418 -20.0406)
		(end 335.3308 -20.0406)
		(stroke
			(width 0.2)
			(type default)
		)
		(fill no)
		(layer "In3.Cu")
	)
	(gr_circle
		(center 335.2038 -77.1906)
		(end 336.0928 -77.1906)
		(stroke
			(width 0.2)
			(type default)
		)
		(fill no)
		(layer "In3.Cu")
	)
	(gr_circle
		(center 335.2038 -76.4286)
		(end 336.0928 -76.4286)
		(stroke
			(width 0.2)
			(type default)
		)
		(fill no)
		(layer "In3.Cu")
	)
	(gr_circle
		(center 335.2038 -68.199)
		(end 336.0928 -68.199)
		(stroke
			(width 0.2)
			(type default)
		)
		(fill no)
		(layer "In3.Cu")
	)
	(gr_circle
		(center 335.2038 -67.437)
		(end 336.0928 -67.437)
		(stroke
			(width 0.2)
			(type default)
		)
		(fill no)
		(layer "In3.Cu")
	)
	(gr_circle
		(center 335.2038 -66.675)
		(end 336.0928 -66.675)
		(stroke
			(width 0.2)
			(type default)
		)
		(fill no)
		(layer "In3.Cu")
	)
	(gr_circle
		(center 335.2038 -65.913)
		(end 336.0928 -65.913)
		(stroke
			(width 0.2)
			(type default)
		)
		(fill no)
		(layer "In3.Cu")
	)
	(gr_circle
		(center 335.2038 -65.151)
		(end 336.0928 -65.151)
		(stroke
			(width 0.2)
			(type default)
		)
		(fill no)
		(layer "In3.Cu")
	)
	(gr_circle
		(center 335.2038 -56.9214)
		(end 336.0928 -56.9214)
		(stroke
			(width 0.2)
			(type default)
		)
		(fill no)
		(layer "In3.Cu")
	)
	(gr_circle
		(center 335.2038 -56.1594)
		(end 336.0928 -56.1594)
		(stroke
			(width 0.2)
			(type default)
		)
		(fill no)
		(layer "In3.Cu")
	)
	(gr_circle
		(center 335.2038 -55.3974)
		(end 336.0928 -55.3974)
		(stroke
			(width 0.2)
			(type default)
		)
		(fill no)
		(layer "In3.Cu")
	)
	(gr_circle
		(center 335.2038 -54.6354)
		(end 336.0928 -54.6354)
		(stroke
			(width 0.2)
			(type default)
		)
		(fill no)
		(layer "In3.Cu")
	)
	(gr_circle
		(center 335.2038 -53.8734)
		(end 336.0928 -53.8734)
		(stroke
			(width 0.2)
			(type default)
		)
		(fill no)
		(layer "In3.Cu")
	)
	(gr_circle
		(center 335.2038 -44.8818)
		(end 336.0928 -44.8818)
		(stroke
			(width 0.2)
			(type default)
		)
		(fill no)
		(layer "In3.Cu")
	)
	(gr_circle
		(center 335.2038 -44.1198)
		(end 336.0928 -44.1198)
		(stroke
			(width 0.2)
			(type default)
		)
		(fill no)
		(layer "In3.Cu")
	)
	(gr_circle
		(center 335.2038 -43.3578)
		(end 336.0928 -43.3578)
		(stroke
			(width 0.2)
			(type default)
		)
		(fill no)
		(layer "In3.Cu")
	)
	(gr_circle
		(center 335.2038 -42.5958)
		(end 336.0928 -42.5958)
		(stroke
			(width 0.2)
			(type default)
		)
		(fill no)
		(layer "In3.Cu")
	)
	(gr_circle
		(center 335.2038 -34.3662)
		(end 336.0928 -34.3662)
		(stroke
			(width 0.2)
			(type default)
		)
		(fill no)
		(layer "In3.Cu")
	)
	(gr_circle
		(center 335.2038 -33.6042)
		(end 336.0928 -33.6042)
		(stroke
			(width 0.2)
			(type default)
		)
		(fill no)
		(layer "In3.Cu")
	)
	(gr_circle
		(center 335.2038 -32.8422)
		(end 336.0928 -32.8422)
		(stroke
			(width 0.2)
			(type default)
		)
		(fill no)
		(layer "In3.Cu")
	)
	(gr_circle
		(center 335.2038 -32.0802)
		(end 336.0928 -32.0802)
		(stroke
			(width 0.2)
			(type default)
		)
		(fill no)
		(layer "In3.Cu")
	)
	(gr_circle
		(center 335.2038 -31.3182)
		(end 336.0928 -31.3182)
		(stroke
			(width 0.2)
			(type default)
		)
		(fill no)
		(layer "In3.Cu")
	)
	(gr_circle
		(center 335.2038 -23.0886)
		(end 336.0928 -23.0886)
		(stroke
			(width 0.2)
			(type default)
		)
		(fill no)
		(layer "In3.Cu")
	)
	(gr_circle
		(center 335.2038 -22.3266)
		(end 336.0928 -22.3266)
		(stroke
			(width 0.2)
			(type default)
		)
		(fill no)
		(layer "In3.Cu")
	)
	(gr_circle
		(center 335.2038 -21.5646)
		(end 336.0928 -21.5646)
		(stroke
			(width 0.2)
			(type default)
		)
		(fill no)
		(layer "In3.Cu")
	)
	(gr_circle
		(center 335.2038 -20.8026)
		(end 336.0928 -20.8026)
		(stroke
			(width 0.2)
			(type default)
		)
		(fill no)
		(layer "In3.Cu")
	)
	(gr_circle
		(center 335.2038 -20.0406)
		(end 336.0928 -20.0406)
		(stroke
			(width 0.2)
			(type default)
		)
		(fill no)
		(layer "In3.Cu")
	)
	(gr_circle
		(center 335.367884 -73.6346)
		(end 336.256884 -73.6346)
		(stroke
			(width 0.2)
			(type default)
		)
		(fill no)
		(layer "In3.Cu")
	)
	(gr_circle
		(center 335.367884 -62.357)
		(end 336.256884 -62.357)
		(stroke
			(width 0.2)
			(type default)
		)
		(fill no)
		(layer "In3.Cu")
	)
	(gr_circle
		(center 335.367884 -51.0794)
		(end 336.256884 -51.0794)
		(stroke
			(width 0.2)
			(type default)
		)
		(fill no)
		(layer "In3.Cu")
	)
	(gr_circle
		(center 335.367884 -39.8018)
		(end 336.256884 -39.8018)
		(stroke
			(width 0.2)
			(type default)
		)
		(fill no)
		(layer "In3.Cu")
	)
	(gr_circle
		(center 335.367884 -28.5242)
		(end 336.256884 -28.5242)
		(stroke
			(width 0.2)
			(type default)
		)
		(fill no)
		(layer "In3.Cu")
	)
	(gr_circle
		(center 335.367884 -17.2466)
		(end 336.256884 -17.2466)
		(stroke
			(width 0.2)
			(type default)
		)
		(fill no)
		(layer "In3.Cu")
	)
	(gr_circle
		(center 336.3214 -49.5046)
		(end 337.2104 -49.5046)
		(stroke
			(width 0.2)
			(type default)
		)
		(fill no)
		(layer "In3.Cu")
	)
	(gr_circle
		(center 336.3214 -38.227)
		(end 337.2104 -38.227)
		(stroke
			(width 0.2)
			(type default)
		)
		(fill no)
		(layer "In3.Cu")
	)
	(gr_circle
		(center 338.498434 -48.423576)
		(end 339.387434 -48.423576)
		(stroke
			(width 0.2)
			(type default)
		)
		(fill no)
		(layer "In3.Cu")
	)
	(gr_circle
		(center 338.87156 -37.247068)
		(end 339.76056 -37.247068)
		(stroke
			(width 0.2)
			(type default)
		)
		(fill no)
		(layer "In3.Cu")
	)
	(gr_circle
		(center 354.89642 -5.353304)
		(end 355.78542 -5.353304)
		(stroke
			(width 0.2)
			(type default)
		)
		(fill no)
		(layer "In3.Cu")
	)
	(gr_circle
		(center 354.89642 -4.591304)
		(end 355.78542 -4.591304)
		(stroke
			(width 0.2)
			(type default)
		)
		(fill no)
		(layer "In3.Cu")
	)
	(gr_circle
		(center 354.89642 -3.829304)
		(end 355.78542 -3.829304)
		(stroke
			(width 0.2)
			(type default)
		)
		(fill no)
		(layer "In3.Cu")
	)
	(gr_circle
		(center 355.65842 -5.353304)
		(end 356.54742 -5.353304)
		(stroke
			(width 0.2)
			(type default)
		)
		(fill no)
		(layer "In3.Cu")
	)
	(gr_circle
		(center 355.65842 -4.591304)
		(end 356.54742 -4.591304)
		(stroke
			(width 0.2)
			(type default)
		)
		(fill no)
		(layer "In3.Cu")
	)
	(gr_circle
		(center 355.65842 -3.829304)
		(end 356.54742 -3.829304)
		(stroke
			(width 0.2)
			(type default)
		)
		(fill no)
		(layer "In3.Cu")
	)
	(gr_circle
		(center 356.42042 -5.353304)
		(end 357.30942 -5.353304)
		(stroke
			(width 0.2)
			(type default)
		)
		(fill no)
		(layer "In3.Cu")
	)
	(gr_circle
		(center 356.42042 -4.591304)
		(end 357.30942 -4.591304)
		(stroke
			(width 0.2)
			(type default)
		)
		(fill no)
		(layer "In3.Cu")
	)
	(gr_circle
		(center 356.42042 -3.829304)
		(end 357.30942 -3.829304)
		(stroke
			(width 0.2)
			(type default)
		)
		(fill no)
		(layer "In3.Cu")
	)
	(gr_circle
		(center 357.18242 -5.353304)
		(end 358.07142 -5.353304)
		(stroke
			(width 0.2)
			(type default)
		)
		(fill no)
		(layer "In3.Cu")
	)
	(gr_circle
		(center 357.18242 -4.591304)
		(end 358.07142 -4.591304)
		(stroke
			(width 0.2)
			(type default)
		)
		(fill no)
		(layer "In3.Cu")
	)
	(gr_circle
		(center 357.18242 -3.829304)
		(end 358.07142 -3.829304)
		(stroke
			(width 0.2)
			(type default)
		)
		(fill no)
		(layer "In3.Cu")
	)
	(gr_circle
		(center 357.94442 -5.353304)
		(end 358.83342 -5.353304)
		(stroke
			(width 0.2)
			(type default)
		)
		(fill no)
		(layer "In3.Cu")
	)
	(gr_circle
		(center 357.94442 -4.591304)
		(end 358.83342 -4.591304)
		(stroke
			(width 0.2)
			(type default)
		)
		(fill no)
		(layer "In3.Cu")
	)
	(gr_circle
		(center 357.94442 -3.829304)
		(end 358.83342 -3.829304)
		(stroke
			(width 0.2)
			(type default)
		)
		(fill no)
		(layer "In3.Cu")
	)
	(gr_circle
		(center 358.70642 -5.353304)
		(end 359.59542 -5.353304)
		(stroke
			(width 0.2)
			(type default)
		)
		(fill no)
		(layer "In3.Cu")
	)
	(gr_circle
		(center 358.70642 -4.591304)
		(end 359.59542 -4.591304)
		(stroke
			(width 0.2)
			(type default)
		)
		(fill no)
		(layer "In3.Cu")
	)
	(gr_circle
		(center 358.70642 -3.829304)
		(end 359.59542 -3.829304)
		(stroke
			(width 0.2)
			(type default)
		)
		(fill no)
		(layer "In3.Cu")
	)
	(gr_circle
		(center 363.000036 -160.830006)
		(end 364.21314 -160.830006)
		(stroke
			(width 0.2)
			(type default)
		)
		(fill no)
		(layer "In3.Cu")
	)
	(gr_circle
		(center 363.000036 -158.83001)
		(end 364.21314 -158.83001)
		(stroke
			(width 0.2)
			(type default)
		)
		(fill no)
		(layer "In3.Cu")
	)
	(gr_circle
		(center 363.000036 -156.830014)
		(end 364.21314 -156.830014)
		(stroke
			(width 0.2)
			(type default)
		)
		(fill no)
		(layer "In3.Cu")
	)
	(gr_circle
		(center 364.123478 -159.82061)
		(end 365.336582 -159.82061)
		(stroke
			(width 0.2)
			(type default)
		)
		(fill no)
		(layer "In3.Cu")
	)
	(gr_circle
		(center 364.123478 -157.820614)
		(end 365.336582 -157.820614)
		(stroke
			(width 0.2)
			(type default)
		)
		(fill no)
		(layer "In3.Cu")
	)
	(gr_circle
		(center 365.000032 -160.830006)
		(end 366.213136 -160.830006)
		(stroke
			(width 0.2)
			(type default)
		)
		(fill no)
		(layer "In3.Cu")
	)
	(gr_circle
		(center 365.000032 -158.83001)
		(end 366.213136 -158.83001)
		(stroke
			(width 0.2)
			(type default)
		)
		(fill no)
		(layer "In3.Cu")
	)
	(gr_circle
		(center 365.000032 -156.830014)
		(end 366.213136 -156.830014)
		(stroke
			(width 0.2)
			(type default)
		)
		(fill no)
		(layer "In3.Cu")
	)
	(gr_circle
		(center 366.119918 -2.590038)
		(end 367.333022 -2.590038)
		(stroke
			(width 0.2)
			(type default)
		)
		(fill no)
		(layer "In3.Cu")
	)
	(gr_circle
		(center 368.659918 -2.590038)
		(end 369.873022 -2.590038)
		(stroke
			(width 0.2)
			(type default)
		)
		(fill no)
		(layer "In3.Cu")
	)
	(gr_circle
		(center 369.000024 -160.830006)
		(end 370.213128 -160.830006)
		(stroke
			(width 0.2)
			(type default)
		)
		(fill no)
		(layer "In3.Cu")
	)
	(gr_circle
		(center 369.000024 -158.83001)
		(end 370.213128 -158.83001)
		(stroke
			(width 0.2)
			(type default)
		)
		(fill no)
		(layer "In3.Cu")
	)
	(gr_circle
		(center 369.000024 -156.830014)
		(end 370.213128 -156.830014)
		(stroke
			(width 0.2)
			(type default)
		)
		(fill no)
		(layer "In3.Cu")
	)
	(gr_circle
		(center 369.990878 -159.87141)
		(end 371.203982 -159.87141)
		(stroke
			(width 0.2)
			(type default)
		)
		(fill no)
		(layer "In3.Cu")
	)
	(gr_circle
		(center 369.990878 -157.871414)
		(end 371.203982 -157.871414)
		(stroke
			(width 0.2)
			(type default)
		)
		(fill no)
		(layer "In3.Cu")
	)
	(gr_circle
		(center 371.00002 -160.830006)
		(end 372.213124 -160.830006)
		(stroke
			(width 0.2)
			(type default)
		)
		(fill no)
		(layer "In3.Cu")
	)
	(gr_circle
		(center 371.00002 -158.83001)
		(end 372.213124 -158.83001)
		(stroke
			(width 0.2)
			(type default)
		)
		(fill no)
		(layer "In3.Cu")
	)
	(gr_circle
		(center 371.00002 -156.830014)
		(end 372.213124 -156.830014)
		(stroke
			(width 0.2)
			(type default)
		)
		(fill no)
		(layer "In3.Cu")
	)
	(gr_circle
		(center 375.000012 -160.830006)
		(end 376.213116 -160.830006)
		(stroke
			(width 0.2)
			(type default)
		)
		(fill no)
		(layer "In3.Cu")
	)
	(gr_circle
		(center 375.000012 -158.83001)
		(end 376.213116 -158.83001)
		(stroke
			(width 0.2)
			(type default)
		)
		(fill no)
		(layer "In3.Cu")
	)
	(gr_circle
		(center 375.000012 -156.830014)
		(end 376.213116 -156.830014)
		(stroke
			(width 0.2)
			(type default)
		)
		(fill no)
		(layer "In3.Cu")
	)
	(gr_circle
		(center 375.909078 -159.79521)
		(end 377.122182 -159.79521)
		(stroke
			(width 0.2)
			(type default)
		)
		(fill no)
		(layer "In3.Cu")
	)
	(gr_circle
		(center 375.909078 -157.795214)
		(end 377.122182 -157.795214)
		(stroke
			(width 0.2)
			(type default)
		)
		(fill no)
		(layer "In3.Cu")
	)
	(gr_circle
		(center 377.000008 -160.830006)
		(end 378.213112 -160.830006)
		(stroke
			(width 0.2)
			(type default)
		)
		(fill no)
		(layer "In3.Cu")
	)
	(gr_circle
		(center 377.000008 -158.83001)
		(end 378.213112 -158.83001)
		(stroke
			(width 0.2)
			(type default)
		)
		(fill no)
		(layer "In3.Cu")
	)
	(gr_circle
		(center 377.000008 -156.830014)
		(end 378.213112 -156.830014)
		(stroke
			(width 0.2)
			(type default)
		)
		(fill no)
		(layer "In3.Cu")
	)
	(gr_circle
		(center 378.079 -139.7)
		(end 379.603 -139.7)
		(stroke
			(width 0.2)
			(type default)
		)
		(fill no)
		(layer "In3.Cu")
	)
	(gr_circle
		(center 378.079 -119.38)
		(end 379.603 -119.38)
		(stroke
			(width 0.2)
			(type default)
		)
		(fill no)
		(layer "In3.Cu")
	)
	(gr_circle
		(center 378.079 -99.06)
		(end 379.603 -99.06)
		(stroke
			(width 0.2)
			(type default)
		)
		(fill no)
		(layer "In3.Cu")
	)
	(gr_circle
		(center 378.079 -78.74)
		(end 379.603 -78.74)
		(stroke
			(width 0.2)
			(type default)
		)
		(fill no)
		(layer "In3.Cu")
	)
	(gr_circle
		(center 378.079 -58.42)
		(end 379.603 -58.42)
		(stroke
			(width 0.2)
			(type default)
		)
		(fill no)
		(layer "In3.Cu")
	)
	(gr_circle
		(center 383.199894 -160.830006)
		(end 384.412998 -160.830006)
		(stroke
			(width 0.2)
			(type default)
		)
		(fill no)
		(layer "In3.Cu")
	)
	(gr_circle
		(center 383.199894 -158.83001)
		(end 384.412998 -158.83001)
		(stroke
			(width 0.2)
			(type default)
		)
		(fill no)
		(layer "In3.Cu")
	)
	(gr_circle
		(center 383.199894 -156.830014)
		(end 384.412998 -156.830014)
		(stroke
			(width 0.2)
			(type default)
		)
		(fill no)
		(layer "In3.Cu")
	)
	(gr_circle
		(center 384.062478 -159.64281)
		(end 385.275582 -159.64281)
		(stroke
			(width 0.2)
			(type default)
		)
		(fill no)
		(layer "In3.Cu")
	)
	(gr_circle
		(center 384.062478 -157.642814)
		(end 385.275582 -157.642814)
		(stroke
			(width 0.2)
			(type default)
		)
		(fill no)
		(layer "In3.Cu")
	)
	(gr_circle
		(center 385.19989 -160.830006)
		(end 386.412994 -160.830006)
		(stroke
			(width 0.2)
			(type default)
		)
		(fill no)
		(layer "In3.Cu")
	)
	(gr_circle
		(center 385.19989 -158.83001)
		(end 386.412994 -158.83001)
		(stroke
			(width 0.2)
			(type default)
		)
		(fill no)
		(layer "In3.Cu")
	)
	(gr_circle
		(center 385.19989 -156.830014)
		(end 386.412994 -156.830014)
		(stroke
			(width 0.2)
			(type default)
		)
		(fill no)
		(layer "In3.Cu")
	)
	(gr_circle
		(center 389.199882 -160.830006)
		(end 390.412986 -160.830006)
		(stroke
			(width 0.2)
			(type default)
		)
		(fill no)
		(layer "In3.Cu")
	)
	(gr_circle
		(center 389.199882 -158.83001)
		(end 390.412986 -158.83001)
		(stroke
			(width 0.2)
			(type default)
		)
		(fill no)
		(layer "In3.Cu")
	)
	(gr_circle
		(center 389.199882 -156.830014)
		(end 390.412986 -156.830014)
		(stroke
			(width 0.2)
			(type default)
		)
		(fill no)
		(layer "In3.Cu")
	)
	(gr_circle
		(center 390.158478 -159.71901)
		(end 391.371582 -159.71901)
		(stroke
			(width 0.2)
			(type default)
		)
		(fill no)
		(layer "In3.Cu")
	)
	(gr_circle
		(center 390.158478 -157.719014)
		(end 391.371582 -157.719014)
		(stroke
			(width 0.2)
			(type default)
		)
		(fill no)
		(layer "In3.Cu")
	)
	(gr_circle
		(center 391.199878 -160.830006)
		(end 392.412982 -160.830006)
		(stroke
			(width 0.2)
			(type default)
		)
		(fill no)
		(layer "In3.Cu")
	)
	(gr_circle
		(center 391.199878 -158.83001)
		(end 392.412982 -158.83001)
		(stroke
			(width 0.2)
			(type default)
		)
		(fill no)
		(layer "In3.Cu")
	)
	(gr_circle
		(center 391.199878 -156.830014)
		(end 392.412982 -156.830014)
		(stroke
			(width 0.2)
			(type default)
		)
		(fill no)
		(layer "In3.Cu")
	)
	(gr_circle
		(center 397.637 -139.7)
		(end 399.161 -139.7)
		(stroke
			(width 0.2)
			(type default)
		)
		(fill no)
		(layer "In3.Cu")
	)
	(gr_circle
		(center 397.637 -119.38)
		(end 399.161 -119.38)
		(stroke
			(width 0.2)
			(type default)
		)
		(fill no)
		(layer "In3.Cu")
	)
	(gr_circle
		(center 397.637 -99.06)
		(end 399.161 -99.06)
		(stroke
			(width 0.2)
			(type default)
		)
		(fill no)
		(layer "In3.Cu")
	)
	(gr_circle
		(center 397.637 -78.74)
		(end 399.161 -78.74)
		(stroke
			(width 0.2)
			(type default)
		)
		(fill no)
		(layer "In3.Cu")
	)
	(gr_circle
		(center 397.637 -58.42)
		(end 399.161 -58.42)
		(stroke
			(width 0.2)
			(type default)
		)
		(fill no)
		(layer "In3.Cu")
	)
	(gr_circle
		(center 398.375124 -168.82999)
		(end 399.588228 -168.82999)
		(stroke
			(width 0.2)
			(type default)
		)
		(fill no)
		(layer "In3.Cu")
	)
	(gr_circle
		(center 398.375124 -166.829994)
		(end 399.588228 -166.829994)
		(stroke
			(width 0.2)
			(type default)
		)
		(fill no)
		(layer "In3.Cu")
	)
	(gr_circle
		(center 398.375124 -164.829998)
		(end 399.588228 -164.829998)
		(stroke
			(width 0.2)
			(type default)
		)
		(fill no)
		(layer "In3.Cu")
	)
	(gr_circle
		(center 398.375124 -162.830002)
		(end 399.588228 -162.830002)
		(stroke
			(width 0.2)
			(type default)
		)
		(fill no)
		(layer "In3.Cu")
	)
	(gr_circle
		(center 398.375124 -160.830006)
		(end 399.588228 -160.830006)
		(stroke
			(width 0.2)
			(type default)
		)
		(fill no)
		(layer "In3.Cu")
	)
	(gr_circle
		(center 398.375124 -158.83001)
		(end 399.588228 -158.83001)
		(stroke
			(width 0.2)
			(type default)
		)
		(fill no)
		(layer "In3.Cu")
	)
	(gr_circle
		(center 398.375124 -156.830014)
		(end 399.588228 -156.830014)
		(stroke
			(width 0.2)
			(type default)
		)
		(fill no)
		(layer "In3.Cu")
	)
	(gr_circle
		(center 398.375124 -154.830018)
		(end 399.588228 -154.830018)
		(stroke
			(width 0.2)
			(type default)
		)
		(fill no)
		(layer "In3.Cu")
	)
	(gr_circle
		(center 398.375124 -152.830022)
		(end 399.588228 -152.830022)
		(stroke
			(width 0.2)
			(type default)
		)
		(fill no)
		(layer "In3.Cu")
	)
	(gr_circle
		(center 399.40992 -167.591994)
		(end 400.623024 -167.591994)
		(stroke
			(width 0.2)
			(type default)
		)
		(fill no)
		(layer "In3.Cu")
	)
	(gr_circle
		(center 399.40992 -165.591998)
		(end 400.623024 -165.591998)
		(stroke
			(width 0.2)
			(type default)
		)
		(fill no)
		(layer "In3.Cu")
	)
	(gr_circle
		(center 399.40992 -163.592002)
		(end 400.623024 -163.592002)
		(stroke
			(width 0.2)
			(type default)
		)
		(fill no)
		(layer "In3.Cu")
	)
	(gr_circle
		(center 399.40992 -161.592006)
		(end 400.623024 -161.592006)
		(stroke
			(width 0.2)
			(type default)
		)
		(fill no)
		(layer "In3.Cu")
	)
	(gr_circle
		(center 399.40992 -159.59201)
		(end 400.623024 -159.59201)
		(stroke
			(width 0.2)
			(type default)
		)
		(fill no)
		(layer "In3.Cu")
	)
	(gr_circle
		(center 399.40992 -157.592014)
		(end 400.623024 -157.592014)
		(stroke
			(width 0.2)
			(type default)
		)
		(fill no)
		(layer "In3.Cu")
	)
	(gr_circle
		(center 399.40992 -155.592018)
		(end 400.623024 -155.592018)
		(stroke
			(width 0.2)
			(type default)
		)
		(fill no)
		(layer "In3.Cu")
	)
	(gr_circle
		(center 399.40992 -153.592022)
		(end 400.623024 -153.592022)
		(stroke
			(width 0.2)
			(type default)
		)
		(fill no)
		(layer "In3.Cu")
	)
	(gr_circle
		(center 400.37512 -168.82999)
		(end 401.588224 -168.82999)
		(stroke
			(width 0.2)
			(type default)
		)
		(fill no)
		(layer "In3.Cu")
	)
	(gr_circle
		(center 400.37512 -166.829994)
		(end 401.588224 -166.829994)
		(stroke
			(width 0.2)
			(type default)
		)
		(fill no)
		(layer "In3.Cu")
	)
	(gr_circle
		(center 400.37512 -164.829998)
		(end 401.588224 -164.829998)
		(stroke
			(width 0.2)
			(type default)
		)
		(fill no)
		(layer "In3.Cu")
	)
	(gr_circle
		(center 400.37512 -162.830002)
		(end 401.588224 -162.830002)
		(stroke
			(width 0.2)
			(type default)
		)
		(fill no)
		(layer "In3.Cu")
	)
	(gr_circle
		(center 400.37512 -160.830006)
		(end 401.588224 -160.830006)
		(stroke
			(width 0.2)
			(type default)
		)
		(fill no)
		(layer "In3.Cu")
	)
	(gr_circle
		(center 400.37512 -158.83001)
		(end 401.588224 -158.83001)
		(stroke
			(width 0.2)
			(type default)
		)
		(fill no)
		(layer "In3.Cu")
	)
	(gr_circle
		(center 400.37512 -156.830014)
		(end 401.588224 -156.830014)
		(stroke
			(width 0.2)
			(type default)
		)
		(fill no)
		(layer "In3.Cu")
	)
	(gr_circle
		(center 400.37512 -154.830018)
		(end 401.588224 -154.830018)
		(stroke
			(width 0.2)
			(type default)
		)
		(fill no)
		(layer "In3.Cu")
	)
	(gr_circle
		(center 400.37512 -152.830022)
		(end 401.588224 -152.830022)
		(stroke
			(width 0.2)
			(type default)
		)
		(fill no)
		(layer "In3.Cu")
	)
	(gr_circle
		(center 468.920068 -76.309982)
		(end 470.329768 -76.309982)
		(stroke
			(width 0.2)
			(type default)
		)
		(fill no)
		(layer "In3.Cu")
	)
	(gr_circle
		(center 468.920068 -73.769982)
		(end 470.329768 -73.769982)
		(stroke
			(width 0.2)
			(type default)
		)
		(fill no)
		(layer "In3.Cu")
	)
	(gr_circle
		(center 468.920068 -71.229982)
		(end 470.329768 -71.229982)
		(stroke
			(width 0.2)
			(type default)
		)
		(fill no)
		(layer "In3.Cu")
	)
	(gr_circle
		(center 468.920068 -68.689982)
		(end 470.329768 -68.689982)
		(stroke
			(width 0.2)
			(type default)
		)
		(fill no)
		(layer "In3.Cu")
	)
	(gr_circle
		(center 469.994488 -74.785982)
		(end 471.404188 -74.785982)
		(stroke
			(width 0.2)
			(type default)
		)
		(fill no)
		(layer "In3.Cu")
	)
	(gr_circle
		(center 469.994488 -72.245982)
		(end 471.404188 -72.245982)
		(stroke
			(width 0.2)
			(type default)
		)
		(fill no)
		(layer "In3.Cu")
	)
	(gr_circle
		(center 469.994488 -69.705982)
		(end 471.404188 -69.705982)
		(stroke
			(width 0.2)
			(type default)
		)
		(fill no)
		(layer "In3.Cu")
	)
	(gr_circle
		(center 471.620088 -76.309982)
		(end 473.029788 -76.309982)
		(stroke
			(width 0.2)
			(type default)
		)
		(fill no)
		(layer "In3.Cu")
	)
	(gr_circle
		(center 471.620088 -73.769982)
		(end 473.029788 -73.769982)
		(stroke
			(width 0.2)
			(type default)
		)
		(fill no)
		(layer "In3.Cu")
	)
	(gr_circle
		(center 471.620088 -71.229982)
		(end 473.029788 -71.229982)
		(stroke
			(width 0.2)
			(type default)
		)
		(fill no)
		(layer "In3.Cu")
	)
	(gr_circle
		(center 471.620088 -68.689982)
		(end 473.029788 -68.689982)
		(stroke
			(width 0.2)
			(type default)
		)
		(fill no)
		(layer "In3.Cu")
	)
	(gr_line
		(start 0 -153.299922)
		(end 0 -4.99999)
		(stroke
			(width 2.032)
			(type default)
		)
		(layer "In4.Cu")
	)
	(gr_arc
		(start 0 -153.299922)
		(mid 1.464464 -156.835448)
		(end 4.99999 -158.299912)
		(stroke
			(width 2.032)
			(type default)
		)
		(layer "In4.Cu")
	)
	(gr_poly
		(pts
			(arc
				(start 192.800224 -51.05908)
				(mid 192.819747 -51.055179)
				(end 192.836292 -51.044094)
			)
			(arc
				(start 193.053462 -50.826924)
				(mid 193.064573 -50.81039)
				(end 193.068448 -50.790856)
			)
			(arc
				(start 193.068448 -46.88586)
				(mid 193.064547 -46.866337)
				(end 193.053462 -46.849792)
			)
			(arc
				(start 189.652656 -43.448986)
				(mid 189.636122 -43.437875)
				(end 189.616588 -43.434)
			)
			(arc
				(start 186.057794 -43.434)
				(mid 186.038271 -43.437901)
				(end 186.021726 -43.448986)
			)
			(arc
				(start 182.666386 -46.804326)
				(mid 182.655275 -46.82086)
				(end 182.6514 -46.840394)
			)
			(arc
				(start 182.6514 -50.663602)
				(mid 182.655301 -50.683125)
				(end 182.666386 -50.69967)
			)
			(arc
				(start 183.01081 -51.044094)
				(mid 183.027344 -51.055205)
				(end 183.046878 -51.05908)
			)
		)
		(stroke
			(width 0)
			(type solid)
		)
		(fill yes)
		(layer "In4.Cu")
		(net "P52V_2_FUSE_1")
	)
	(gr_poly
		(pts
			(arc
				(start 257.287522 -51.05908)
				(mid 257.307045 -51.055179)
				(end 257.32359 -51.044094)
			)
			(arc
				(start 257.668014 -50.69967)
				(mid 257.679125 -50.683136)
				(end 257.683 -50.663602)
			)
			(arc
				(start 257.683 -46.840394)
				(mid 257.679099 -46.820871)
				(end 257.668014 -46.804326)
			)
			(arc
				(start 254.312674 -43.448986)
				(mid 254.29614 -43.437875)
				(end 254.276606 -43.434)
			)
			(arc
				(start 250.717812 -43.434)
				(mid 250.698289 -43.437901)
				(end 250.681744 -43.448986)
			)
			(arc
				(start 247.280938 -46.849792)
				(mid 247.269827 -46.866326)
				(end 247.265952 -46.88586)
			)
			(arc
				(start 247.265952 -50.790856)
				(mid 247.269853 -50.810379)
				(end 247.280938 -50.826924)
			)
			(arc
				(start 247.498108 -51.044094)
				(mid 247.514642 -51.055205)
				(end 247.534176 -51.05908)
			)
		)
		(stroke
			(width 0)
			(type solid)
		)
		(fill yes)
		(layer "In4.Cu")
		(net "P52V_1_FUSE_1")
	)
	(gr_poly
		(pts
			(arc
				(start 136.007856 -80.01)
				(mid 136.027379 -80.006099)
				(end 136.043924 -79.995014)
			)
			(arc
				(start 136.343644 -79.695294)
				(mid 136.354755 -79.67876)
				(end 136.35863 -79.659226)
			)
			(arc
				(start 136.35863 -68.303902)
				(mid 136.397314 -68.109513)
				(end 136.507474 -67.944746)
			)
			(arc
				(start 137.49655 -66.95567)
				(mid 137.661318 -66.845512)
				(end 137.855706 -66.806826)
			)
			(arc
				(start 139.442444 -66.806826)
				(mid 139.460379 -66.803555)
				(end 139.475972 -66.794126)
			)
			(arc
				(start 139.475972 -66.794126)
				(mid 139.749442 -66.630021)
				(end 140.06322 -66.572892)
			)
			(arc
				(start 140.06322 -66.572892)
				(mid 140.377013 -66.629983)
				(end 140.650468 -66.794126)
			)
			(arc
				(start 140.650468 -66.794126)
				(mid 140.666078 -66.80351)
				(end 140.683996 -66.806826)
			)
			(arc
				(start 142.0876 -66.806826)
				(mid 142.123521 -66.791947)
				(end 142.1384 -66.756026)
			)
			(xy 142.1384 -64.13246)
			(arc
				(start 142.13713 -64.126618)
				(mid 142.119868 -64.026946)
				(end 142.114016 -63.925958)
			)
			(arc
				(start 142.114016 -63.925958)
				(mid 142.119853 -63.824969)
				(end 142.13713 -63.725298)
			)
			(xy 142.1384 -63.719456) (xy 142.1384 -63.026544)
			(arc
				(start 142.13713 -63.020702)
				(mid 142.119868 -62.92103)
				(end 142.114016 -62.820042)
			)
			(arc
				(start 142.114016 -62.820042)
				(mid 142.119853 -62.719053)
				(end 142.13713 -62.619382)
			)
			(xy 142.1384 -62.61354)
			(arc
				(start 142.1384 -47.729394)
				(mid 142.134499 -47.709871)
				(end 142.123414 -47.693326)
			)
			(arc
				(start 141.308074 -46.877986)
				(mid 141.29154 -46.866875)
				(end 141.272006 -46.863)
			)
			(arc
				(start 123.573794 -46.863)
				(mid 123.554271 -46.866901)
				(end 123.537726 -46.877986)
			)
			(arc
				(start 123.357386 -47.058326)
				(mid 123.346275 -47.07486)
				(end 123.3424 -47.094394)
			)
			(arc
				(start 123.3424 -79.651606)
				(mid 123.346301 -79.671129)
				(end 123.357386 -79.687674)
			)
			(arc
				(start 123.664726 -79.995014)
				(mid 123.68126 -80.006125)
				(end 123.700794 -80.01)
			)
		)
		(stroke
			(width 0)
			(type solid)
		)
		(fill yes)
		(layer "In4.Cu")
		(net "P52V_HS2_DRAIN_1")
	)
	(gr_poly
		(pts
			(arc
				(start 323.745606 -80.01)
				(mid 323.765129 -80.006099)
				(end 323.781674 -79.995014)
			)
			(arc
				(start 324.089014 -79.687674)
				(mid 324.100125 -79.67114)
				(end 324.104 -79.651606)
			)
			(arc
				(start 324.104 -47.094394)
				(mid 324.100099 -47.074871)
				(end 324.089014 -47.058326)
			)
			(arc
				(start 323.908674 -46.877986)
				(mid 323.89214 -46.866875)
				(end 323.872606 -46.863)
			)
			(arc
				(start 305.3588 -46.863)
				(mid 305.322879 -46.877879)
				(end 305.308 -46.9138)
			)
			(arc
				(start 305.308 -62.2427)
				(mid 305.310753 -62.259197)
				(end 305.318668 -62.273942)
			)
			(arc
				(start 305.318668 -62.273942)
				(mid 305.457939 -62.531362)
				(end 305.50612 -62.820042)
			)
			(arc
				(start 305.50612 -62.820042)
				(mid 305.462479 -63.095027)
				(end 305.33594 -63.343028)
			)
			(arc
				(start 305.33594 -63.343028)
				(mid 305.326181 -63.373)
				(end 305.33594 -63.402972)
			)
			(arc
				(start 305.33594 -63.402972)
				(mid 305.462426 -63.65099)
				(end 305.50612 -63.925958)
			)
			(arc
				(start 305.50612 -63.925958)
				(mid 305.457904 -64.214626)
				(end 305.318668 -64.472058)
			)
			(arc
				(start 305.318668 -64.472058)
				(mid 305.310697 -64.486784)
				(end 305.308 -64.5033)
			)
			(arc
				(start 305.308 -66.78549)
				(mid 305.322879 -66.821411)
				(end 305.3588 -66.83629)
			)
			(arc
				(start 306.81422 -66.83629)
				(mid 306.833245 -66.832593)
				(end 306.849526 -66.822066)
			)
			(arc
				(start 306.849526 -66.822066)
				(mid 307.467 -66.57292)
				(end 308.084474 -66.822066)
			)
			(arc
				(start 308.084474 -66.822066)
				(mid 308.100741 -66.832627)
				(end 308.11978 -66.83629)
			)
			(arc
				(start 309.808372 -66.83629)
				(mid 310.002761 -66.874974)
				(end 310.167528 -66.985134)
			)
			(arc
				(start 311.081166 -67.898772)
				(mid 311.191324 -68.06354)
				(end 311.23001 -68.257928)
			)
			(arc
				(start 311.23001 -79.613252)
				(mid 311.233911 -79.632775)
				(end 311.244996 -79.64932)
			)
			(arc
				(start 311.59069 -79.995014)
				(mid 311.607224 -80.006125)
				(end 311.626758 -80.01)
			)
		)
		(stroke
			(width 0)
			(type solid)
		)
		(fill yes)
		(layer "In4.Cu")
		(net "P52V_HS1_DRAIN_1")
	)
	(gr_poly
		(pts
			(arc
				(start 141.221206 -45.847)
				(mid 141.240729 -45.843099)
				(end 141.257274 -45.832014)
			)
			(arc
				(start 142.123414 -44.965874)
				(mid 142.134525 -44.94934)
				(end 142.1384 -44.929806)
			)
			(arc
				(start 142.1384 -41.667176)
				(mid 142.131291 -41.641003)
				(end 142.11173 -41.622218)
			)
			(arc
				(start 142.11173 -41.622218)
				(mid 141.769734 -41.29524)
				(end 141.643862 -40.839136)
			)
			(arc
				(start 141.643862 -40.839136)
				(mid 141.647416 -40.759442)
				(end 141.658086 -40.680386)
			)
			(xy 141.660372 -40.66794) (xy 141.653006 -40.644318)
			(arc
				(start 141.511274 -40.502586)
				(mid 141.49474 -40.491475)
				(end 141.475206 -40.4876)
			)
			(arc
				(start 139.1666 -40.4876)
				(mid 138.972211 -40.448916)
				(end 138.807444 -40.338756)
			)
			(arc
				(start 137.689844 -39.221156)
				(mid 137.579686 -39.056388)
				(end 137.541 -38.862)
			)
			(arc
				(start 137.541 -33.8328)
				(mid 137.579684 -33.638411)
				(end 137.689844 -33.473644)
			)
			(arc
				(start 137.989564 -33.173924)
				(mid 138.154332 -33.063766)
				(end 138.34872 -33.02508)
			)
			(arc
				(start 139.388596 -33.02508)
				(mid 139.40845 -33.02104)
				(end 139.425172 -33.009586)
			)
			(arc
				(start 139.425172 -33.009586)
				(mid 139.716889 -32.810192)
				(end 140.06322 -32.740092)
			)
			(arc
				(start 140.06322 -32.740092)
				(mid 140.409556 -32.810179)
				(end 140.701268 -33.009586)
			)
			(arc
				(start 140.701268 -33.009586)
				(mid 140.717976 -33.021073)
				(end 140.737844 -33.02508)
			)
			(arc
				(start 141.520926 -33.02508)
				(mid 141.540449 -33.021179)
				(end 141.556994 -33.010094)
			)
			(arc
				(start 142.123414 -32.443674)
				(mid 142.134525 -32.42714)
				(end 142.1384 -32.407606)
			)
			(xy 142.1384 -30.29966)
			(arc
				(start 142.13713 -30.293818)
				(mid 142.119868 -30.194146)
				(end 142.114016 -30.093158)
			)
			(arc
				(start 142.114016 -30.093158)
				(mid 142.119853 -29.992169)
				(end 142.13713 -29.892498)
			)
			(xy 142.1384 -29.886656) (xy 142.1384 -29.193744)
			(arc
				(start 142.13713 -29.187902)
				(mid 142.119868 -29.08823)
				(end 142.114016 -28.987242)
			)
			(arc
				(start 142.114016 -28.987242)
				(mid 142.119853 -28.886253)
				(end 142.13713 -28.786582)
			)
			(xy 142.1384 -28.78074)
			(arc
				(start 142.1384 -13.439394)
				(mid 142.134499 -13.419871)
				(end 142.123414 -13.403326)
			)
			(arc
				(start 141.689074 -12.968986)
				(mid 141.67254 -12.957875)
				(end 141.653006 -12.954)
			)
			(arc
				(start 123.700794 -12.954)
				(mid 123.681271 -12.957901)
				(end 123.664726 -12.968986)
			)
			(arc
				(start 123.357386 -13.276326)
				(mid 123.346275 -13.29286)
				(end 123.3424 -13.312394)
			)
			(arc
				(start 123.3424 -45.615606)
				(mid 123.346301 -45.635129)
				(end 123.357386 -45.651674)
			)
			(arc
				(start 123.537726 -45.832014)
				(mid 123.55426 -45.843125)
				(end 123.573794 -45.847)
			)
		)
		(stroke
			(width 0)
			(type solid)
		)
		(fill yes)
		(layer "In4.Cu")
		(net "P52V_HS2_DRAIN_2")
	)
	(gr_poly
		(pts
			(arc
				(start 323.872606 -45.847)
				(mid 323.892129 -45.843099)
				(end 323.908674 -45.832014)
			)
			(arc
				(start 324.089014 -45.651674)
				(mid 324.100125 -45.63514)
				(end 324.104 -45.615606)
			)
			(arc
				(start 324.104 -13.312394)
				(mid 324.100099 -13.292871)
				(end 324.089014 -13.276326)
			)
			(arc
				(start 323.781674 -12.968986)
				(mid 323.76514 -12.957875)
				(end 323.745606 -12.954)
			)
			(arc
				(start 305.793394 -12.954)
				(mid 305.773871 -12.957901)
				(end 305.757326 -12.968986)
			)
			(arc
				(start 305.322986 -13.403326)
				(mid 305.311875 -13.41986)
				(end 305.308 -13.439394)
			)
			(arc
				(start 305.308 -28.4099)
				(mid 305.310753 -28.426397)
				(end 305.318668 -28.441142)
			)
			(arc
				(start 305.318668 -28.441142)
				(mid 305.457939 -28.698562)
				(end 305.50612 -28.987242)
			)
			(arc
				(start 305.50612 -28.987242)
				(mid 305.462479 -29.262227)
				(end 305.33594 -29.510228)
			)
			(arc
				(start 305.33594 -29.510228)
				(mid 305.326181 -29.5402)
				(end 305.33594 -29.570172)
			)
			(arc
				(start 305.33594 -29.570172)
				(mid 305.462426 -29.81819)
				(end 305.50612 -30.093158)
			)
			(arc
				(start 305.50612 -30.093158)
				(mid 305.457904 -30.381826)
				(end 305.318668 -30.639258)
			)
			(arc
				(start 305.318668 -30.639258)
				(mid 305.310697 -30.653984)
				(end 305.308 -30.6705)
			)
			(arc
				(start 305.308 -32.712406)
				(mid 305.311901 -32.731929)
				(end 305.322986 -32.748474)
			)
			(arc
				(start 305.53152 -32.957008)
				(mid 305.548054 -32.968119)
				(end 305.567588 -32.971994)
			)
			(arc
				(start 306.84851 -32.971994)
				(mid 306.866277 -32.968786)
				(end 306.881784 -32.959548)
			)
			(arc
				(start 306.881784 -32.959548)
				(mid 307.154486 -32.796747)
				(end 307.467 -32.740092)
			)
			(arc
				(start 307.467 -32.740092)
				(mid 307.779529 -32.796708)
				(end 308.052216 -32.959548)
			)
			(arc
				(start 308.052216 -32.959548)
				(mid 308.067731 -32.968763)
				(end 308.08549 -32.971994)
			)
			(arc
				(start 309.723028 -32.971994)
				(mid 309.917417 -33.010678)
				(end 310.082184 -33.120838)
			)
			(arc
				(start 311.103518 -34.142172)
				(mid 311.213676 -34.30694)
				(end 311.252362 -34.501328)
			)
			(arc
				(start 311.252362 -39.039038)
				(mid 311.213678 -39.233427)
				(end 311.103518 -39.398194)
			)
			(arc
				(start 309.629556 -40.872156)
				(mid 309.464788 -40.982314)
				(end 309.2704 -41.021)
			)
			(arc
				(start 305.844194 -41.021)
				(mid 305.824671 -41.024901)
				(end 305.808126 -41.035986)
			)
			(xy 305.748944 -41.095168)
			(arc
				(start 305.745134 -41.102788)
				(mid 305.574995 -41.341081)
				(end 305.336702 -41.51122)
			)
			(xy 305.329082 -41.51503)
			(arc
				(start 305.322986 -41.521126)
				(mid 305.311875 -41.53766)
				(end 305.308 -41.557194)
			)
			(arc
				(start 305.308 -45.158406)
				(mid 305.311901 -45.177929)
				(end 305.322986 -45.194474)
			)
			(arc
				(start 305.960526 -45.832014)
				(mid 305.97706 -45.843125)
				(end 305.996594 -45.847)
			)
		)
		(stroke
			(width 0)
			(type solid)
		)
		(fill yes)
		(layer "In4.Cu")
		(net "P52V_HS1_DRAIN_2")
	)
	(gr_poly
		(pts
			(arc
				(start 301.02302 -66.83629)
				(mid 301.042045 -66.832593)
				(end 301.058326 -66.822066)
			)
			(arc
				(start 301.058326 -66.822066)
				(mid 301.6758 -66.57292)
				(end 302.293274 -66.822066)
			)
			(arc
				(start 302.293274 -66.822066)
				(mid 302.309541 -66.832627)
				(end 302.32858 -66.83629)
			)
			(arc
				(start 304.2412 -66.83629)
				(mid 304.277121 -66.821411)
				(end 304.292 -66.78549)
			)
			(arc
				(start 304.292 -64.788288)
				(mid 304.283711 -64.760477)
				(end 304.26152 -64.741806)
			)
			(arc
				(start 304.26152 -64.741806)
				(mid 303.872207 -64.413764)
				(end 303.726596 -63.925958)
			)
			(arc
				(start 303.726596 -63.925958)
				(mid 303.770237 -63.650973)
				(end 303.896776 -63.402972)
			)
			(arc
				(start 303.896776 -63.402972)
				(mid 303.906535 -63.373)
				(end 303.896776 -63.343028)
			)
			(arc
				(start 303.896776 -63.343028)
				(mid 303.77029 -63.09501)
				(end 303.726596 -62.820042)
			)
			(arc
				(start 303.726596 -62.820042)
				(mid 303.87226 -62.332271)
				(end 304.26152 -62.004194)
			)
			(arc
				(start 304.26152 -62.004194)
				(mid 304.283652 -61.985485)
				(end 304.292 -61.957712)
			)
			(arc
				(start 304.292 -42.065194)
				(mid 304.288099 -42.045671)
				(end 304.277014 -42.029126)
			)
			(xy 303.762918 -41.51503)
			(arc
				(start 303.755298 -41.51122)
				(mid 303.517005 -41.341081)
				(end 303.346866 -41.102788)
			)
			(arc
				(start 303.346866 -41.102788)
				(mid 303.342572 -41.095678)
				(end 303.337214 -41.089326)
			)
			(arc
				(start 303.283874 -41.035986)
				(mid 303.26734 -41.024875)
				(end 303.247806 -41.021)
			)
			(arc
				(start 300.6852 -41.021)
				(mid 300.490811 -40.982316)
				(end 300.326044 -40.872156)
			)
			(arc
				(start 298.809156 -39.355268)
				(mid 298.698998 -39.1905)
				(end 298.660312 -38.996112)
			)
			(arc
				(start 298.660312 -33.576768)
				(mid 298.698996 -33.382379)
				(end 298.809156 -33.217612)
			)
			(arc
				(start 298.90593 -33.120838)
				(mid 299.070698 -33.01068)
				(end 299.265086 -32.971994)
			)
			(arc
				(start 301.05731 -32.971994)
				(mid 301.075077 -32.968786)
				(end 301.090584 -32.959548)
			)
			(arc
				(start 301.090584 -32.959548)
				(mid 301.363286 -32.796747)
				(end 301.6758 -32.740092)
			)
			(arc
				(start 301.6758 -32.740092)
				(mid 301.988329 -32.796708)
				(end 302.261016 -32.959548)
			)
			(arc
				(start 302.261016 -32.959548)
				(mid 302.276531 -32.968763)
				(end 302.29429 -32.971994)
			)
			(arc
				(start 304.007012 -32.971994)
				(mid 304.026535 -32.968093)
				(end 304.04308 -32.957008)
			)
			(arc
				(start 304.277014 -32.723074)
				(mid 304.288125 -32.70654)
				(end 304.292 -32.687006)
			)
			(arc
				(start 304.292 -30.955488)
				(mid 304.283711 -30.927677)
				(end 304.26152 -30.909006)
			)
			(arc
				(start 304.26152 -30.909006)
				(mid 303.872207 -30.580964)
				(end 303.726596 -30.093158)
			)
			(arc
				(start 303.726596 -30.093158)
				(mid 303.770237 -29.818173)
				(end 303.896776 -29.570172)
			)
			(arc
				(start 303.896776 -29.570172)
				(mid 303.906535 -29.5402)
				(end 303.896776 -29.510228)
			)
			(arc
				(start 303.896776 -29.510228)
				(mid 303.77029 -29.26221)
				(end 303.726596 -28.987242)
			)
			(arc
				(start 303.726596 -28.987242)
				(mid 303.87226 -28.499471)
				(end 304.26152 -28.171394)
			)
			(arc
				(start 304.26152 -28.171394)
				(mid 304.283652 -28.152685)
				(end 304.292 -28.124912)
			)
			(arc
				(start 304.292 -13.439394)
				(mid 304.288099 -13.419871)
				(end 304.277014 -13.403326)
			)
			(arc
				(start 303.842674 -12.968986)
				(mid 303.82614 -12.957875)
				(end 303.806606 -12.954)
			)
			(arc
				(start 283.585412 -12.954)
				(mid 283.565889 -12.957901)
				(end 283.549344 -12.968986)
			)
			(arc
				(start 280.176986 -16.341344)
				(mid 280.165875 -16.357878)
				(end 280.162 -16.377412)
			)
			(arc
				(start 280.162 -27.182318)
				(mid 280.123316 -27.376707)
				(end 280.013156 -27.541474)
			)
			(arc
				(start 278.747474 -28.807156)
				(mid 278.582706 -28.917314)
				(end 278.388318 -28.956)
			)
			(arc
				(start 231.371394 -28.956)
				(mid 231.351871 -28.959901)
				(end 231.335326 -28.970986)
			)
			(arc
				(start 229.884986 -30.421326)
				(mid 229.873875 -30.43786)
				(end 229.87 -30.457394)
			)
			(arc
				(start 229.87 -46.758606)
				(mid 229.873901 -46.778129)
				(end 229.884986 -46.794674)
			)
			(arc
				(start 230.446326 -47.356014)
				(mid 230.46286 -47.367125)
				(end 230.482394 -47.371)
			)
			(arc
				(start 242.73256 -47.371)
				(mid 242.752083 -47.367099)
				(end 242.768628 -47.356014)
			)
			(arc
				(start 248.63425 -41.490392)
				(mid 248.799018 -41.380234)
				(end 248.993406 -41.341548)
			)
			(arc
				(start 255.895348 -41.341548)
				(mid 256.089737 -41.380232)
				(end 256.254504 -41.490392)
			)
			(arc
				(start 258.716526 -43.952414)
				(mid 258.73306 -43.963525)
				(end 258.752594 -43.9674)
			)
			(arc
				(start 267.97 -43.9674)
				(mid 268.164389 -44.006084)
				(end 268.329156 -44.116244)
			)
			(arc
				(start 282.490926 -58.278014)
				(mid 282.50746 -58.289125)
				(end 282.526994 -58.293)
			)
			(arc
				(start 293.3954 -58.293)
				(mid 293.589789 -58.331684)
				(end 293.754556 -58.441844)
			)
			(arc
				(start 296.904156 -61.591444)
				(mid 297.014314 -61.756212)
				(end 297.053 -61.9506)
			)
			(arc
				(start 297.053 -65.300606)
				(mid 297.056901 -65.320129)
				(end 297.067986 -65.336674)
			)
			(arc
				(start 298.552616 -66.821304)
				(mid 298.56915 -66.832415)
				(end 298.588684 -66.83629)
			)
		)
		(stroke
			(width 0)
			(type solid)
		)
		(fill yes)
		(layer "In4.Cu")
		(net "P52V_1")
	)
	(gr_poly
		(pts
			(arc
				(start 145.801842 -66.806826)
				(mid 145.819777 -66.803555)
				(end 145.83537 -66.794126)
			)
			(arc
				(start 145.83537 -66.794126)
				(mid 146.10884 -66.630021)
				(end 146.422618 -66.572892)
			)
			(arc
				(start 146.422618 -66.572892)
				(mid 146.736411 -66.629983)
				(end 147.009866 -66.794126)
			)
			(arc
				(start 147.009866 -66.794126)
				(mid 147.025476 -66.80351)
				(end 147.043394 -66.806826)
			)
			(arc
				(start 148.436838 -66.806826)
				(mid 148.456361 -66.802925)
				(end 148.472906 -66.79184)
			)
			(arc
				(start 148.661628 -66.603118)
				(mid 148.672739 -66.586584)
				(end 148.676614 -66.56705)
			)
			(arc
				(start 148.676614 -59.603386)
				(mid 148.715298 -59.408997)
				(end 148.825458 -59.24423)
			)
			(arc
				(start 149.221444 -58.848244)
				(mid 149.386212 -58.738086)
				(end 149.5806 -58.6994)
			)
			(arc
				(start 152.040336 -58.6994)
				(mid 152.234725 -58.738084)
				(end 152.399492 -58.848244)
			)
			(arc
				(start 152.967182 -59.415934)
				(mid 153.07734 -59.580702)
				(end 153.116026 -59.77509)
			)
			(arc
				(start 153.116026 -62.026038)
				(mid 153.124563 -62.054225)
				(end 153.147268 -62.073028)
			)
			(xy 153.161746 -62.079124) (xy 153.191718 -62.073028)
			(arc
				(start 160.253934 -55.010812)
				(mid 160.418702 -54.900654)
				(end 160.61309 -54.861968)
			)
			(arc
				(start 175.379888 -54.861968)
				(mid 175.399411 -54.858067)
				(end 175.415956 -54.846982)
			)
			(arc
				(start 175.779176 -54.483762)
				(mid 175.790287 -54.467228)
				(end 175.794162 -54.447694)
			)
			(arc
				(start 175.794162 -53.658516)
				(mid 175.790261 -53.638993)
				(end 175.779176 -53.622448)
			)
			(arc
				(start 173.785022 -51.628294)
				(mid 173.768488 -51.617183)
				(end 173.748954 -51.613308)
			)
			(arc
				(start 172.583348 -51.613308)
				(mid 172.388959 -51.574624)
				(end 172.224192 -51.464464)
			)
			(arc
				(start 171.815506 -51.055778)
				(mid 171.705348 -50.89101)
				(end 171.666662 -50.696622)
			)
			(arc
				(start 171.666662 -43.570398)
				(mid 171.705346 -43.376009)
				(end 171.815506 -43.211242)
			)
			(arc
				(start 173.556676 -41.470072)
				(mid 173.721444 -41.359914)
				(end 173.915832 -41.321228)
			)
			(arc
				(start 191.747394 -41.321228)
				(mid 191.941783 -41.359912)
				(end 192.10655 -41.470072)
			)
			(arc
				(start 197.992492 -47.356014)
				(mid 198.009026 -47.367125)
				(end 198.02856 -47.371)
			)
			(arc
				(start 209.852006 -47.371)
				(mid 209.871529 -47.367099)
				(end 209.888074 -47.356014)
			)
			(arc
				(start 210.449414 -46.794674)
				(mid 210.460525 -46.77814)
				(end 210.4644 -46.758606)
			)
			(arc
				(start 210.4644 -30.457394)
				(mid 210.460499 -30.437871)
				(end 210.449414 -30.421326)
			)
			(arc
				(start 208.999074 -28.970986)
				(mid 208.98254 -28.959875)
				(end 208.963006 -28.956)
			)
			(arc
				(start 161.946082 -28.956)
				(mid 161.751693 -28.917316)
				(end 161.586926 -28.807156)
			)
			(arc
				(start 160.321244 -27.541474)
				(mid 160.211086 -27.376706)
				(end 160.1724 -27.182318)
			)
			(arc
				(start 160.1724 -16.377412)
				(mid 160.168499 -16.357889)
				(end 160.157414 -16.341344)
			)
			(arc
				(start 156.785056 -12.968986)
				(mid 156.768522 -12.957875)
				(end 156.748988 -12.954)
			)
			(arc
				(start 143.639794 -12.954)
				(mid 143.620271 -12.957901)
				(end 143.603726 -12.968986)
			)
			(arc
				(start 143.169386 -13.403326)
				(mid 143.158275 -13.41986)
				(end 143.1544 -13.439394)
			)
			(xy 143.1544 -28.086558) (xy 143.176752 -28.114498)
			(arc
				(start 143.194278 -28.118308)
				(mid 143.697021 -28.429562)
				(end 143.89354 -28.987242)
			)
			(arc
				(start 143.89354 -28.987242)
				(mid 143.849899 -29.262227)
				(end 143.72336 -29.510228)
			)
			(arc
				(start 143.72336 -29.510228)
				(mid 143.713601 -29.5402)
				(end 143.72336 -29.570172)
			)
			(arc
				(start 143.72336 -29.570172)
				(mid 143.849846 -29.81819)
				(end 143.89354 -30.093158)
			)
			(arc
				(start 143.89354 -30.093158)
				(mid 143.697014 -30.650832)
				(end 143.194278 -30.962092)
			)
			(xy 143.176752 -30.965902) (xy 143.1544 -30.993842)
			(arc
				(start 143.1544 -32.458406)
				(mid 143.158301 -32.477929)
				(end 143.169386 -32.494474)
			)
			(arc
				(start 143.685006 -33.010094)
				(mid 143.70154 -33.021205)
				(end 143.721074 -33.02508)
			)
			(arc
				(start 145.179796 -33.02508)
				(mid 145.19965 -33.02104)
				(end 145.216372 -33.009586)
			)
			(arc
				(start 145.216372 -33.009586)
				(mid 145.508089 -32.810192)
				(end 145.85442 -32.740092)
			)
			(arc
				(start 145.85442 -32.740092)
				(mid 146.200756 -32.810179)
				(end 146.492468 -33.009586)
			)
			(arc
				(start 146.492468 -33.009586)
				(mid 146.509176 -33.021073)
				(end 146.529044 -33.02508)
			)
			(arc
				(start 147.35048 -33.02508)
				(mid 147.544869 -33.063764)
				(end 147.709636 -33.173924)
			)
			(arc
				(start 148.212556 -33.676844)
				(mid 148.322714 -33.841612)
				(end 148.3614 -34.036)
			)
			(arc
				(start 148.3614 -38.3794)
				(mid 148.322716 -38.573789)
				(end 148.212556 -38.738556)
			)
			(arc
				(start 146.612356 -40.338756)
				(mid 146.447588 -40.448914)
				(end 146.2532 -40.4876)
			)
			(arc
				(start 144.292574 -40.4876)
				(mid 144.270175 -40.492805)
				(end 144.252442 -40.507412)
			)
			(xy 144.1958 -40.58031) (xy 144.191228 -40.60317)
			(arc
				(start 144.194276 -40.614854)
				(mid 144.215769 -40.72608)
				(end 144.222978 -40.839136)
			)
			(arc
				(start 144.222978 -40.839136)
				(mid 143.962447 -41.468113)
				(end 143.33347 -41.728644)
			)
			(arc
				(start 143.33347 -41.728644)
				(mid 143.298644 -41.727932)
				(end 143.263874 -41.72585)
			)
			(xy 143.253206 -41.725088) (xy 143.233394 -41.731946)
			(arc
				(start 143.170656 -41.789858)
				(mid 143.158592 -41.806821)
				(end 143.1544 -41.827196)
			)
			(xy 143.1544 -61.919358) (xy 143.176752 -61.947298)
			(arc
				(start 143.194278 -61.951108)
				(mid 143.697021 -62.262362)
				(end 143.89354 -62.820042)
			)
			(arc
				(start 143.89354 -62.820042)
				(mid 143.849899 -63.095027)
				(end 143.72336 -63.343028)
			)
			(arc
				(start 143.72336 -63.343028)
				(mid 143.713601 -63.373)
				(end 143.72336 -63.402972)
			)
			(arc
				(start 143.72336 -63.402972)
				(mid 143.849846 -63.65099)
				(end 143.89354 -63.925958)
			)
			(arc
				(start 143.89354 -63.925958)
				(mid 143.697014 -64.483632)
				(end 143.194278 -64.794892)
			)
			(xy 143.176752 -64.798702) (xy 143.1544 -64.826642)
			(arc
				(start 143.1544 -66.756026)
				(mid 143.169279 -66.791947)
				(end 143.2052 -66.806826)
			)
		)
		(stroke
			(width 0)
			(type solid)
		)
		(fill yes)
		(layer "In4.Cu")
		(net "P52V_2")
	)
	(gr_poly
		(pts
			(xy 474.000068 -199.098154) (xy 474.055876 -199.097646) (xy 474.167179 -199.089307) (xy 474.277548 -199.072673)
			(xy 474.386365 -199.047838) (xy 474.493022 -199.01494) (xy 474.596923 -198.974164) (xy 474.697485 -198.925736)
			(xy 474.794147 -198.869929) (xy 474.886368 -198.807054) (xy 474.973633 -198.737463) (xy 475.055452 -198.661545)
			(xy 475.13137 -198.579725) (xy 475.20096 -198.49246) (xy 475.263834 -198.400239) (xy 475.319641 -198.303576)
			(xy 475.368068 -198.203014) (xy 475.408844 -198.099113) (xy 475.441741 -197.992456) (xy 475.466575 -197.883638)
			(xy 475.483208 -197.773269) (xy 475.491546 -197.661966) (xy 475.492064 -197.606158) (xy 475.492064 -135.770112)
			(xy 475.491555 -135.714305) (xy 475.483215 -135.603002) (xy 475.46658 -135.492634) (xy 475.441744 -135.383817)
			(xy 475.408845 -135.277161) (xy 475.368068 -135.173262) (xy 475.31964 -135.072701) (xy 475.263833 -134.97604)
			(xy 475.200958 -134.88382) (xy 475.131367 -134.796556) (xy 475.055449 -134.714737) (xy 474.973629 -134.63882)
			(xy 474.886364 -134.569231) (xy 474.794143 -134.506357) (xy 474.697481 -134.450551) (xy 474.596919 -134.402124)
			(xy 474.49302 -134.361348) (xy 474.386363 -134.328451) (xy 474.277546 -134.303616) (xy 474.167178 -134.286983)
			(xy 474.055875 -134.278644) (xy 474.000068 -134.278116) (xy 444.999872 -134.278116) (xy 444.929968 -134.278612)
			(xy 444.790381 -134.286463) (xy 444.651454 -134.302127) (xy 444.513624 -134.325555) (xy 444.377323 -134.356674)
			(xy 444.242982 -134.395385) (xy 444.111022 -134.441566) (xy 443.981859 -134.495074) (xy 443.855899 -134.555738)
			(xy 443.733538 -134.623368) (xy 443.615161 -134.697752) (xy 443.50114 -134.778656) (xy 443.391834 -134.865825)
			(xy 443.287587 -134.958985) (xy 443.188727 -135.057842) (xy 443.095565 -135.162087) (xy 443.008393 -135.27139)
			(xy 442.927487 -135.385409) (xy 442.8531 -135.503784) (xy 442.785466 -135.626144) (xy 442.724799 -135.752102)
			(xy 442.671289 -135.881264) (xy 442.625104 -136.013223) (xy 442.586389 -136.147563) (xy 442.555267 -136.283863)
			(xy 442.531836 -136.421693) (xy 442.516168 -136.56062) (xy 442.508314 -136.700206) (xy 442.507878 -136.77011)
			(xy 442.507878 -153.299922) (xy 442.507375 -153.422774) (xy 442.499335 -153.668345) (xy 442.483265 -153.913522)
			(xy 442.459181 -154.158042) (xy 442.42711 -154.401643) (xy 442.387085 -154.644065) (xy 442.33915 -154.885047)
			(xy 442.283356 -155.124331) (xy 442.219763 -155.361662) (xy 442.148438 -155.596785) (xy 442.069459 -155.829449)
			(xy 441.982909 -156.059404) (xy 441.888882 -156.286404) (xy 441.787478 -156.510205) (xy 441.678806 -156.73057)
			(xy 441.562982 -156.94726) (xy 441.44013 -157.160045) (xy 441.310381 -157.368697) (xy 441.173875 -157.572991)
			(xy 441.030758 -157.77271) (xy 440.881183 -157.967639) (xy 440.72531 -158.15757) (xy 440.563307 -158.342299)
			(xy 440.395346 -158.521628) (xy 440.221607 -158.695366) (xy 440.042277 -158.863327) (xy 439.857547 -159.02533)
			(xy 439.667615 -159.181202) (xy 439.472686 -159.330776) (xy 439.272966 -159.473893) (xy 439.068671 -159.610398)
			(xy 438.860019 -159.740145) (xy 438.647234 -159.862996) (xy 438.430543 -159.97882) (xy 438.210178 -160.087491)
			(xy 437.986376 -160.188894) (xy 437.759376 -160.28292) (xy 437.52942 -160.369469) (xy 437.296757 -160.448447)
			(xy 437.061633 -160.519771) (xy 436.824302 -160.583363) (xy 436.585017 -160.639156) (xy 436.344035 -160.68709)
			(xy 436.101614 -160.727114) (xy 435.858012 -160.759184) (xy 435.613492 -160.783267) (xy 435.368315 -160.799337)
			(xy 435.122744 -160.807376) (xy 434.999892 -160.807908) (xy 416.576256 -160.807908) (xy 416.506352 -160.808399)
			(xy 416.366764 -160.816241) (xy 416.227835 -160.831897) (xy 416.090003 -160.855317) (xy 415.9537 -160.88643)
			(xy 415.819357 -160.925136) (xy 415.687395 -160.971313) (xy 415.55823 -161.024817) (xy 415.432268 -161.085479)
			(xy 415.309905 -161.153108) (xy 415.191527 -161.227492) (xy 415.077506 -161.308396) (xy 414.968201 -161.395567)
			(xy 414.863955 -161.488728) (xy 414.765097 -161.587588) (xy 414.671937 -161.691836) (xy 414.584769 -161.801143)
			(xy 414.503867 -161.915166) (xy 414.429485 -162.033545) (xy 414.361858 -162.155909) (xy 414.301198 -162.281872)
			(xy 414.247697 -162.411038) (xy 414.201522 -162.543001) (xy 414.162818 -162.677345) (xy 414.131708 -162.813648)
			(xy 414.10829 -162.951481) (xy 414.092637 -163.09041) (xy 414.084798 -163.229998) (xy 414.084262 -163.299902)
			(xy 414.084262 -187.606178) (xy 414.083778 -187.676532) (xy 414.07589 -187.817019) (xy 414.060137 -187.956842)
			(xy 414.036568 -188.095562) (xy 414.005258 -188.232743) (xy 413.966306 -188.367952) (xy 413.919834 -188.500764)
			(xy 413.865987 -188.630762) (xy 413.804937 -188.757535) (xy 413.736874 -188.880686) (xy 413.662013 -188.999827)
			(xy 413.580589 -189.114583) (xy 413.492859 -189.224593) (xy 413.399098 -189.329511) (xy 413.299602 -189.429006)
			(xy 413.194684 -189.522766) (xy 413.084674 -189.610496) (xy 412.969917 -189.691919) (xy 412.850776 -189.76678)
			(xy 412.727625 -189.834842) (xy 412.600851 -189.895892) (xy 412.470853 -189.949738) (xy 412.33804 -189.99621)
			(xy 412.202831 -190.035161) (xy 412.065651 -190.06647) (xy 411.92693 -190.090038) (xy 411.787107 -190.105791)
			(xy 411.64662 -190.113679) (xy 411.576266 -190.114174) (xy 351.499932 -190.114174) (xy 351.429578 -190.113691)
			(xy 351.28909 -190.105803) (xy 351.149266 -190.09005) (xy 351.010545 -190.066482) (xy 350.873364 -190.035172)
			(xy 350.738154 -189.996221) (xy 350.605341 -189.949748) (xy 350.475343 -189.895903) (xy 350.348569 -189.834852)
			(xy 350.225417 -189.766789) (xy 350.106275 -189.691929) (xy 349.991518 -189.610505) (xy 349.881507 -189.522775)
			(xy 349.776589 -189.429014) (xy 349.677092 -189.329519) (xy 349.583332 -189.2246) (xy 349.495601 -189.11459)
			(xy 349.414177 -188.999833) (xy 349.339316 -188.880692) (xy 349.271252 -188.75754) (xy 349.210202 -188.630766)
			(xy 349.156355 -188.500768) (xy 349.109883 -188.367955) (xy 349.07093 -188.232746) (xy 349.03962 -188.095565)
			(xy 349.016052 -187.956844) (xy 349.000298 -187.81702) (xy 348.99241 -187.676532) (xy 348.991936 -187.606178)
			(xy 348.991936 -110.499906) (xy 348.991437 -110.399374) (xy 348.983341 -110.198474) (xy 348.967162 -109.998063)
			(xy 348.942927 -109.798466) (xy 348.910674 -109.600006) (xy 348.870457 -109.403006) (xy 348.822339 -109.207786)
			(xy 348.7664 -109.014661) (xy 348.702729 -108.823945) (xy 348.631431 -108.635948) (xy 348.552621 -108.450974)
			(xy 348.466427 -108.269323) (xy 348.372988 -108.09129) (xy 348.272456 -107.917165) (xy 348.164995 -107.747228)
			(xy 348.050777 -107.581757) (xy 347.92999 -107.421018) (xy 347.802828 -107.265274) (xy 347.669498 -107.114776)
			(xy 347.530217 -106.969769) (xy 347.385209 -106.830488) (xy 347.234711 -106.697159) (xy 347.078966 -106.569998)
			(xy 346.918227 -106.449211) (xy 346.752755 -106.334994) (xy 346.582818 -106.227533) (xy 346.408692 -106.127002)
			(xy 346.230659 -106.033564) (xy 346.049008 -105.947371) (xy 345.864034 -105.868561) (xy 345.676036 -105.797264)
			(xy 345.48532 -105.733594) (xy 345.292195 -105.677656) (xy 345.096974 -105.629539) (xy 344.899974 -105.589322)
			(xy 344.701514 -105.55707) (xy 344.501917 -105.532836) (xy 344.301506 -105.516658) (xy 344.100606 -105.508563)
			(xy 344.000074 -105.508044) (xy 293.310056 -105.508044) (xy 293.254251 -105.508567) (xy 293.142952 -105.516911)
			(xy 293.032588 -105.533549) (xy 292.923776 -105.558388) (xy 292.817125 -105.591289) (xy 292.713231 -105.632068)
			(xy 292.612674 -105.680497) (xy 292.516018 -105.736305) (xy 292.423802 -105.799181) (xy 292.336543 -105.868771)
			(xy 292.254729 -105.944688) (xy 292.178817 -106.026507) (xy 292.109231 -106.11377) (xy 292.046361 -106.205989)
			(xy 291.990558 -106.302648) (xy 291.942135 -106.403208) (xy 291.901361 -106.507104) (xy 291.868466 -106.613758)
			(xy 291.843634 -106.722571) (xy 291.827002 -106.832936) (xy 291.818664 -106.944235) (xy 291.81806 -107.00004)
			(xy 291.81806 -121.780046) (xy 291.817562 -121.863539) (xy 291.809615 -122.030336) (xy 291.793739 -122.196566)
			(xy 291.769973 -122.361852) (xy 291.738368 -122.52582) (xy 291.698998 -122.688098) (xy 291.65195 -122.848319)
			(xy 291.597333 -123.006121) (xy 291.535268 -123.161144) (xy 291.465898 -123.313039) (xy 291.389379 -123.461461)
			(xy 291.305884 -123.606075) (xy 291.215603 -123.746551) (xy 291.11874 -123.882573) (xy 291.015514 -124.013832)
			(xy 290.90616 -124.14003) (xy 290.790925 -124.260882) (xy 290.670071 -124.376114) (xy 290.54387 -124.485465)
			(xy 290.412609 -124.588688) (xy 290.276585 -124.685548) (xy 290.136106 -124.775826) (xy 289.991491 -124.859317)
			(xy 289.843067 -124.935833) (xy 289.691171 -125.0052) (xy 289.536146 -125.067261) (xy 289.378343 -125.121875)
			(xy 289.218121 -125.168919) (xy 289.055841 -125.208285) (xy 288.891873 -125.239886) (xy 288.726586 -125.263649)
			(xy 288.560356 -125.27952) (xy 288.393559 -125.287464) (xy 288.310066 -125.28804) (xy 139.910058 -125.28804)
			(xy 139.826564 -125.287542) (xy 139.659766 -125.279595) (xy 139.493535 -125.26372) (xy 139.328247 -125.239954)
			(xy 139.164277 -125.20835) (xy 139.001997 -125.168979) (xy 138.841774 -125.121932) (xy 138.683971 -125.067315)
			(xy 138.528946 -125.005251) (xy 138.377049 -124.935881) (xy 138.228625 -124.859362) (xy 138.08401 -124.775868)
			(xy 137.943531 -124.685588) (xy 137.807507 -124.588725) (xy 137.676246 -124.4855) (xy 137.550046 -124.376146)
			(xy 137.429191 -124.260912) (xy 137.313956 -124.140057) (xy 137.204603 -124.013857) (xy 137.101377 -123.882596)
			(xy 137.004515 -123.746572) (xy 136.914234 -123.606094) (xy 136.830739 -123.461479) (xy 136.75422 -123.313055)
			(xy 136.68485 -123.161158) (xy 136.622786 -123.006132) (xy 136.568169 -122.848329) (xy 136.521122 -122.688106)
			(xy 136.481751 -122.525826) (xy 136.450147 -122.361857) (xy 136.42638 -122.196569) (xy 136.410505 -122.030338)
			(xy 136.402558 -121.86354) (xy 136.402064 -121.780046) (xy 136.402064 -107.00004) (xy 136.401556 -106.944232)
			(xy 136.393218 -106.832928) (xy 136.376585 -106.722558) (xy 136.35175 -106.61374) (xy 136.318853 -106.507082)
			(xy 136.278076 -106.403181) (xy 136.229649 -106.302618) (xy 136.173842 -106.205955) (xy 136.110967 -106.113733)
			(xy 136.041377 -106.026468) (xy 135.965459 -105.944647) (xy 135.883638 -105.868729) (xy 135.796373 -105.799137)
			(xy 135.704152 -105.736262) (xy 135.607489 -105.680455) (xy 135.506926 -105.632027) (xy 135.403025 -105.59125)
			(xy 135.296368 -105.558352) (xy 135.18755 -105.533517) (xy 135.07718 -105.516883) (xy 134.965876 -105.508544)
			(xy 134.910068 -105.508044) (xy 95.999808 -105.508044) (xy 95.899276 -105.508543) (xy 95.698376 -105.516639)
			(xy 95.497964 -105.532817) (xy 95.298366 -105.557053) (xy 95.099907 -105.589305) (xy 94.902906 -105.629523)
			(xy 94.707685 -105.67764) (xy 94.51456 -105.73358) (xy 94.323844 -105.79725) (xy 94.135846 -105.868548)
			(xy 93.950872 -105.947358) (xy 93.769221 -106.033552) (xy 93.591188 -106.126991) (xy 93.417061 -106.227522)
			(xy 93.247124 -106.334984) (xy 93.081652 -106.449201) (xy 92.920913 -106.569988) (xy 92.765169 -106.69715)
			(xy 92.61467 -106.83048) (xy 92.469663 -106.969761) (xy 92.330381 -107.114769) (xy 92.197051 -107.265267)
			(xy 92.06989 -107.421012) (xy 91.949102 -107.581751) (xy 91.834885 -107.747223) (xy 91.727424 -107.91716)
			(xy 91.626892 -108.091286) (xy 91.533453 -108.269319) (xy 91.447259 -108.45097) (xy 91.368448 -108.635944)
			(xy 91.29715 -108.823942) (xy 91.23348 -109.014658) (xy 91.177541 -109.207783) (xy 91.129423 -109.403004)
			(xy 91.089206 -109.600005) (xy 91.056953 -109.798465) (xy 91.032718 -109.998062) (xy 91.016539 -110.198474)
			(xy 91.008443 -110.399374) (xy 91.007946 -110.499906) (xy 91.007946 -187.606178) (xy 91.007462 -187.676532)
			(xy 90.999574 -187.817018) (xy 90.983821 -187.956841) (xy 90.960252 -188.095561) (xy 90.928942 -188.232741)
			(xy 90.88999 -188.36795) (xy 90.843517 -188.500762) (xy 90.789671 -188.630759) (xy 90.72862 -188.757532)
			(xy 90.660557 -188.880683) (xy 90.585696 -188.999823) (xy 90.504272 -189.114579) (xy 90.416542 -189.224588)
			(xy 90.322781 -189.329506) (xy 90.223285 -189.429) (xy 90.118367 -189.52276) (xy 90.008357 -189.610489)
			(xy 89.8936 -189.691911) (xy 89.774459 -189.766771) (xy 89.651307 -189.834833) (xy 89.524533 -189.895882)
			(xy 89.394536 -189.949727) (xy 89.261723 -189.996198) (xy 89.126514 -190.035149) (xy 88.989334 -190.066457)
			(xy 88.850614 -190.090024) (xy 88.71079 -190.105776) (xy 88.570304 -190.113663) (xy 88.49995 -190.114174)
			(xy 28.42387 -190.114174) (xy 28.353517 -190.11368) (xy 28.213033 -190.105789) (xy 28.073211 -190.090033)
			(xy 27.934494 -190.066462) (xy 27.797316 -190.035151) (xy 27.66211 -189.996197) (xy 27.5293 -189.949723)
			(xy 27.399305 -189.895876) (xy 27.272534 -189.834824) (xy 27.149386 -189.766761) (xy 27.030248 -189.691899)
			(xy 26.915494 -189.610476) (xy 26.805487 -189.522746) (xy 26.700572 -189.428986) (xy 26.601078 -189.329491)
			(xy 26.507321 -189.224573) (xy 26.419593 -189.114564) (xy 26.338172 -188.999809) (xy 26.263313 -188.880669)
			(xy 26.195252 -188.757519) (xy 26.134203 -188.630747) (xy 26.080358 -188.500751) (xy 26.033887 -188.367941)
			(xy 25.994936 -188.232734) (xy 25.963628 -188.095555) (xy 25.94006 -187.956837) (xy 25.924307 -187.817016)
			(xy 25.916419 -187.676531) (xy 25.915874 -187.606178) (xy 25.915874 -163.299902) (xy 25.915393 -163.229997)
			(xy 25.907553 -163.090407) (xy 25.8919 -162.951476) (xy 25.868481 -162.813642) (xy 25.83737 -162.677337)
			(xy 25.798666 -162.542992) (xy 25.752489 -162.411028) (xy 25.698986 -162.28186) (xy 25.638325 -162.155896)
			(xy 25.570696 -162.033531) (xy 25.496312 -161.915151) (xy 25.415408 -161.801128) (xy 25.328237 -161.69182)
			(xy 25.235075 -161.587572) (xy 25.136214 -161.488712) (xy 25.031966 -161.395551) (xy 24.922658 -161.308381)
			(xy 24.808634 -161.227478) (xy 24.690253 -161.153095) (xy 24.567888 -161.085467) (xy 24.441923 -161.024807)
			(xy 24.312756 -160.971304) (xy 24.180791 -160.925129) (xy 24.046445 -160.886426) (xy 23.91014 -160.855316)
			(xy 23.772306 -160.831898) (xy 23.633375 -160.816245) (xy 23.493785 -160.808407) (xy 23.42388 -160.807908)
			(xy 1.999996 -160.807908) (xy 1.944189 -160.80843) (xy 1.832887 -160.816771) (xy 1.72252 -160.833407)
			(xy 1.613705 -160.858243) (xy 1.50705 -160.891142) (xy 1.403152 -160.93192) (xy 1.302591 -160.980347)
			(xy 1.205931 -161.036154) (xy 1.113712 -161.099029) (xy 1.026449 -161.168619) (xy 0.94463 -161.244536)
			(xy 0.868714 -161.326355) (xy 0.799124 -161.413618) (xy 0.73625 -161.505838) (xy 0.680444 -161.602499)
			(xy 0.632016 -161.703059) (xy 0.59124 -161.806958) (xy 0.558341 -161.913613) (xy 0.533505 -162.022428)
			(xy 0.51687 -162.132795) (xy 0.50853 -162.244097) (xy 0.508 -162.299904) (xy 0.508 -194.670734) (xy 2.904225 -194.670734)
			(xy 2.904225 -194.541594) (xy 2.912175 -194.412699) (xy 2.928045 -194.284539) (xy 2.951774 -194.157598)
			(xy 2.983273 -194.032359) (xy 3.022422 -193.909296) (xy 3.069073 -193.788877) (xy 3.123048 -193.671558)
			(xy 3.184143 -193.557784) (xy 3.252126 -193.447987) (xy 3.32674 -193.342584) (xy 3.407701 -193.241974)
			(xy 3.494701 -193.146539) (xy 3.587412 -193.05664) (xy 3.685482 -192.972619) (xy 3.788537 -192.894795)
			(xy 3.896188 -192.823463) (xy 4.008027 -192.758893) (xy 4.123628 -192.701331) (xy 4.242553 -192.650994)
			(xy 4.364352 -192.608074) (xy 4.488562 -192.572733) (xy 4.614711 -192.545106) (xy 4.742323 -192.525297)
			(xy 4.870912 -192.513381) (xy 4.99999 -192.509405) (xy 5.129068 -192.513381) (xy 5.257657 -192.525297)
			(xy 5.385269 -192.545106) (xy 5.511418 -192.572733) (xy 5.635628 -192.608074) (xy 5.757427 -192.650994)
			(xy 5.876352 -192.701331) (xy 5.991953 -192.758893) (xy 6.103792 -192.823463) (xy 6.211443 -192.894795)
			(xy 6.314498 -192.972619) (xy 6.412568 -193.05664) (xy 6.505279 -193.146539) (xy 6.592279 -193.241974)
			(xy 6.67324 -193.342584) (xy 6.747854 -193.447987) (xy 6.815837 -193.557784) (xy 6.876932 -193.671558)
			(xy 6.930907 -193.788877) (xy 6.977558 -193.909296) (xy 7.016707 -194.032359) (xy 7.048206 -194.157598)
			(xy 7.071935 -194.284539) (xy 7.087805 -194.412699) (xy 7.095755 -194.541594) (xy 7.096252 -194.606164)
			(xy 7.095755 -194.670734) (xy 468.904309 -194.670734) (xy 468.904309 -194.541594) (xy 468.912259 -194.412699)
			(xy 468.928129 -194.284539) (xy 468.951858 -194.157598) (xy 468.983357 -194.032359) (xy 469.022506 -193.909296)
			(xy 469.069157 -193.788877) (xy 469.123132 -193.671558) (xy 469.184227 -193.557784) (xy 469.25221 -193.447987)
			(xy 469.326824 -193.342584) (xy 469.407785 -193.241974) (xy 469.494785 -193.146539) (xy 469.587496 -193.05664)
			(xy 469.685566 -192.972619) (xy 469.788621 -192.894795) (xy 469.896272 -192.823463) (xy 470.008111 -192.758893)
			(xy 470.123712 -192.701331) (xy 470.242637 -192.650994) (xy 470.364436 -192.608074) (xy 470.488646 -192.572733)
			(xy 470.614795 -192.545106) (xy 470.742407 -192.525297) (xy 470.870996 -192.513381) (xy 471.000074 -192.509405)
			(xy 471.129152 -192.513381) (xy 471.257741 -192.525297) (xy 471.385353 -192.545106) (xy 471.511502 -192.572733)
			(xy 471.635712 -192.608074) (xy 471.757511 -192.650994) (xy 471.876436 -192.701331) (xy 471.992037 -192.758893)
			(xy 472.103876 -192.823463) (xy 472.211527 -192.894795) (xy 472.314582 -192.972619) (xy 472.412652 -193.05664)
			(xy 472.505363 -193.146539) (xy 472.592363 -193.241974) (xy 472.673324 -193.342584) (xy 472.747938 -193.447987)
			(xy 472.815921 -193.557784) (xy 472.877016 -193.671558) (xy 472.930991 -193.788877) (xy 472.977642 -193.909296)
			(xy 473.016791 -194.032359) (xy 473.04829 -194.157598) (xy 473.072019 -194.284539) (xy 473.087889 -194.412699)
			(xy 473.095839 -194.541594) (xy 473.096336 -194.606164) (xy 473.095839 -194.670734) (xy 473.087889 -194.799629)
			(xy 473.072019 -194.927789) (xy 473.04829 -195.05473) (xy 473.016791 -195.179969) (xy 472.977642 -195.303032)
			(xy 472.930991 -195.423451) (xy 472.877016 -195.54077) (xy 472.815921 -195.654544) (xy 472.747938 -195.764341)
			(xy 472.673324 -195.869744) (xy 472.592363 -195.970354) (xy 472.505363 -196.065789) (xy 472.412652 -196.155688)
			(xy 472.314582 -196.239709) (xy 472.211527 -196.317533) (xy 472.103876 -196.388865) (xy 471.992037 -196.453435)
			(xy 471.876436 -196.510997) (xy 471.757511 -196.561334) (xy 471.635712 -196.604254) (xy 471.511502 -196.639595)
			(xy 471.385353 -196.667222) (xy 471.257741 -196.687031) (xy 471.129152 -196.698947) (xy 471.000074 -196.702924)
			(xy 470.870996 -196.698947) (xy 470.742407 -196.687031) (xy 470.614795 -196.667222) (xy 470.488646 -196.639595)
			(xy 470.364436 -196.604254) (xy 470.242637 -196.561334) (xy 470.123712 -196.510997) (xy 470.008111 -196.453435)
			(xy 469.896272 -196.388865) (xy 469.788621 -196.317533) (xy 469.685566 -196.239709) (xy 469.587496 -196.155688)
			(xy 469.494785 -196.065789) (xy 469.407785 -195.970354) (xy 469.326824 -195.869744) (xy 469.25221 -195.764341)
			(xy 469.184227 -195.654544) (xy 469.123132 -195.54077) (xy 469.069157 -195.423451) (xy 469.022506 -195.303032)
			(xy 468.983357 -195.179969) (xy 468.951858 -195.05473) (xy 468.928129 -194.927789) (xy 468.912259 -194.799629)
			(xy 468.904309 -194.670734) (xy 7.095755 -194.670734) (xy 7.087805 -194.799629) (xy 7.071935 -194.927789)
			(xy 7.048206 -195.05473) (xy 7.016707 -195.179969) (xy 6.977558 -195.303032) (xy 6.930907 -195.423451)
			(xy 6.876932 -195.54077) (xy 6.815837 -195.654544) (xy 6.747854 -195.764341) (xy 6.67324 -195.869744)
			(xy 6.592279 -195.970354) (xy 6.505279 -196.065789) (xy 6.412568 -196.155688) (xy 6.314498 -196.239709)
			(xy 6.211443 -196.317533) (xy 6.103792 -196.388865) (xy 5.991953 -196.453435) (xy 5.876352 -196.510997)
			(xy 5.757427 -196.561334) (xy 5.635628 -196.604254) (xy 5.511418 -196.639595) (xy 5.385269 -196.667222)
			(xy 5.257657 -196.687031) (xy 5.129068 -196.698947) (xy 4.99999 -196.702924) (xy 4.870912 -196.698947)
			(xy 4.742323 -196.687031) (xy 4.614711 -196.667222) (xy 4.488562 -196.639595) (xy 4.364352 -196.604254)
			(xy 4.242553 -196.561334) (xy 4.123628 -196.510997) (xy 4.008027 -196.453435) (xy 3.896188 -196.388865)
			(xy 3.788537 -196.317533) (xy 3.685482 -196.239709) (xy 3.587412 -196.155688) (xy 3.494701 -196.065789)
			(xy 3.407701 -195.970354) (xy 3.32674 -195.869744) (xy 3.252126 -195.764341) (xy 3.184143 -195.654544)
			(xy 3.123048 -195.54077) (xy 3.069073 -195.423451) (xy 3.022422 -195.303032) (xy 2.983273 -195.179969)
			(xy 2.951774 -195.05473) (xy 2.928045 -194.927789) (xy 2.912175 -194.799629) (xy 2.904225 -194.670734)
			(xy 0.508 -194.670734) (xy 0.508 -197.606158) (xy 0.508522 -197.661965) (xy 0.516863 -197.773267)
			(xy 0.533498 -197.883634) (xy 0.558335 -197.99245) (xy 0.591234 -198.099105) (xy 0.632011 -198.203004)
			(xy 0.680438 -198.303564) (xy 0.736246 -198.400225) (xy 0.79912 -198.492445) (xy 0.86871 -198.579708)
			(xy 0.944627 -198.661527) (xy 1.026446 -198.737444) (xy 1.113709 -198.807034) (xy 1.205929 -198.869908)
			(xy 1.30259 -198.925716) (xy 1.40315 -198.974143) (xy 1.507049 -199.01492) (xy 1.613704 -199.047819)
			(xy 1.72252 -199.072656) (xy 1.832887 -199.089291) (xy 1.944189 -199.097632) (xy 1.999996 -199.098154)
		)
		(stroke
			(width 0)
			(type solid)
		)
		(fill yes)
		(layer "In4.Cu")
		(net "GND3")
	)
	(gr_poly
		(pts
			(xy 8.69061 -157.283912) (xy 8.701029 -157.283399) (xy 8.720158 -157.275126) (xy 8.727694 -157.26791)
			(xy 8.747468 -157.24764) (xy 8.791935 -157.212581) (xy 8.841096 -157.184481) (xy 8.893871 -157.163956)
			(xy 8.9491 -157.151458) (xy 9.00557 -157.147261) (xy 9.06204 -157.151458) (xy 9.117269 -157.163956)
			(xy 9.170044 -157.184481) (xy 9.219205 -157.212581) (xy 9.263672 -157.24764) (xy 9.283446 -157.26791)
			(xy 9.290947 -157.275171) (xy 9.3101 -157.283424) (xy 9.32053 -157.283912) (xy 13.77061 -157.283912)
			(xy 13.781029 -157.283399) (xy 13.800158 -157.275126) (xy 13.807694 -157.26791) (xy 13.827468 -157.24764)
			(xy 13.871935 -157.212581) (xy 13.921096 -157.184481) (xy 13.973871 -157.163956) (xy 14.0291 -157.151458)
			(xy 14.08557 -157.147261) (xy 14.14204 -157.151458) (xy 14.197269 -157.163956) (xy 14.250044 -157.184481)
			(xy 14.299205 -157.212581) (xy 14.343672 -157.24764) (xy 14.363446 -157.26791) (xy 14.370947 -157.275171)
			(xy 14.3901 -157.283424) (xy 14.40053 -157.283912) (xy 18.85061 -157.283912) (xy 18.861029 -157.283399)
			(xy 18.880158 -157.275126) (xy 18.887694 -157.26791) (xy 18.907468 -157.24764) (xy 18.951935 -157.212581)
			(xy 19.001096 -157.184481) (xy 19.053871 -157.163956) (xy 19.1091 -157.151458) (xy 19.16557 -157.147261)
			(xy 19.22204 -157.151458) (xy 19.277269 -157.163956) (xy 19.330044 -157.184481) (xy 19.379205 -157.212581)
			(xy 19.423672 -157.24764) (xy 19.443446 -157.26791) (xy 19.450947 -157.275171) (xy 19.4701 -157.283424)
			(xy 19.48053 -157.283912) (xy 21.99767 -157.283912) (xy 22.007735 -157.283477) (xy 22.026322 -157.275746)
			(xy 22.033738 -157.268926) (xy 22.689566 -156.613098) (xy 22.696416 -156.605701) (xy 22.704155 -156.587103)
			(xy 22.704552 -156.57703) (xy 22.704552 -44.961048) (xy 22.70507 -44.927786) (xy 22.713751 -44.861832)
			(xy 22.730971 -44.797577) (xy 22.756434 -44.73612) (xy 22.789704 -44.678515) (xy 22.830212 -44.625747)
			(xy 22.853396 -44.601892) (xy 33.29686 -34.158428) (xy 33.30448 -34.137092) (xy 33.30321 -34.125662)
			(xy 33.301137 -34.103305) (xy 33.298976 -34.058453) (xy 33.298892 -34.036) (xy 33.299367 -33.994898)
			(xy 33.306952 -33.913043) (xy 33.322057 -33.832238) (xy 33.344553 -33.753171) (xy 33.374249 -33.676517)
			(xy 33.410891 -33.60293) (xy 33.454166 -33.533038) (xy 33.503706 -33.467437) (xy 33.559087 -33.406687)
			(xy 33.619837 -33.351306) (xy 33.685438 -33.301766) (xy 33.75533 -33.258491) (xy 33.828917 -33.221849)
			(xy 33.905571 -33.192153) (xy 33.984638 -33.169657) (xy 34.065443 -33.154552) (xy 34.147298 -33.146967)
			(xy 34.1884 -33.146492) (xy 34.211427 -33.146595) (xy 34.257424 -33.148881) (xy 34.280348 -33.151064)
			(xy 34.290624 -33.151678) (xy 34.310288 -33.145654) (xy 34.318448 -33.13938) (xy 34.341386 -33.12062)
			(xy 34.390857 -33.087996) (xy 34.443787 -33.061348) (xy 34.499458 -33.041039) (xy 34.557113 -33.027344)
			(xy 34.61597 -33.02045) (xy 34.6456 -33.02) (xy 57.66181 -33.02) (xy 57.671879 -33.019575) (xy 57.690481 -33.011858)
			(xy 57.697878 -33.005014) (xy 57.793636 -32.909256) (xy 57.801256 -32.890206) (xy 57.800748 -32.879538)
			(xy 57.800494 -32.85871) (xy 57.800494 -22.431502) (xy 57.800153 -22.422615) (xy 57.794057 -22.405919)
			(xy 57.782606 -22.392326) (xy 57.775094 -22.38756) (xy 57.719579 -22.354802) (xy 57.612238 -22.283409)
			(xy 57.509488 -22.205552) (xy 57.411717 -22.121528) (xy 57.319296 -22.031654) (xy 57.232573 -21.936269)
			(xy 57.151877 -21.835734) (xy 57.077513 -21.730429) (xy 57.009761 -21.620753) (xy 56.948878 -21.50712)
			(xy 56.895095 -21.389961) (xy 56.848614 -21.269716) (xy 56.809611 -21.146843) (xy 56.778235 -21.021804)
			(xy 56.754602 -20.895074) (xy 56.738804 -20.76713) (xy 56.730899 -20.638458) (xy 56.730392 -20.574)
			(xy 56.730879 -20.509543) (xy 56.73879 -20.380871) (xy 56.754594 -20.252929) (xy 56.77823 -20.126199)
			(xy 56.809611 -20.001162) (xy 56.848617 -19.87829) (xy 56.895101 -19.758048) (xy 56.948886 -19.640889)
			(xy 57.009771 -19.527258) (xy 57.077524 -19.417583) (xy 57.151889 -19.31228) (xy 57.232585 -19.211746)
			(xy 57.319308 -19.116361) (xy 57.411729 -19.026487) (xy 57.509498 -18.942463) (xy 57.612247 -18.864606)
			(xy 57.719587 -18.793211) (xy 57.775094 -18.76044) (xy 57.782587 -18.755661) (xy 57.793999 -18.742057)
			(xy 57.800088 -18.725376) (xy 57.800494 -18.716498) (xy 57.800494 -1.761744) (xy 57.80006 -1.751678)
			(xy 57.792331 -1.733089) (xy 57.785508 -1.725676) (xy 57.090818 -1.030986) (xy 57.083419 -1.024143)
			(xy 57.06482 -1.016425) (xy 57.05475 -1.016) (xy 56.553862 -1.016) (xy 56.543415 -1.016563) (xy 56.524271 -1.024954)
			(xy 56.516778 -1.032256) (xy 56.496959 -1.052804) (xy 56.452307 -1.088372) (xy 56.402856 -1.116893)
			(xy 56.349709 -1.137732) (xy 56.294051 -1.150425) (xy 56.237124 -1.154687) (xy 56.180197 -1.150425)
			(xy 56.124539 -1.137732) (xy 56.071392 -1.116893) (xy 56.021941 -1.088372) (xy 55.977289 -1.052804)
			(xy 55.95747 -1.032256) (xy 55.949995 -1.024929) (xy 55.93084 -1.01655) (xy 55.920386 -1.016) (xy 51.473862 -1.016)
			(xy 51.463415 -1.016563) (xy 51.444271 -1.024954) (xy 51.436778 -1.032256) (xy 51.416959 -1.052804)
			(xy 51.372307 -1.088372) (xy 51.322856 -1.116893) (xy 51.269709 -1.137732) (xy 51.214051 -1.150425)
			(xy 51.157124 -1.154687) (xy 51.100197 -1.150425) (xy 51.044539 -1.137732) (xy 50.991392 -1.116893)
			(xy 50.941941 -1.088372) (xy 50.897289 -1.052804) (xy 50.87747 -1.032256) (xy 50.869995 -1.024929)
			(xy 50.85084 -1.01655) (xy 50.840386 -1.016) (xy 46.393862 -1.016) (xy 46.383415 -1.016563) (xy 46.364271 -1.024954)
			(xy 46.356778 -1.032256) (xy 46.336959 -1.052804) (xy 46.292307 -1.088372) (xy 46.242856 -1.116893)
			(xy 46.189709 -1.137732) (xy 46.134051 -1.150425) (xy 46.077124 -1.154687) (xy 46.020197 -1.150425)
			(xy 45.964539 -1.137732) (xy 45.911392 -1.116893) (xy 45.861941 -1.088372) (xy 45.817289 -1.052804)
			(xy 45.79747 -1.032256) (xy 45.789995 -1.024929) (xy 45.77084 -1.01655) (xy 45.760386 -1.016) (xy 41.313862 -1.016)
			(xy 41.303415 -1.016563) (xy 41.284271 -1.024954) (xy 41.276778 -1.032256) (xy 41.256959 -1.052804)
			(xy 41.212307 -1.088372) (xy 41.162856 -1.116893) (xy 41.109709 -1.137732) (xy 41.054051 -1.150425)
			(xy 40.997124 -1.154687) (xy 40.940197 -1.150425) (xy 40.884539 -1.137732) (xy 40.831392 -1.116893)
			(xy 40.781941 -1.088372) (xy 40.737289 -1.052804) (xy 40.71747 -1.032256) (xy 40.709995 -1.024929)
			(xy 40.69084 -1.01655) (xy 40.680386 -1.016) (xy 36.233862 -1.016) (xy 36.223415 -1.016563) (xy 36.204271 -1.024954)
			(xy 36.196778 -1.032256) (xy 36.176959 -1.052804) (xy 36.132307 -1.088372) (xy 36.082856 -1.116893)
			(xy 36.029709 -1.137732) (xy 35.974051 -1.150425) (xy 35.917124 -1.154687) (xy 35.860197 -1.150425)
			(xy 35.804539 -1.137732) (xy 35.751392 -1.116893) (xy 35.701941 -1.088372) (xy 35.657289 -1.052804)
			(xy 35.63747 -1.032256) (xy 35.629995 -1.024929) (xy 35.61084 -1.01655) (xy 35.600386 -1.016) (xy 31.153862 -1.016)
			(xy 31.143415 -1.016563) (xy 31.124271 -1.024954) (xy 31.116778 -1.032256) (xy 31.096959 -1.052804)
			(xy 31.052307 -1.088372) (xy 31.002856 -1.116893) (xy 30.949709 -1.137732) (xy 30.894051 -1.150425)
			(xy 30.837124 -1.154687) (xy 30.780197 -1.150425) (xy 30.724539 -1.137732) (xy 30.671392 -1.116893)
			(xy 30.621941 -1.088372) (xy 30.577289 -1.052804) (xy 30.55747 -1.032256) (xy 30.549995 -1.024929)
			(xy 30.53084 -1.01655) (xy 30.520386 -1.016) (xy 26.073862 -1.016) (xy 26.063415 -1.016563) (xy 26.044271 -1.024954)
			(xy 26.036778 -1.032256) (xy 26.016959 -1.052804) (xy 25.972307 -1.088372) (xy 25.922856 -1.116893)
			(xy 25.869709 -1.137732) (xy 25.814051 -1.150425) (xy 25.757124 -1.154687) (xy 25.700197 -1.150425)
			(xy 25.644539 -1.137732) (xy 25.591392 -1.116893) (xy 25.541941 -1.088372) (xy 25.497289 -1.052804)
			(xy 25.47747 -1.032256) (xy 25.469995 -1.024929) (xy 25.45084 -1.01655) (xy 25.440386 -1.016) (xy 20.993862 -1.016)
			(xy 20.983415 -1.016563) (xy 20.964271 -1.024954) (xy 20.956778 -1.032256) (xy 20.936959 -1.052804)
			(xy 20.892307 -1.088372) (xy 20.842856 -1.116893) (xy 20.789709 -1.137732) (xy 20.734051 -1.150425)
			(xy 20.677124 -1.154687) (xy 20.620197 -1.150425) (xy 20.564539 -1.137732) (xy 20.511392 -1.116893)
			(xy 20.461941 -1.088372) (xy 20.417289 -1.052804) (xy 20.39747 -1.032256) (xy 20.389995 -1.024929)
			(xy 20.37084 -1.01655) (xy 20.360386 -1.016) (xy 8.11022 -1.016) (xy 8.099978 -1.016474) (xy 8.081122 -1.024478)
			(xy 8.073644 -1.031494) (xy 8.053949 -1.051039) (xy 8.009917 -1.084801) (xy 7.961459 -1.111829) (xy 7.909597 -1.131553)
			(xy 7.855425 -1.143556) (xy 7.800086 -1.147586) (xy 7.744747 -1.143556) (xy 7.690575 -1.131553) (xy 7.638713 -1.111829)
			(xy 7.590255 -1.084801) (xy 7.546223 -1.051039) (xy 7.526528 -1.031494) (xy 7.519077 -1.024442) (xy 7.500202 -1.016451)
			(xy 7.489952 -1.016) (xy 4.99999 -1.016) (xy 4.908159 -1.016535) (xy 4.724692 -1.025013) (xy 4.541811 -1.041936)
			(xy 4.359903 -1.067266) (xy 4.179356 -1.10095) (xy 4.000552 -1.142916) (xy 3.823872 -1.193076) (xy 3.64969 -1.251323)
			(xy 3.478377 -1.317533) (xy 3.310297 -1.391566) (xy 3.145805 -1.473264) (xy 3.065272 -1.517396) (xy 3.055752 -1.523279)
			(xy 3.042572 -1.541333) (xy 3.039872 -1.552194) (xy 3.034517 -1.578033) (xy 3.017628 -1.628025) (xy 2.994005 -1.675209)
			(xy 2.964098 -1.718684) (xy 2.928481 -1.757618) (xy 2.887834 -1.791266) (xy 2.842933 -1.818986) (xy 2.794639 -1.840248)
			(xy 2.743873 -1.854644) (xy 2.691606 -1.8619) (xy 2.665222 -1.862328) (xy 2.645131 -1.862086) (xy 2.605168 -1.857888)
			(xy 2.585466 -1.853946) (xy 2.574372 -1.852091) (xy 2.552469 -1.857083) (xy 2.543302 -1.863598) (xy 2.472546 -1.919663)
			(xy 2.335599 -2.037321) (xy 2.204122 -2.161062) (xy 2.078386 -2.290632) (xy 1.958649 -2.425765) (xy 1.845157 -2.566184)
			(xy 1.738142 -2.7116) (xy 1.637825 -2.861714) (xy 1.544411 -3.016219) (xy 1.458092 -3.174798) (xy 1.379046 -3.337123)
			(xy 1.307435 -3.502863) (xy 1.243405 -3.671677) (xy 1.187089 -3.843219) (xy 1.138601 -4.017135) (xy 1.098042 -4.193069)
			(xy 1.065495 -4.37066) (xy 1.041027 -4.549544) (xy 1.024687 -4.729352) (xy 1.01651 -4.909716) (xy 1.016 -4.99999)
			(xy 1.016 -5.76707) (xy 1.016472 -5.777312) (xy 1.024474 -5.796171) (xy 1.031494 -5.803646) (xy 1.051201 -5.823366)
			(xy 1.085261 -5.867503) (xy 1.112534 -5.916126) (xy 1.132441 -5.968201) (xy 1.144557 -6.022619) (xy 1.148624 -6.07822)
			(xy 1.144557 -6.133821) (xy 1.132441 -6.188239) (xy 1.112534 -6.240314) (xy 1.085261 -6.288937) (xy 1.051201 -6.333074)
			(xy 1.031494 -6.352794) (xy 1.024446 -6.360247) (xy 1.016463 -6.379122) (xy 1.016 -6.38937) (xy 1.016 -10.84707)
			(xy 1.016472 -10.857312) (xy 1.024474 -10.876171) (xy 1.031494 -10.883646) (xy 1.051201 -10.903366)
			(xy 1.085261 -10.947503) (xy 1.112534 -10.996126) (xy 1.132441 -11.048201) (xy 1.144557 -11.102619)
			(xy 1.148624 -11.15822) (xy 1.144557 -11.213821) (xy 1.132441 -11.268239) (xy 1.112534 -11.320314)
			(xy 1.085261 -11.368937) (xy 1.051201 -11.413074) (xy 1.031494 -11.432794) (xy 1.024446 -11.440247)
			(xy 1.016463 -11.459122) (xy 1.016 -11.46937) (xy 1.016 -15.92707) (xy 1.016472 -15.937312) (xy 1.024474 -15.956171)
			(xy 1.031494 -15.963646) (xy 1.051201 -15.983366) (xy 1.085261 -16.027503) (xy 1.112534 -16.076126)
			(xy 1.132441 -16.128201) (xy 1.144557 -16.182619) (xy 1.148624 -16.23822) (xy 1.144557 -16.293821)
			(xy 1.132441 -16.348239) (xy 1.112534 -16.400314) (xy 1.085261 -16.448937) (xy 1.051201 -16.493074)
			(xy 1.031494 -16.512794) (xy 1.024446 -16.520247) (xy 1.016463 -16.539122) (xy 1.016 -16.54937) (xy 1.016 -21.00707)
			(xy 1.016472 -21.017312) (xy 1.024474 -21.036171) (xy 1.031494 -21.043646) (xy 1.051201 -21.063366)
			(xy 1.085261 -21.107503) (xy 1.112534 -21.156126) (xy 1.132441 -21.208201) (xy 1.144557 -21.262619)
			(xy 1.148624 -21.31822) (xy 1.144557 -21.373821) (xy 1.132441 -21.428239) (xy 1.112534 -21.480314)
			(xy 1.085261 -21.528937) (xy 1.051201 -21.573074) (xy 1.031494 -21.592794) (xy 1.024446 -21.600247)
			(xy 1.016463 -21.619122) (xy 1.016 -21.62937) (xy 1.016 -26.08707) (xy 1.016472 -26.097312) (xy 1.024474 -26.116171)
			(xy 1.031494 -26.123646) (xy 1.051201 -26.143366) (xy 1.085261 -26.187503) (xy 1.112534 -26.236126)
			(xy 1.132441 -26.288201) (xy 1.144557 -26.342619) (xy 1.148624 -26.39822) (xy 1.144557 -26.453821)
			(xy 1.132441 -26.508239) (xy 1.112534 -26.560314) (xy 1.085261 -26.608937) (xy 1.051201 -26.653074)
			(xy 1.031494 -26.672794) (xy 1.024446 -26.680247) (xy 1.016463 -26.699122) (xy 1.016 -26.70937) (xy 1.016 -31.16707)
			(xy 1.016472 -31.177312) (xy 1.024474 -31.196171) (xy 1.031494 -31.203646) (xy 1.051201 -31.223366)
			(xy 1.085261 -31.267503) (xy 1.112534 -31.316126) (xy 1.132441 -31.368201) (xy 1.144557 -31.422619)
			(xy 1.148624 -31.47822) (xy 1.144557 -31.533821) (xy 1.132441 -31.588239) (xy 1.112534 -31.640314)
			(xy 1.085261 -31.688937) (xy 1.051201 -31.733074) (xy 1.031494 -31.752794) (xy 1.024446 -31.760247)
			(xy 1.016463 -31.779122) (xy 1.016 -31.78937) (xy 1.016 -36.24707) (xy 1.016472 -36.257312) (xy 1.024474 -36.276171)
			(xy 1.031494 -36.283646) (xy 1.051201 -36.303366) (xy 1.085261 -36.347503) (xy 1.112534 -36.396126)
			(xy 1.132441 -36.448201) (xy 1.144557 -36.502619) (xy 1.148624 -36.55822) (xy 1.144557 -36.613821)
			(xy 1.132441 -36.668239) (xy 1.112534 -36.720314) (xy 1.085261 -36.768937) (xy 1.051201 -36.813074)
			(xy 1.031494 -36.832794) (xy 1.024446 -36.840247) (xy 1.016463 -36.859122) (xy 1.016 -36.86937) (xy 1.016 -41.32707)
			(xy 1.016472 -41.337312) (xy 1.024474 -41.356171) (xy 1.031494 -41.363646) (xy 1.051201 -41.383366)
			(xy 1.085261 -41.427503) (xy 1.112534 -41.476126) (xy 1.132441 -41.528201) (xy 1.144557 -41.582619)
			(xy 1.148624 -41.63822) (xy 1.144557 -41.693821) (xy 1.132441 -41.748239) (xy 1.112534 -41.800314)
			(xy 1.085261 -41.848937) (xy 1.051201 -41.893074) (xy 1.031494 -41.912794) (xy 1.024446 -41.920247)
			(xy 1.016463 -41.939122) (xy 1.016 -41.94937) (xy 1.016 -46.40707) (xy 1.016472 -46.417312) (xy 1.024474 -46.436171)
			(xy 1.031494 -46.443646) (xy 1.051201 -46.463366) (xy 1.085261 -46.507503) (xy 1.112534 -46.556126)
			(xy 1.132441 -46.608201) (xy 1.144557 -46.662619) (xy 1.148624 -46.71822) (xy 1.144557 -46.773821)
			(xy 1.132441 -46.828239) (xy 1.112534 -46.880314) (xy 1.085261 -46.928937) (xy 1.051201 -46.973074)
			(xy 1.031494 -46.992794) (xy 1.024446 -47.000247) (xy 1.016463 -47.019122) (xy 1.016 -47.02937) (xy 1.016 -51.48707)
			(xy 1.016472 -51.497312) (xy 1.024474 -51.516171) (xy 1.031494 -51.523646) (xy 1.051201 -51.543366)
			(xy 1.085261 -51.587503) (xy 1.112534 -51.636126) (xy 1.132441 -51.688201) (xy 1.144557 -51.742619)
			(xy 1.148624 -51.79822) (xy 1.144557 -51.853821) (xy 1.132441 -51.908239) (xy 1.112534 -51.960314)
			(xy 1.085261 -52.008937) (xy 1.051201 -52.053074) (xy 1.031494 -52.072794) (xy 1.024446 -52.080247)
			(xy 1.016463 -52.099122) (xy 1.016 -52.10937) (xy 1.016 -56.56707) (xy 1.016472 -56.577312) (xy 1.024474 -56.596171)
			(xy 1.031494 -56.603646) (xy 1.051201 -56.623366) (xy 1.085261 -56.667503) (xy 1.112534 -56.716126)
			(xy 1.132441 -56.768201) (xy 1.144557 -56.822619) (xy 1.148624 -56.87822) (xy 1.144557 -56.933821)
			(xy 1.132441 -56.988239) (xy 1.112534 -57.040314) (xy 1.085261 -57.088937) (xy 1.051201 -57.133074)
			(xy 1.031494 -57.152794) (xy 1.024446 -57.160247) (xy 1.016463 -57.179122) (xy 1.016 -57.18937) (xy 1.016 -60.099956)
			(xy 12.484104 -60.099956) (xy 12.488134 -59.957621) (xy 12.500209 -59.815741) (xy 12.520292 -59.674773)
			(xy 12.548319 -59.535166) (xy 12.584199 -59.397368) (xy 12.627817 -59.261821) (xy 12.679034 -59.128959)
			(xy 12.737685 -58.999207) (xy 12.803583 -58.872981) (xy 12.876517 -58.750685) (xy 12.956254 -58.632712)
			(xy 13.042536 -58.519439) (xy 13.135089 -58.411228) (xy 13.233616 -58.308427) (xy 13.337801 -58.211365)
			(xy 13.44731 -58.120353) (xy 13.561793 -58.035681) (xy 13.680883 -57.957623) (xy 13.804198 -57.886427)
			(xy 13.931344 -57.822321) (xy 14.061913 -57.765512) (xy 14.195487 -57.71618) (xy 14.331638 -57.674484)
			(xy 14.469929 -57.640558) (xy 14.609919 -57.61451) (xy 14.751158 -57.596424) (xy 14.893194 -57.586357)
			(xy 15.035572 -57.584342) (xy 15.177836 -57.590385) (xy 15.31953 -57.604467) (xy 15.4602 -57.626543)
			(xy 15.599397 -57.656543) (xy 15.736673 -57.694369) (xy 15.871589 -57.739901) (xy 16.003713 -57.792992)
			(xy 16.132622 -57.853474) (xy 16.257903 -57.921152) (xy 16.379154 -57.995809) (xy 16.495987 -58.077207)
			(xy 16.608028 -58.165084) (xy 16.714918 -58.259159) (xy 16.816315 -58.359131) (xy 16.911893 -58.464679)
			(xy 17.001347 -58.575465) (xy 17.084389 -58.691134) (xy 17.160755 -58.811317) (xy 17.230199 -58.935627)
			(xy 17.292499 -59.063668) (xy 17.347455 -59.195027) (xy 17.394892 -59.329286) (xy 17.434656 -59.466013)
			(xy 17.466622 -59.604771) (xy 17.490687 -59.745115) (xy 17.506773 -59.886596) (xy 17.514828 -60.02876)
			(xy 17.515332 -60.099956) (xy 17.514828 -60.171152) (xy 17.506773 -60.313316) (xy 17.490687 -60.454797)
			(xy 17.466622 -60.595141) (xy 17.434656 -60.733899) (xy 17.394892 -60.870626) (xy 17.347455 -61.004885)
			(xy 17.292499 -61.136244) (xy 17.230199 -61.264285) (xy 17.160755 -61.388595) (xy 17.084389 -61.508778)
			(xy 17.001347 -61.624447) (xy 16.911893 -61.735233) (xy 16.816315 -61.840781) (xy 16.714918 -61.940753)
			(xy 16.608028 -62.034828) (xy 16.495987 -62.122705) (xy 16.379154 -62.204103) (xy 16.257903 -62.27876)
			(xy 16.132622 -62.346438) (xy 16.003713 -62.40692) (xy 15.871589 -62.460011) (xy 15.736673 -62.505543)
			(xy 15.599397 -62.543369) (xy 15.4602 -62.573369) (xy 15.31953 -62.595445) (xy 15.177836 -62.609527)
			(xy 15.035572 -62.61557) (xy 14.893194 -62.613555) (xy 14.751158 -62.603488) (xy 14.609919 -62.585402)
			(xy 14.469929 -62.559354) (xy 14.331638 -62.525428) (xy 14.195487 -62.483732) (xy 14.061913 -62.4344)
			(xy 13.931344 -62.377591) (xy 13.804198 -62.313485) (xy 13.680883 -62.242289) (xy 13.561793 -62.164231)
			(xy 13.44731 -62.079559) (xy 13.337801 -61.988547) (xy 13.233616 -61.891485) (xy 13.135089 -61.788684)
			(xy 13.042536 -61.680473) (xy 12.956254 -61.5672) (xy 12.876517 -61.449227) (xy 12.803583 -61.326931)
			(xy 12.737685 -61.200705) (xy 12.679034 -61.070953) (xy 12.627817 -60.938091) (xy 12.584199 -60.802544)
			(xy 12.548319 -60.664746) (xy 12.520292 -60.525139) (xy 12.500209 -60.384171) (xy 12.488134 -60.242291)
			(xy 12.484104 -60.099956) (xy 1.016 -60.099956) (xy 1.016 -61.64707) (xy 1.016472 -61.657312) (xy 1.024474 -61.676171)
			(xy 1.031494 -61.683646) (xy 1.051201 -61.703366) (xy 1.085261 -61.747503) (xy 1.112534 -61.796126)
			(xy 1.132441 -61.848201) (xy 1.144557 -61.902619) (xy 1.148624 -61.95822) (xy 1.144557 -62.013821)
			(xy 1.132441 -62.068239) (xy 1.112534 -62.120314) (xy 1.085261 -62.168937) (xy 1.051201 -62.213074)
			(xy 1.031494 -62.232794) (xy 1.024446 -62.240247) (xy 1.016463 -62.259122) (xy 1.016 -62.26937) (xy 1.016 -66.72707)
			(xy 1.016472 -66.737312) (xy 1.024474 -66.756171) (xy 1.031494 -66.763646) (xy 1.051201 -66.783366)
			(xy 1.085261 -66.827503) (xy 1.112534 -66.876126) (xy 1.132441 -66.928201) (xy 1.144557 -66.982619)
			(xy 1.148624 -67.03822) (xy 1.144557 -67.093821) (xy 1.132441 -67.148239) (xy 1.112534 -67.200314)
			(xy 1.085261 -67.248937) (xy 1.051201 -67.293074) (xy 1.031494 -67.312794) (xy 1.024446 -67.320247)
			(xy 1.016463 -67.339122) (xy 1.016 -67.34937) (xy 1.016 -71.80707) (xy 1.016472 -71.817312) (xy 1.024474 -71.836171)
			(xy 1.031494 -71.843646) (xy 1.051201 -71.863366) (xy 1.085261 -71.907503) (xy 1.112534 -71.956126)
			(xy 1.132441 -72.008201) (xy 1.144557 -72.062619) (xy 1.148624 -72.11822) (xy 1.144557 -72.173821)
			(xy 1.132441 -72.228239) (xy 1.112534 -72.280314) (xy 1.085261 -72.328937) (xy 1.051201 -72.373074)
			(xy 1.031494 -72.392794) (xy 1.024446 -72.400247) (xy 1.016463 -72.419122) (xy 1.016 -72.42937) (xy 1.016 -76.88707)
			(xy 1.016472 -76.897312) (xy 1.024474 -76.916171) (xy 1.031494 -76.923646) (xy 1.051201 -76.943366)
			(xy 1.085261 -76.987503) (xy 1.112534 -77.036126) (xy 1.132441 -77.088201) (xy 1.144557 -77.142619)
			(xy 1.148624 -77.19822) (xy 1.144557 -77.253821) (xy 1.132441 -77.308239) (xy 1.112534 -77.360314)
			(xy 1.085261 -77.408937) (xy 1.051201 -77.453074) (xy 1.031494 -77.472794) (xy 1.024446 -77.480247)
			(xy 1.016463 -77.499122) (xy 1.016 -77.50937) (xy 1.016 -81.96707) (xy 1.016472 -81.977312) (xy 1.024474 -81.996171)
			(xy 1.031494 -82.003646) (xy 1.051201 -82.023366) (xy 1.085261 -82.067503) (xy 1.112534 -82.116126)
			(xy 1.132441 -82.168201) (xy 1.144557 -82.222619) (xy 1.148624 -82.27822) (xy 1.144557 -82.333821)
			(xy 1.132441 -82.388239) (xy 1.112534 -82.440314) (xy 1.085261 -82.488937) (xy 1.051201 -82.533074)
			(xy 1.031494 -82.552794) (xy 1.024446 -82.560247) (xy 1.016463 -82.579122) (xy 1.016 -82.58937) (xy 1.016 -87.04707)
			(xy 1.016472 -87.057312) (xy 1.024474 -87.076171) (xy 1.031494 -87.083646) (xy 1.051201 -87.103366)
			(xy 1.085261 -87.147503) (xy 1.112534 -87.196126) (xy 1.132441 -87.248201) (xy 1.144557 -87.302619)
			(xy 1.148624 -87.35822) (xy 1.144557 -87.413821) (xy 1.132441 -87.468239) (xy 1.112534 -87.520314)
			(xy 1.085261 -87.568937) (xy 1.051201 -87.613074) (xy 1.031494 -87.632794) (xy 1.024446 -87.640247)
			(xy 1.016463 -87.659122) (xy 1.016 -87.66937) (xy 1.016 -92.12707) (xy 1.016472 -92.137312) (xy 1.024474 -92.156171)
			(xy 1.031494 -92.163646) (xy 1.051201 -92.183366) (xy 1.085261 -92.227503) (xy 1.112534 -92.276126)
			(xy 1.132441 -92.328201) (xy 1.144557 -92.382619) (xy 1.148624 -92.43822) (xy 1.144557 -92.493821)
			(xy 1.132441 -92.548239) (xy 1.112534 -92.600314) (xy 1.085261 -92.648937) (xy 1.051201 -92.693074)
			(xy 1.031494 -92.712794) (xy 1.024446 -92.720247) (xy 1.016463 -92.739122) (xy 1.016 -92.74937) (xy 1.016 -97.20707)
			(xy 1.016472 -97.217312) (xy 1.024474 -97.236171) (xy 1.031494 -97.243646) (xy 1.051201 -97.263366)
			(xy 1.085261 -97.307503) (xy 1.112534 -97.356126) (xy 1.132441 -97.408201) (xy 1.144557 -97.462619)
			(xy 1.148624 -97.51822) (xy 1.144557 -97.573821) (xy 1.132441 -97.628239) (xy 1.112534 -97.680314)
			(xy 1.085261 -97.728937) (xy 1.051201 -97.773074) (xy 1.031494 -97.792794) (xy 1.024446 -97.800247)
			(xy 1.016463 -97.819122) (xy 1.016 -97.82937) (xy 1.016 -102.28707) (xy 1.016472 -102.297312) (xy 1.024474 -102.316171)
			(xy 1.031494 -102.323646) (xy 1.051201 -102.343366) (xy 1.085261 -102.387503) (xy 1.112534 -102.436126)
			(xy 1.132441 -102.488201) (xy 1.144557 -102.542619) (xy 1.148624 -102.59822) (xy 1.144557 -102.653821)
			(xy 1.132441 -102.708239) (xy 1.112534 -102.760314) (xy 1.085261 -102.808937) (xy 1.051201 -102.853074)
			(xy 1.031494 -102.872794) (xy 1.024446 -102.880247) (xy 1.016463 -102.899122) (xy 1.016 -102.90937)
			(xy 1.016 -104.544876) (xy 12.484104 -104.544876) (xy 12.488134 -104.402541) (xy 12.500209 -104.260661)
			(xy 12.520292 -104.119693) (xy 12.548319 -103.980086) (xy 12.584199 -103.842288) (xy 12.627817 -103.706741)
			(xy 12.679034 -103.573879) (xy 12.737685 -103.444127) (xy 12.803583 -103.317901) (xy 12.876517 -103.195605)
			(xy 12.956254 -103.077632) (xy 13.042536 -102.964359) (xy 13.135089 -102.856148) (xy 13.233616 -102.753347)
			(xy 13.337801 -102.656285) (xy 13.44731 -102.565273) (xy 13.561793 -102.480601) (xy 13.680883 -102.402543)
			(xy 13.804198 -102.331347) (xy 13.931344 -102.267241) (xy 14.061913 -102.210432) (xy 14.195487 -102.1611)
			(xy 14.331638 -102.119404) (xy 14.469929 -102.085478) (xy 14.609919 -102.05943) (xy 14.751158 -102.041344)
			(xy 14.893194 -102.031277) (xy 15.035572 -102.029262) (xy 15.177836 -102.035305) (xy 15.31953 -102.049387)
			(xy 15.4602 -102.071463) (xy 15.599397 -102.101463) (xy 15.736673 -102.139289) (xy 15.871589 -102.184821)
			(xy 16.003713 -102.237912) (xy 16.132622 -102.298394) (xy 16.257903 -102.366072) (xy 16.379154 -102.440729)
			(xy 16.495987 -102.522127) (xy 16.608028 -102.610004) (xy 16.714918 -102.704079) (xy 16.816315 -102.804051)
			(xy 16.911893 -102.909599) (xy 17.001347 -103.020385) (xy 17.084389 -103.136054) (xy 17.160755 -103.256237)
			(xy 17.230199 -103.380547) (xy 17.292499 -103.508588) (xy 17.347455 -103.639947) (xy 17.394892 -103.774206)
			(xy 17.434656 -103.910933) (xy 17.466622 -104.049691) (xy 17.490687 -104.190035) (xy 17.506773 -104.331516)
			(xy 17.514828 -104.47368) (xy 17.515332 -104.544876) (xy 17.514828 -104.616072) (xy 17.506773 -104.758236)
			(xy 17.490687 -104.899717) (xy 17.466622 -105.040061) (xy 17.434656 -105.178819) (xy 17.394892 -105.315546)
			(xy 17.347455 -105.449805) (xy 17.292499 -105.581164) (xy 17.230199 -105.709205) (xy 17.160755 -105.833515)
			(xy 17.084389 -105.953698) (xy 17.001347 -106.069367) (xy 16.911893 -106.180153) (xy 16.816315 -106.285701)
			(xy 16.714918 -106.385673) (xy 16.608028 -106.479748) (xy 16.495987 -106.567625) (xy 16.379154 -106.649023)
			(xy 16.257903 -106.72368) (xy 16.132622 -106.791358) (xy 16.003713 -106.85184) (xy 15.871589 -106.904931)
			(xy 15.736673 -106.950463) (xy 15.599397 -106.988289) (xy 15.4602 -107.018289) (xy 15.31953 -107.040365)
			(xy 15.177836 -107.054447) (xy 15.035572 -107.06049) (xy 14.893194 -107.058475) (xy 14.751158 -107.048408)
			(xy 14.609919 -107.030322) (xy 14.469929 -107.004274) (xy 14.331638 -106.970348) (xy 14.195487 -106.928652)
			(xy 14.061913 -106.87932) (xy 13.931344 -106.822511) (xy 13.804198 -106.758405) (xy 13.680883 -106.687209)
			(xy 13.561793 -106.609151) (xy 13.44731 -106.524479) (xy 13.337801 -106.433467) (xy 13.233616 -106.336405)
			(xy 13.135089 -106.233604) (xy 13.042536 -106.125393) (xy 12.956254 -106.01212) (xy 12.876517 -105.894147)
			(xy 12.803583 -105.771851) (xy 12.737685 -105.645625) (xy 12.679034 -105.515873) (xy 12.627817 -105.383011)
			(xy 12.584199 -105.247464) (xy 12.548319 -105.109666) (xy 12.520292 -104.970059) (xy 12.500209 -104.829091)
			(xy 12.488134 -104.687211) (xy 12.484104 -104.544876) (xy 1.016 -104.544876) (xy 1.016 -107.36707)
			(xy 1.016472 -107.377312) (xy 1.024474 -107.396171) (xy 1.031494 -107.403646) (xy 1.051201 -107.423366)
			(xy 1.085261 -107.467503) (xy 1.112534 -107.516126) (xy 1.132441 -107.568201) (xy 1.144557 -107.622619)
			(xy 1.148624 -107.67822) (xy 1.144557 -107.733821) (xy 1.132441 -107.788239) (xy 1.112534 -107.840314)
			(xy 1.085261 -107.888937) (xy 1.051201 -107.933074) (xy 1.031494 -107.952794) (xy 1.024446 -107.960247)
			(xy 1.016463 -107.979122) (xy 1.016 -107.98937) (xy 1.016 -112.44707) (xy 1.016472 -112.457312) (xy 1.024474 -112.476171)
			(xy 1.031494 -112.483646) (xy 1.051201 -112.503366) (xy 1.085261 -112.547503) (xy 1.112534 -112.596126)
			(xy 1.132441 -112.648201) (xy 1.144557 -112.702619) (xy 1.148624 -112.75822) (xy 1.144557 -112.813821)
			(xy 1.132441 -112.868239) (xy 1.112534 -112.920314) (xy 1.085261 -112.968937) (xy 1.051201 -113.013074)
			(xy 1.031494 -113.032794) (xy 1.024446 -113.040247) (xy 1.016463 -113.059122) (xy 1.016 -113.06937)
			(xy 1.016 -117.52707) (xy 1.016472 -117.537312) (xy 1.024474 -117.556171) (xy 1.031494 -117.563646)
			(xy 1.051201 -117.583366) (xy 1.085261 -117.627503) (xy 1.112534 -117.676126) (xy 1.132441 -117.728201)
			(xy 1.144557 -117.782619) (xy 1.148624 -117.83822) (xy 1.144557 -117.893821) (xy 1.132441 -117.948239)
			(xy 1.112534 -118.000314) (xy 1.085261 -118.048937) (xy 1.051201 -118.093074) (xy 1.031494 -118.112794)
			(xy 1.024446 -118.120247) (xy 1.016463 -118.139122) (xy 1.016 -118.14937) (xy 1.016 -122.60707) (xy 1.016472 -122.617312)
			(xy 1.024474 -122.636171) (xy 1.031494 -122.643646) (xy 1.051201 -122.663366) (xy 1.085261 -122.707503)
			(xy 1.112534 -122.756126) (xy 1.132441 -122.808201) (xy 1.144557 -122.862619) (xy 1.148624 -122.91822)
			(xy 1.144557 -122.973821) (xy 1.132441 -123.028239) (xy 1.112534 -123.080314) (xy 1.085261 -123.128937)
			(xy 1.051201 -123.173074) (xy 1.031494 -123.192794) (xy 1.024446 -123.200247) (xy 1.016463 -123.219122)
			(xy 1.016 -123.22937) (xy 1.016 -127.68707) (xy 1.016472 -127.697312) (xy 1.024474 -127.716171) (xy 1.031494 -127.723646)
			(xy 1.051201 -127.743366) (xy 1.085261 -127.787503) (xy 1.112534 -127.836126) (xy 1.132441 -127.888201)
			(xy 1.144557 -127.942619) (xy 1.148624 -127.99822) (xy 1.144557 -128.053821) (xy 1.132441 -128.108239)
			(xy 1.112534 -128.160314) (xy 1.085261 -128.208937) (xy 1.051201 -128.253074) (xy 1.031494 -128.272794)
			(xy 1.024446 -128.280247) (xy 1.016463 -128.299122) (xy 1.016 -128.30937) (xy 1.016 -132.76707) (xy 1.016472 -132.777312)
			(xy 1.024474 -132.796171) (xy 1.031494 -132.803646) (xy 1.051201 -132.823366) (xy 1.085261 -132.867503)
			(xy 1.112534 -132.916126) (xy 1.132441 -132.968201) (xy 1.144557 -133.022619) (xy 1.148624 -133.07822)
			(xy 1.144557 -133.133821) (xy 1.132441 -133.188239) (xy 1.112534 -133.240314) (xy 1.085261 -133.288937)
			(xy 1.051201 -133.333074) (xy 1.031494 -133.352794) (xy 1.024446 -133.360247) (xy 1.016463 -133.379122)
			(xy 1.016 -133.38937) (xy 1.016 -137.84707) (xy 1.016472 -137.857312) (xy 1.024474 -137.876171) (xy 1.031494 -137.883646)
			(xy 1.051201 -137.903366) (xy 1.085261 -137.947503) (xy 1.112534 -137.996126) (xy 1.132441 -138.048201)
			(xy 1.144557 -138.102619) (xy 1.148624 -138.15822) (xy 1.144557 -138.213821) (xy 1.132441 -138.268239)
			(xy 1.112534 -138.320314) (xy 1.085261 -138.368937) (xy 1.051201 -138.413074) (xy 1.031494 -138.432794)
			(xy 1.024446 -138.440247) (xy 1.016463 -138.459122) (xy 1.016 -138.46937) (xy 1.016 -142.92707) (xy 1.016472 -142.937312)
			(xy 1.024474 -142.956171) (xy 1.031494 -142.963646) (xy 1.051201 -142.983366) (xy 1.085261 -143.027503)
			(xy 1.112534 -143.076126) (xy 1.132441 -143.128201) (xy 1.144557 -143.182619) (xy 1.148624 -143.23822)
			(xy 1.144557 -143.293821) (xy 1.132441 -143.348239) (xy 1.112534 -143.400314) (xy 1.085261 -143.448937)
			(xy 1.051201 -143.493074) (xy 1.031494 -143.512794) (xy 1.024446 -143.520247) (xy 1.016463 -143.539122)
			(xy 1.016 -143.54937) (xy 1.016 -148.00707) (xy 1.016472 -148.017312) (xy 1.024474 -148.036171) (xy 1.031494 -148.043646)
			(xy 1.051201 -148.063366) (xy 1.085261 -148.107503) (xy 1.112534 -148.156126) (xy 1.132441 -148.208201)
			(xy 1.144557 -148.262619) (xy 1.148624 -148.31822) (xy 1.144557 -148.373821) (xy 1.132441 -148.428239)
			(xy 1.112534 -148.480314) (xy 1.085261 -148.528937) (xy 1.051201 -148.573074) (xy 1.031494 -148.592794)
			(xy 1.024446 -148.600247) (xy 1.016463 -148.619122) (xy 1.016 -148.62937) (xy 1.016 -153.08707) (xy 1.016472 -153.097312)
			(xy 1.024474 -153.116171) (xy 1.031494 -153.123646) (xy 1.049599 -153.141681) (xy 1.08131 -153.181753)
			(xy 1.107386 -153.225701) (xy 1.127359 -153.272739) (xy 1.140871 -153.322022) (xy 1.14768 -153.372669)
			(xy 1.14808 -153.39822) (xy 1.14757 -153.426437) (xy 1.139255 -153.482255) (xy 1.122812 -153.53624)
			(xy 1.098598 -153.587216) (xy 1.067142 -153.63407) (xy 1.048512 -153.655268) (xy 1.04178 -153.66353)
			(xy 1.035082 -153.683738) (xy 1.035558 -153.694384) (xy 1.044767 -153.782058) (xy 1.069972 -153.956556)
			(xy 1.102871 -154.129769) (xy 1.143399 -154.301357) (xy 1.191478 -154.470985) (xy 1.247013 -154.63832)
			(xy 1.309896 -154.803034) (xy 1.380003 -154.964806) (xy 1.457197 -155.123318) (xy 1.541328 -155.27826)
			(xy 1.632229 -155.429329) (xy 1.729725 -155.57623) (xy 1.833622 -155.718674) (xy 1.943719 -155.856383)
			(xy 2.0598 -155.989087) (xy 2.181637 -156.116526) (xy 2.308991 -156.238452) (xy 2.441615 -156.354624)
			(xy 2.579247 -156.464817) (xy 2.721619 -156.568813) (xy 2.868452 -156.666411) (xy 3.019458 -156.757417)
			(xy 3.174342 -156.841655) (xy 3.3328 -156.91896) (xy 3.494523 -156.989179) (xy 3.659194 -157.052176)
			(xy 3.74269 -157.080458) (xy 3.753078 -157.083386) (xy 3.774523 -157.081136) (xy 3.784092 -157.07614)
			(xy 3.805765 -157.064242) (xy 3.851524 -157.04552) (xy 3.899319 -157.032864) (xy 3.948347 -157.026487)
			(xy 3.973068 -157.026102) (xy 4.000564 -157.02658) (xy 4.054988 -157.034469) (xy 4.107715 -157.050089)
			(xy 4.157654 -157.073116) (xy 4.203771 -157.103072) (xy 4.24511 -157.139339) (xy 4.280814 -157.181164)
			(xy 4.295902 -157.204156) (xy 4.301964 -157.212996) (xy 4.319724 -157.224965) (xy 4.330192 -157.22727)
			(xy 4.413197 -157.240969) (xy 4.580104 -157.262209) (xy 4.747759 -157.276389) (xy 4.915863 -157.283483)
			(xy 4.99999 -157.283912)
		)
		(stroke
			(width 0)
			(type solid)
		)
		(fill yes)
		(layer "In4.Cu")
		(net "GND")
	)
	(gr_poly
		(pts
			(xy 423.536364 -157.283912) (xy 423.546429 -157.283478) (xy 423.565018 -157.275748) (xy 423.572432 -157.268926)
			(xy 423.592063 -157.249784) (xy 423.635828 -157.216758) (xy 423.683871 -157.190337) (xy 423.735202 -157.171066)
			(xy 423.788763 -157.159343) (xy 423.84345 -157.155408) (xy 423.898137 -157.159343) (xy 423.951698 -157.171066)
			(xy 424.003029 -157.190337) (xy 424.051072 -157.216758) (xy 424.094837 -157.249784) (xy 424.114468 -157.268926)
			(xy 424.121867 -157.27577) (xy 424.140466 -157.283491) (xy 424.150536 -157.283912) (xy 428.612046 -157.283912)
			(xy 428.622471 -157.283411) (xy 428.641618 -157.275155) (xy 428.64913 -157.26791) (xy 428.66892 -157.247516)
			(xy 428.713464 -157.21223) (xy 428.762748 -157.183941) (xy 428.815684 -157.163275) (xy 428.871099 -157.15069)
			(xy 428.927768 -157.146464) (xy 428.984437 -157.15069) (xy 429.039852 -157.163275) (xy 429.092788 -157.183941)
			(xy 429.142072 -157.21223) (xy 429.186616 -157.247516) (xy 429.206406 -157.26791) (xy 429.213905 -157.275178)
			(xy 429.233058 -157.283446) (xy 429.24349 -157.283912) (xy 433.692046 -157.283912) (xy 433.702471 -157.283411)
			(xy 433.721618 -157.275155) (xy 433.72913 -157.26791) (xy 433.74892 -157.247516) (xy 433.793464 -157.21223)
			(xy 433.842748 -157.183941) (xy 433.895684 -157.163275) (xy 433.951099 -157.15069) (xy 434.007768 -157.146464)
			(xy 434.064437 -157.15069) (xy 434.119852 -157.163275) (xy 434.172788 -157.183941) (xy 434.222072 -157.21223)
			(xy 434.266616 -157.247516) (xy 434.286406 -157.26791) (xy 434.293905 -157.275178) (xy 434.313058 -157.283446)
			(xy 434.32349 -157.283912) (xy 434.999892 -157.283912) (xy 435.090344 -157.283402) (xy 435.271063 -157.27519)
			(xy 435.451222 -157.258784) (xy 435.630451 -157.234217) (xy 435.80838 -157.20154) (xy 435.984642 -157.16082)
			(xy 436.158874 -157.112141) (xy 436.330717 -157.055603) (xy 436.499816 -156.991323) (xy 436.665823 -156.919433)
			(xy 436.828396 -156.840082) (xy 436.9872 -156.753434) (xy 437.141906 -156.659666) (xy 437.292197 -156.558972)
			(xy 437.437762 -156.45156) (xy 437.578301 -156.337652) (xy 437.713525 -156.217481) (xy 437.843155 -156.091296)
			(xy 437.966923 -155.959357) (xy 438.084575 -155.821936) (xy 438.195867 -155.679315) (xy 438.300571 -155.531791)
			(xy 438.398471 -155.379665) (xy 438.489364 -155.223252) (xy 438.573064 -155.062875) (xy 438.649397 -154.898864)
			(xy 438.718207 -154.731556) (xy 438.779351 -154.561298) (xy 438.832704 -154.38844) (xy 438.878156 -154.213338)
			(xy 438.915613 -154.036353) (xy 438.944997 -153.857851) (xy 438.966248 -153.678199) (xy 438.979322 -153.497767)
			(xy 438.982358 -153.407364) (xy 438.982175 -153.396901) (xy 438.974452 -153.377475) (xy 438.967372 -153.369772)
			(xy 438.946352 -153.348138) (xy 438.910721 -153.299471) (xy 438.883189 -153.245805) (xy 438.864442 -153.188476)
			(xy 438.854945 -153.128912) (xy 438.854342 -153.098754) (xy 438.854924 -153.068413) (xy 438.864523 -153.008494)
			(xy 438.883487 -152.950851) (xy 438.911338 -152.896937) (xy 438.947374 -152.848112) (xy 438.968642 -152.826466)
			(xy 438.975579 -152.819036) (xy 438.983417 -152.8003) (xy 438.983882 -152.790144) (xy 438.983882 -148.327364)
			(xy 438.983434 -148.317208) (xy 438.975574 -148.298478) (xy 438.968642 -148.291042) (xy 438.949305 -148.271377)
			(xy 438.915922 -148.227477) (xy 438.889209 -148.179228) (xy 438.869721 -148.127636) (xy 438.857866 -148.073775)
			(xy 438.85389 -148.018768) (xy 438.857875 -147.963761) (xy 438.86974 -147.909902) (xy 438.889236 -147.858313)
			(xy 438.915958 -147.810068) (xy 438.949348 -147.766174) (xy 438.968642 -147.746466) (xy 438.975579 -147.739036)
			(xy 438.983417 -147.7203) (xy 438.983882 -147.710144) (xy 438.983882 -143.247364) (xy 438.983434 -143.237208)
			(xy 438.975574 -143.218478) (xy 438.968642 -143.211042) (xy 438.949305 -143.191377) (xy 438.915922 -143.147477)
			(xy 438.889209 -143.099228) (xy 438.869721 -143.047636) (xy 438.857866 -142.993775) (xy 438.85389 -142.938768)
			(xy 438.857875 -142.883761) (xy 438.86974 -142.829902) (xy 438.889236 -142.778313) (xy 438.915958 -142.730068)
			(xy 438.949348 -142.686174) (xy 438.968642 -142.666466) (xy 438.975579 -142.659036) (xy 438.983417 -142.6403)
			(xy 438.983882 -142.630144) (xy 438.983882 -138.167364) (xy 438.983434 -138.157208) (xy 438.975574 -138.138478)
			(xy 438.968642 -138.131042) (xy 438.949305 -138.111377) (xy 438.915922 -138.067477) (xy 438.889209 -138.019228)
			(xy 438.869721 -137.967636) (xy 438.857866 -137.913775) (xy 438.85389 -137.858768) (xy 438.857875 -137.803761)
			(xy 438.86974 -137.749902) (xy 438.889236 -137.698313) (xy 438.915958 -137.650068) (xy 438.949348 -137.606174)
			(xy 438.968642 -137.586466) (xy 438.975579 -137.579036) (xy 438.983417 -137.5603) (xy 438.983882 -137.550144)
			(xy 438.983882 -136.77011) (xy 438.984389 -136.660226) (xy 438.992425 -136.440606) (xy 439.008477 -136.221425)
			(xy 439.032522 -136.002978) (xy 439.06453 -135.785553) (xy 439.104456 -135.569443) (xy 439.152247 -135.354935)
			(xy 439.207841 -135.142316) (xy 439.271163 -134.931868) (xy 439.342128 -134.723874) (xy 439.420641 -134.51861)
			(xy 439.506599 -134.31635) (xy 439.599885 -134.117364) (xy 439.700376 -133.921918) (xy 439.807938 -133.730272)
			(xy 439.922427 -133.542682) (xy 440.043691 -133.359399) (xy 440.171567 -133.180666) (xy 440.305885 -133.006723)
			(xy 440.446466 -132.8378) (xy 440.593123 -132.674125) (xy 440.745658 -132.515915) (xy 440.90387 -132.36338)
			(xy 441.067547 -132.216726) (xy 441.236471 -132.076147) (xy 441.410416 -131.94183) (xy 441.58915 -131.813956)
			(xy 441.772435 -131.692694) (xy 441.960026 -131.578207) (xy 442.151673 -131.470647) (xy 442.34712 -131.370158)
			(xy 442.546107 -131.276873) (xy 442.748367 -131.190918) (xy 442.953632 -131.112407) (xy 443.161627 -131.041444)
			(xy 443.372075 -130.978124) (xy 443.584696 -130.922533) (xy 443.799204 -130.874743) (xy 444.015315 -130.834819)
			(xy 444.232739 -130.802814) (xy 444.451187 -130.778771) (xy 444.670368 -130.762722) (xy 444.889988 -130.754688)
			(xy 444.999872 -130.75412) (xy 445.570356 -130.75412) (xy 445.58078 -130.753617) (xy 445.599925 -130.745359)
			(xy 445.60744 -130.738118) (xy 445.627214 -130.717848) (xy 445.671681 -130.682789) (xy 445.720842 -130.654689)
			(xy 445.773617 -130.634164) (xy 445.828846 -130.621666) (xy 445.885316 -130.617469) (xy 445.941786 -130.621666)
			(xy 445.997015 -130.634164) (xy 446.04979 -130.654689) (xy 446.098951 -130.682789) (xy 446.143418 -130.717848)
			(xy 446.163192 -130.738118) (xy 446.170691 -130.745387) (xy 446.189843 -130.753659) (xy 446.200276 -130.75412)
			(xy 450.650356 -130.75412) (xy 450.66078 -130.753617) (xy 450.679925 -130.745359) (xy 450.68744 -130.738118)
			(xy 450.707214 -130.717848) (xy 450.751681 -130.682789) (xy 450.800842 -130.654689) (xy 450.853617 -130.634164)
			(xy 450.908846 -130.621666) (xy 450.965316 -130.617469) (xy 451.021786 -130.621666) (xy 451.077015 -130.634164)
			(xy 451.12979 -130.654689) (xy 451.178951 -130.682789) (xy 451.223418 -130.717848) (xy 451.243192 -130.738118)
			(xy 451.250691 -130.745387) (xy 451.269843 -130.753659) (xy 451.280276 -130.75412) (xy 460.810356 -130.75412)
			(xy 460.82078 -130.753617) (xy 460.839925 -130.745359) (xy 460.84744 -130.738118) (xy 460.867214 -130.717848)
			(xy 460.911681 -130.682789) (xy 460.960842 -130.654689) (xy 461.013617 -130.634164) (xy 461.068846 -130.621666)
			(xy 461.125316 -130.617469) (xy 461.181786 -130.621666) (xy 461.237015 -130.634164) (xy 461.28979 -130.654689)
			(xy 461.338951 -130.682789) (xy 461.383418 -130.717848) (xy 461.403192 -130.738118) (xy 461.410691 -130.745387)
			(xy 461.429843 -130.753659) (xy 461.440276 -130.75412) (xy 465.890356 -130.75412) (xy 465.90078 -130.753617)
			(xy 465.919925 -130.745359) (xy 465.92744 -130.738118) (xy 465.947214 -130.717848) (xy 465.991681 -130.682789)
			(xy 466.040842 -130.654689) (xy 466.093617 -130.634164) (xy 466.148846 -130.621666) (xy 466.205316 -130.617469)
			(xy 466.261786 -130.621666) (xy 466.317015 -130.634164) (xy 466.36979 -130.654689) (xy 466.418951 -130.682789)
			(xy 466.463418 -130.717848) (xy 466.483192 -130.738118) (xy 466.490691 -130.745387) (xy 466.509843 -130.753659)
			(xy 466.520276 -130.75412) (xy 470.97315 -130.75412) (xy 470.984079 -130.753603) (xy 471.00396 -130.744519)
			(xy 471.011504 -130.736594) (xy 471.029713 -130.716407) (xy 471.070865 -130.680882) (xy 471.116642 -130.651559)
			(xy 471.166118 -130.629029) (xy 471.218291 -130.613751) (xy 471.272104 -130.606033) (xy 471.299286 -130.60553)
			(xy 471.326486 -130.606038) (xy 471.380328 -130.613808) (xy 471.432524 -130.629137) (xy 471.482018 -130.651715)
			(xy 471.527809 -130.681085) (xy 471.548714 -130.698494) (xy 471.557442 -130.705241) (xy 471.578633 -130.711296)
			(xy 471.589608 -130.710178) (xy 471.677102 -130.696597) (xy 471.850897 -130.662646) (xy 472.023012 -130.621006)
			(xy 472.193108 -130.57176) (xy 472.360846 -130.515005) (xy 472.525898 -130.450852) (xy 472.687936 -130.379429)
			(xy 472.84664 -130.300877) (xy 473.001697 -130.21535) (xy 473.152801 -130.123019) (xy 473.299652 -130.024064)
			(xy 473.441962 -129.918682) (xy 473.579449 -129.80708) (xy 473.711841 -129.68948) (xy 473.838877 -129.566113)
			(xy 473.960306 -129.437223) (xy 474.075888 -129.303066) (xy 474.185395 -129.163905) (xy 474.28861 -129.020015)
			(xy 474.38533 -128.871682) (xy 474.475363 -128.719197) (xy 474.558531 -128.562863) (xy 474.634672 -128.402987)
			(xy 474.703633 -128.239886) (xy 474.765278 -128.073883) (xy 474.819487 -127.905303) (xy 474.866152 -127.734482)
			(xy 474.90518 -127.561756) (xy 474.936495 -127.387466) (xy 474.960035 -127.211958) (xy 474.975753 -127.035576)
			(xy 474.983618 -126.85867) (xy 474.984064 -126.77013) (xy 474.984064 -126.575058) (xy 474.983615 -126.564903)
			(xy 474.975751 -126.546176) (xy 474.968824 -126.538736) (xy 474.949477 -126.519073) (xy 474.916074 -126.475174)
			(xy 474.889341 -126.426921) (xy 474.869837 -126.375322) (xy 474.857967 -126.321452) (xy 474.85398 -126.266434)
			(xy 474.857958 -126.211415) (xy 474.869818 -126.157542) (xy 474.889313 -126.10594) (xy 474.916037 -126.057683)
			(xy 474.949432 -126.013778) (xy 474.968824 -125.99416) (xy 474.975762 -125.986731) (xy 474.9836 -125.967994)
			(xy 474.984064 -125.957838) (xy 474.984064 -121.495058) (xy 474.983615 -121.484903) (xy 474.975751 -121.466176)
			(xy 474.968824 -121.458736) (xy 474.949477 -121.439073) (xy 474.916074 -121.395174) (xy 474.889341 -121.346921)
			(xy 474.869837 -121.295322) (xy 474.857967 -121.241452) (xy 474.85398 -121.186434) (xy 474.857958 -121.131415)
			(xy 474.869818 -121.077542) (xy 474.889313 -121.02594) (xy 474.916037 -120.977683) (xy 474.949432 -120.933778)
			(xy 474.968824 -120.91416) (xy 474.975762 -120.906731) (xy 474.9836 -120.887994) (xy 474.984064 -120.877838)
			(xy 474.984064 -116.415058) (xy 474.983615 -116.404903) (xy 474.975751 -116.386176) (xy 474.968824 -116.378736)
			(xy 474.949477 -116.359073) (xy 474.916074 -116.315174) (xy 474.889341 -116.266921) (xy 474.869837 -116.215322)
			(xy 474.857967 -116.161452) (xy 474.85398 -116.106434) (xy 474.857958 -116.051415) (xy 474.869818 -115.997542)
			(xy 474.889313 -115.94594) (xy 474.916037 -115.897683) (xy 474.949432 -115.853778) (xy 474.968824 -115.83416)
			(xy 474.975762 -115.826731) (xy 474.9836 -115.807994) (xy 474.984064 -115.797838) (xy 474.984064 -111.335058)
			(xy 474.983615 -111.324903) (xy 474.975751 -111.306176) (xy 474.968824 -111.298736) (xy 474.949477 -111.279073)
			(xy 474.916074 -111.235174) (xy 474.889341 -111.186921) (xy 474.869837 -111.135322) (xy 474.857967 -111.081452)
			(xy 474.85398 -111.026434) (xy 474.857958 -110.971415) (xy 474.869818 -110.917542) (xy 474.889313 -110.86594)
			(xy 474.916037 -110.817683) (xy 474.949432 -110.773778) (xy 474.968824 -110.75416) (xy 474.975762 -110.746731)
			(xy 474.9836 -110.727994) (xy 474.984064 -110.717838) (xy 474.984064 -106.255058) (xy 474.983615 -106.244903)
			(xy 474.975751 -106.226176) (xy 474.968824 -106.218736) (xy 474.949477 -106.199073) (xy 474.916074 -106.155174)
			(xy 474.889341 -106.106921) (xy 474.869837 -106.055322) (xy 474.857967 -106.001452) (xy 474.85398 -105.946434)
			(xy 474.857958 -105.891415) (xy 474.869818 -105.837542) (xy 474.889313 -105.78594) (xy 474.916037 -105.737683)
			(xy 474.949432 -105.693778) (xy 474.968824 -105.67416) (xy 474.975762 -105.666731) (xy 474.9836 -105.647994)
			(xy 474.984064 -105.637838) (xy 474.984064 -101.175058) (xy 474.983615 -101.164903) (xy 474.975751 -101.146176)
			(xy 474.968824 -101.138736) (xy 474.949477 -101.119073) (xy 474.916074 -101.075174) (xy 474.889341 -101.026921)
			(xy 474.869837 -100.975322) (xy 474.857967 -100.921452) (xy 474.85398 -100.866434) (xy 474.857958 -100.811415)
			(xy 474.869818 -100.757542) (xy 474.889313 -100.70594) (xy 474.916037 -100.657683) (xy 474.949432 -100.613778)
			(xy 474.968824 -100.59416) (xy 474.975762 -100.586731) (xy 474.9836 -100.567994) (xy 474.984064 -100.557838)
			(xy 474.984064 -96.095058) (xy 474.983615 -96.084903) (xy 474.975751 -96.066176) (xy 474.968824 -96.058736)
			(xy 474.949477 -96.039073) (xy 474.916074 -95.995174) (xy 474.889341 -95.946921) (xy 474.869837 -95.895322)
			(xy 474.857967 -95.841452) (xy 474.85398 -95.786434) (xy 474.857958 -95.731415) (xy 474.869818 -95.677542)
			(xy 474.889313 -95.62594) (xy 474.916037 -95.577683) (xy 474.949432 -95.533778) (xy 474.968824 -95.51416)
			(xy 474.975762 -95.506731) (xy 474.9836 -95.487994) (xy 474.984064 -95.477838) (xy 474.984064 -91.015058)
			(xy 474.983615 -91.004903) (xy 474.975751 -90.986176) (xy 474.968824 -90.978736) (xy 474.949477 -90.959073)
			(xy 474.916074 -90.915174) (xy 474.889341 -90.866921) (xy 474.869837 -90.815322) (xy 474.857967 -90.761452)
			(xy 474.85398 -90.706434) (xy 474.857958 -90.651415) (xy 474.869818 -90.597542) (xy 474.889313 -90.54594)
			(xy 474.916037 -90.497683) (xy 474.949432 -90.453778) (xy 474.968824 -90.43416) (xy 474.975762 -90.426731)
			(xy 474.9836 -90.407994) (xy 474.984064 -90.397838) (xy 474.984064 -85.935058) (xy 474.983615 -85.924903)
			(xy 474.975751 -85.906176) (xy 474.968824 -85.898736) (xy 474.949477 -85.879073) (xy 474.916074 -85.835174)
			(xy 474.889341 -85.786921) (xy 474.869837 -85.735322) (xy 474.857967 -85.681452) (xy 474.85398 -85.626434)
			(xy 474.857958 -85.571415) (xy 474.869818 -85.517542) (xy 474.889313 -85.46594) (xy 474.916037 -85.417683)
			(xy 474.949432 -85.373778) (xy 474.968824 -85.35416) (xy 474.975762 -85.346731) (xy 474.9836 -85.327994)
			(xy 474.984064 -85.317838) (xy 474.984064 -80.855058) (xy 474.983615 -80.844903) (xy 474.975751 -80.826176)
			(xy 474.968824 -80.818736) (xy 474.949477 -80.799073) (xy 474.916074 -80.755174) (xy 474.889341 -80.706921)
			(xy 474.869837 -80.655322) (xy 474.857967 -80.601452) (xy 474.85398 -80.546434) (xy 474.857958 -80.491415)
			(xy 474.869818 -80.437542) (xy 474.889313 -80.38594) (xy 474.916037 -80.337683) (xy 474.949432 -80.293778)
			(xy 474.968824 -80.27416) (xy 474.975762 -80.266731) (xy 474.9836 -80.247994) (xy 474.984064 -80.237838)
			(xy 474.984064 -75.775058) (xy 474.983615 -75.764903) (xy 474.975751 -75.746176) (xy 474.968824 -75.738736)
			(xy 474.949477 -75.719073) (xy 474.916074 -75.675174) (xy 474.889341 -75.626921) (xy 474.869837 -75.575322)
			(xy 474.857967 -75.521452) (xy 474.85398 -75.466434) (xy 474.857958 -75.411415) (xy 474.869818 -75.357542)
			(xy 474.889313 -75.30594) (xy 474.916037 -75.257683) (xy 474.949432 -75.213778) (xy 474.968824 -75.19416)
			(xy 474.975762 -75.186731) (xy 474.9836 -75.167994) (xy 474.984064 -75.157838) (xy 474.984064 -70.695058)
			(xy 474.983615 -70.684903) (xy 474.975751 -70.666176) (xy 474.968824 -70.658736) (xy 474.949477 -70.639073)
			(xy 474.916074 -70.595174) (xy 474.889341 -70.546921) (xy 474.869837 -70.495322) (xy 474.857967 -70.441452)
			(xy 474.85398 -70.386434) (xy 474.857958 -70.331415) (xy 474.869818 -70.277542) (xy 474.889313 -70.22594)
			(xy 474.916037 -70.177683) (xy 474.949432 -70.133778) (xy 474.968824 -70.11416) (xy 474.975762 -70.106731)
			(xy 474.9836 -70.087994) (xy 474.984064 -70.077838) (xy 474.984064 -65.615058) (xy 474.983615 -65.604903)
			(xy 474.975751 -65.586176) (xy 474.968824 -65.578736) (xy 474.949477 -65.559073) (xy 474.916074 -65.515174)
			(xy 474.889341 -65.466921) (xy 474.869837 -65.415322) (xy 474.857967 -65.361452) (xy 474.85398 -65.306434)
			(xy 474.857958 -65.251415) (xy 474.869818 -65.197542) (xy 474.889313 -65.14594) (xy 474.916037 -65.097683)
			(xy 474.949432 -65.053778) (xy 474.968824 -65.03416) (xy 474.975762 -65.026731) (xy 474.9836 -65.007994)
			(xy 474.984064 -64.997838) (xy 474.984064 -60.535058) (xy 474.983615 -60.524903) (xy 474.975751 -60.506176)
			(xy 474.968824 -60.498736) (xy 474.949477 -60.479073) (xy 474.916074 -60.435174) (xy 474.889341 -60.386921)
			(xy 474.869837 -60.335322) (xy 474.857967 -60.281452) (xy 474.85398 -60.226434) (xy 474.857958 -60.171415)
			(xy 474.869818 -60.117542) (xy 474.889313 -60.06594) (xy 474.916037 -60.017683) (xy 474.949432 -59.973778)
			(xy 474.968824 -59.95416) (xy 474.975762 -59.946731) (xy 474.9836 -59.927994) (xy 474.984064 -59.917838)
			(xy 474.984064 -55.455058) (xy 474.983615 -55.444903) (xy 474.975751 -55.426176) (xy 474.968824 -55.418736)
			(xy 474.949477 -55.399073) (xy 474.916074 -55.355174) (xy 474.889341 -55.306921) (xy 474.869837 -55.255322)
			(xy 474.857967 -55.201452) (xy 474.85398 -55.146434) (xy 474.857958 -55.091415) (xy 474.869818 -55.037542)
			(xy 474.889313 -54.98594) (xy 474.916037 -54.937683) (xy 474.949432 -54.893778) (xy 474.968824 -54.87416)
			(xy 474.975762 -54.866731) (xy 474.9836 -54.847994) (xy 474.984064 -54.837838) (xy 474.984064 -50.375058)
			(xy 474.983615 -50.364903) (xy 474.975751 -50.346176) (xy 474.968824 -50.338736) (xy 474.949477 -50.319073)
			(xy 474.916074 -50.275174) (xy 474.889341 -50.226921) (xy 474.869837 -50.175322) (xy 474.857967 -50.121452)
			(xy 474.85398 -50.066434) (xy 474.857958 -50.011415) (xy 474.869818 -49.957542) (xy 474.889313 -49.90594)
			(xy 474.916037 -49.857683) (xy 474.949432 -49.813778) (xy 474.968824 -49.79416) (xy 474.975762 -49.786731)
			(xy 474.9836 -49.767994) (xy 474.984064 -49.757838) (xy 474.984064 -45.295058) (xy 474.983615 -45.284903)
			(xy 474.975751 -45.266176) (xy 474.968824 -45.258736) (xy 474.949477 -45.239073) (xy 474.916074 -45.195174)
			(xy 474.889341 -45.146921) (xy 474.869837 -45.095322) (xy 474.857967 -45.041452) (xy 474.85398 -44.986434)
			(xy 474.857958 -44.931415) (xy 474.869818 -44.877542) (xy 474.889313 -44.82594) (xy 474.916037 -44.777683)
			(xy 474.949432 -44.733778) (xy 474.968824 -44.71416) (xy 474.975762 -44.706731) (xy 474.9836 -44.687994)
			(xy 474.984064 -44.677838) (xy 474.984064 -40.215058) (xy 474.983615 -40.204903) (xy 474.975751 -40.186176)
			(xy 474.968824 -40.178736) (xy 474.949477 -40.159073) (xy 474.916074 -40.115174) (xy 474.889341 -40.066921)
			(xy 474.869837 -40.015322) (xy 474.857967 -39.961452) (xy 474.85398 -39.906434) (xy 474.857958 -39.851415)
			(xy 474.869818 -39.797542) (xy 474.889313 -39.74594) (xy 474.916037 -39.697683) (xy 474.949432 -39.653778)
			(xy 474.968824 -39.63416) (xy 474.975762 -39.626731) (xy 474.9836 -39.607994) (xy 474.984064 -39.597838)
			(xy 474.984064 -35.135058) (xy 474.983615 -35.124903) (xy 474.975751 -35.106176) (xy 474.968824 -35.098736)
			(xy 474.949477 -35.079073) (xy 474.916074 -35.035174) (xy 474.889341 -34.986921) (xy 474.869837 -34.935322)
			(xy 474.857967 -34.881452) (xy 474.85398 -34.826434) (xy 474.857958 -34.771415) (xy 474.869818 -34.717542)
			(xy 474.889313 -34.66594) (xy 474.916037 -34.617683) (xy 474.949432 -34.573778) (xy 474.968824 -34.55416)
			(xy 474.975762 -34.546731) (xy 474.9836 -34.527994) (xy 474.984064 -34.517838) (xy 474.984064 -30.055058)
			(xy 474.983615 -30.044903) (xy 474.975751 -30.026176) (xy 474.968824 -30.018736) (xy 474.949477 -29.999073)
			(xy 474.916074 -29.955174) (xy 474.889341 -29.906921) (xy 474.869837 -29.855322) (xy 474.857967 -29.801452)
			(xy 474.85398 -29.746434) (xy 474.857958 -29.691415) (xy 474.869818 -29.637542) (xy 474.889313 -29.58594)
			(xy 474.916037 -29.537683) (xy 474.949432 -29.493778) (xy 474.968824 -29.47416) (xy 474.975762 -29.466731)
			(xy 474.9836 -29.447994) (xy 474.984064 -29.437838) (xy 474.984064 -24.162258) (xy 474.983615 -24.152103)
			(xy 474.975751 -24.133376) (xy 474.968824 -24.125936) (xy 474.949522 -24.106278) (xy 474.916203 -24.062405)
			(xy 474.889541 -24.014196) (xy 474.870091 -23.962653) (xy 474.858256 -23.908849) (xy 474.854284 -23.853901)
			(xy 474.858256 -23.798954) (xy 474.87009 -23.745149) (xy 474.88954 -23.693606) (xy 474.916202 -23.645397)
			(xy 474.94952 -23.601524) (xy 474.968824 -23.581868) (xy 474.975763 -23.574439) (xy 474.983605 -23.555703)
			(xy 474.984064 -23.545546) (xy 474.984064 -21.770086) (xy 474.983564 -21.680002) (xy 474.975423 -21.500018)
			(xy 474.959154 -21.320586) (xy 474.93479 -21.142073) (xy 474.90238 -20.964844) (xy 474.861992 -20.789262)
			(xy 474.813708 -20.615684) (xy 474.757626 -20.444467) (xy 474.693861 -20.27596) (xy 474.622544 -20.110509)
			(xy 474.54382 -19.94845) (xy 474.45785 -19.790116) (xy 474.364811 -19.63583) (xy 474.264892 -19.485908)
			(xy 474.158297 -19.340656) (xy 474.045245 -19.200372) (xy 473.925967 -19.065341) (xy 473.800706 -18.935841)
			(xy 473.669719 -18.812137) (xy 473.533274 -18.69448) (xy 473.391649 -18.583111) (xy 473.245134 -18.478259)
			(xy 473.09403 -18.380138) (xy 472.938643 -18.288948) (xy 472.779294 -18.204875) (xy 472.616306 -18.128093)
			(xy 472.450014 -18.058757) (xy 472.280758 -17.997009) (xy 472.108883 -17.942976) (xy 471.934742 -17.896769)
			(xy 471.758689 -17.858481) (xy 471.581085 -17.828191) (xy 471.402294 -17.805961) (xy 471.222681 -17.791836)
			(xy 471.132662 -17.788382) (xy 471.122139 -17.788535) (xy 471.102593 -17.796277) (xy 471.094816 -17.803368)
			(xy 471.073169 -17.82448) (xy 471.024442 -17.860279) (xy 470.97068 -17.887947) (xy 470.913227 -17.90679)
			(xy 470.853522 -17.916339) (xy 470.82329 -17.916906) (xy 470.797892 -17.916487) (xy 470.747545 -17.909745)
			(xy 470.698538 -17.896381) (xy 470.651738 -17.876632) (xy 470.607973 -17.850847) (xy 470.568016 -17.819483)
			(xy 470.549986 -17.80159) (xy 470.542538 -17.794529) (xy 470.523663 -17.786518) (xy 470.51341 -17.786096)
			(xy 466.05317 -17.786096) (xy 466.042924 -17.786561) (xy 466.024054 -17.794552) (xy 466.016594 -17.80159)
			(xy 465.996905 -17.821094) (xy 465.952899 -17.854782) (xy 465.904483 -17.881749) (xy 465.852674 -17.901427)
			(xy 465.798564 -17.913402) (xy 465.74329 -17.917422) (xy 465.688016 -17.913402) (xy 465.633906 -17.901427)
			(xy 465.582097 -17.881749) (xy 465.533681 -17.854782) (xy 465.489675 -17.821094) (xy 465.469986 -17.80159)
			(xy 465.462538 -17.794529) (xy 465.443663 -17.786518) (xy 465.43341 -17.786096) (xy 460.97317 -17.786096)
			(xy 460.962924 -17.786561) (xy 460.944054 -17.794552) (xy 460.936594 -17.80159) (xy 460.916905 -17.821094)
			(xy 460.872899 -17.854782) (xy 460.824483 -17.881749) (xy 460.772674 -17.901427) (xy 460.718564 -17.913402)
			(xy 460.66329 -17.917422) (xy 460.608016 -17.913402) (xy 460.553906 -17.901427) (xy 460.502097 -17.881749)
			(xy 460.453681 -17.854782) (xy 460.409675 -17.821094) (xy 460.389986 -17.80159) (xy 460.382538 -17.794529)
			(xy 460.363663 -17.786518) (xy 460.35341 -17.786096) (xy 455.89317 -17.786096) (xy 455.882924 -17.786561)
			(xy 455.864054 -17.794552) (xy 455.856594 -17.80159) (xy 455.836905 -17.821094) (xy 455.792899 -17.854782)
			(xy 455.744483 -17.881749) (xy 455.692674 -17.901427) (xy 455.638564 -17.913402) (xy 455.58329 -17.917422)
			(xy 455.528016 -17.913402) (xy 455.473906 -17.901427) (xy 455.422097 -17.881749) (xy 455.373681 -17.854782)
			(xy 455.329675 -17.821094) (xy 455.309986 -17.80159) (xy 455.302538 -17.794529) (xy 455.283663 -17.786518)
			(xy 455.27341 -17.786096) (xy 450.81317 -17.786096) (xy 450.802924 -17.786561) (xy 450.784054 -17.794552)
			(xy 450.776594 -17.80159) (xy 450.756905 -17.821094) (xy 450.712899 -17.854782) (xy 450.664483 -17.881749)
			(xy 450.612674 -17.901427) (xy 450.558564 -17.913402) (xy 450.50329 -17.917422) (xy 450.448016 -17.913402)
			(xy 450.393906 -17.901427) (xy 450.342097 -17.881749) (xy 450.293681 -17.854782) (xy 450.249675 -17.821094)
			(xy 450.229986 -17.80159) (xy 450.222538 -17.794529) (xy 450.203663 -17.786518) (xy 450.19341 -17.786096)
			(xy 445.73317 -17.786096) (xy 445.722924 -17.786561) (xy 445.704054 -17.794552) (xy 445.696594 -17.80159)
			(xy 445.676905 -17.821094) (xy 445.632899 -17.854782) (xy 445.584483 -17.881749) (xy 445.532674 -17.901427)
			(xy 445.478564 -17.913402) (xy 445.42329 -17.917422) (xy 445.368016 -17.913402) (xy 445.313906 -17.901427)
			(xy 445.262097 -17.881749) (xy 445.213681 -17.854782) (xy 445.169675 -17.821094) (xy 445.149986 -17.80159)
			(xy 445.142538 -17.794529) (xy 445.123663 -17.786518) (xy 445.11341 -17.786096) (xy 444.999872 -17.786096)
			(xy 444.889371 -17.785588) (xy 444.668519 -17.777471) (xy 444.448114 -17.761248) (xy 444.228454 -17.736942)
			(xy 444.009834 -17.704585) (xy 443.792551 -17.664222) (xy 443.576896 -17.615905) (xy 443.363161 -17.559702)
			(xy 443.151634 -17.495687) (xy 442.942601 -17.423946) (xy 442.736343 -17.344578) (xy 442.53314 -17.257688)
			(xy 442.333264 -17.163394) (xy 442.136987 -17.061823) (xy 441.944572 -16.953112) (xy 441.756279 -16.837409)
			(xy 441.572363 -16.714868) (xy 441.393071 -16.585656) (xy 441.218645 -16.449946) (xy 441.049321 -16.307922)
			(xy 440.885326 -16.159775) (xy 440.726884 -16.005706) (xy 440.574206 -15.845922) (xy 440.427499 -15.680638)
			(xy 440.286962 -15.510078) (xy 440.152783 -15.334472) (xy 440.088528 -15.244572) (xy 440.082522 -15.236833)
			(xy 440.066057 -15.226253) (xy 440.056524 -15.223998) (xy 440.030665 -15.218643) (xy 439.980632 -15.20175)
			(xy 439.933409 -15.178116) (xy 439.889898 -15.148192) (xy 439.850931 -15.112551) (xy 439.817255 -15.071875)
			(xy 439.789513 -15.026941) (xy 439.768236 -14.97861) (xy 439.753831 -14.927805) (xy 439.746573 -14.875498)
			(xy 439.746136 -14.849094) (xy 439.746529 -14.824626) (xy 439.752768 -14.77609) (xy 439.758582 -14.75232)
			(xy 439.760641 -14.742719) (xy 439.758146 -14.723259) (xy 439.753756 -14.714474) (xy 439.701459 -14.62032)
			(xy 439.60282 -14.428828) (xy 439.511099 -14.233928) (xy 439.426412 -14.03587) (xy 439.348869 -13.834908)
			(xy 439.278569 -13.631299) (xy 439.215602 -13.425304) (xy 439.160049 -13.217187) (xy 439.11198 -13.007215)
			(xy 439.071458 -12.795657) (xy 439.038534 -12.582784) (xy 439.013251 -12.368869) (xy 438.995641 -12.154187)
			(xy 438.985727 -11.939011) (xy 438.984136 -11.83132) (xy 438.983571 -11.821118) (xy 438.975441 -11.802392)
			(xy 438.968388 -11.794998) (xy 438.949927 -11.776925) (xy 438.917556 -11.736662) (xy 438.890919 -11.692397)
			(xy 438.870504 -11.644939) (xy 438.856686 -11.595159) (xy 438.849717 -11.543969) (xy 438.849262 -11.518138)
			(xy 438.849687 -11.492335) (xy 438.856643 -11.441201) (xy 438.870434 -11.391473) (xy 438.890806 -11.344059)
			(xy 438.917388 -11.299827) (xy 438.949694 -11.259585) (xy 438.968134 -11.241532) (xy 438.975286 -11.234053)
			(xy 438.983399 -11.21504) (xy 438.983882 -11.204702) (xy 438.983882 -6.751574) (xy 438.983402 -6.741237)
			(xy 438.975285 -6.722223) (xy 438.968134 -6.714744) (xy 438.948055 -6.695005) (xy 438.913344 -6.650673)
			(xy 438.88553 -6.601719) (xy 438.865218 -6.549206) (xy 438.85285 -6.494277) (xy 438.848694 -6.438126)
			(xy 438.852842 -6.381975) (xy 438.865202 -6.327044) (xy 438.885507 -6.274529) (xy 438.913314 -6.22557)
			(xy 438.948019 -6.181233) (xy 438.968134 -6.161532) (xy 438.975286 -6.154053) (xy 438.983399 -6.13504)
			(xy 438.983882 -6.124702) (xy 438.983882 -4.99999) (xy 438.98338 -4.910586) (xy 438.975357 -4.731958)
			(xy 438.959329 -4.55387) (xy 438.935326 -4.37668) (xy 438.903399 -4.200745) (xy 438.86361 -4.02642)
			(xy 438.81604 -3.854056) (xy 438.760784 -3.683999) (xy 438.697955 -3.516593) (xy 438.627679 -3.352174)
			(xy 438.550097 -3.191074) (xy 438.465365 -3.033617) (xy 438.373654 -2.880119) (xy 438.275148 -2.730891)
			(xy 438.170047 -2.586232) (xy 438.058562 -2.446435) (xy 437.940917 -2.31178) (xy 437.817349 -2.182538)
			(xy 437.688107 -2.058971) (xy 437.553451 -1.941327) (xy 437.413653 -1.829842) (xy 437.268994 -1.724741)
			(xy 437.119766 -1.626237) (xy 436.966268 -1.534527) (xy 436.80881 -1.449795) (xy 436.647709 -1.372214)
			(xy 436.48329 -1.301938) (xy 436.315884 -1.23911) (xy 436.145827 -1.183855) (xy 435.973462 -1.136286)
			(xy 435.799137 -1.096498) (xy 435.623202 -1.064571) (xy 435.446013 -1.040569) (xy 435.267924 -1.024541)
			(xy 435.089296 -1.016519) (xy 434.999892 -1.016) (xy 434.25618 -1.016) (xy 434.246111 -1.016427)
			(xy 434.227512 -1.024146) (xy 434.220112 -1.030986) (xy 434.200474 -1.050168) (xy 434.156682 -1.083267)
			(xy 434.108597 -1.109748) (xy 434.057214 -1.129064) (xy 434.003592 -1.140815) (xy 433.94884 -1.144759)
			(xy 433.894088 -1.140815) (xy 433.840466 -1.129064) (xy 433.789083 -1.109748) (xy 433.740998 -1.083267)
			(xy 433.697206 -1.050168) (xy 433.677568 -1.030986) (xy 433.670172 -1.024135) (xy 433.651573 -1.016399)
			(xy 433.6415 -1.016) (xy 424.248834 -1.016) (xy 424.238769 -1.016435) (xy 424.220182 -1.024167) (xy 424.212766 -1.030986)
			(xy 423.213276 -2.030222) (xy 423.19829 -2.044954) (xy 423.19117 -2.052378) (xy 423.18305 -2.071256)
			(xy 423.182542 -2.08153) (xy 423.182542 -11.420348) (xy 423.182975 -11.430413) (xy 423.190707 -11.449001)
			(xy 423.197528 -11.456416) (xy 428.472346 -16.731234) (xy 428.479744 -16.73808) (xy 428.498343 -16.745809)
			(xy 428.508414 -16.74622) (xy 435.226968 -16.74622) (xy 435.260229 -16.746739) (xy 435.326181 -16.755423)
			(xy 435.390434 -16.772646) (xy 435.451887 -16.798113) (xy 435.509488 -16.831388) (xy 435.56225 -16.8719)
			(xy 435.586124 -16.895064) (xy 446.877694 -28.186634) (xy 446.897252 -28.194254) (xy 446.907666 -28.194)
			(xy 446.9384 -28.193492) (xy 446.979502 -28.193967) (xy 447.061357 -28.201552) (xy 447.142162 -28.216657)
			(xy 447.221229 -28.239153) (xy 447.297883 -28.268849) (xy 447.37147 -28.305491) (xy 447.441362 -28.348766)
			(xy 447.506963 -28.398306) (xy 447.567713 -28.453687) (xy 447.623094 -28.514437) (xy 447.672634 -28.580038)
			(xy 447.715909 -28.64993) (xy 447.752551 -28.723517) (xy 447.782247 -28.800171) (xy 447.804743 -28.879238)
			(xy 447.819848 -28.960043) (xy 447.827433 -29.041898) (xy 447.827908 -29.083) (xy 447.8274 -29.113734)
			(xy 447.827146 -29.124148) (xy 447.834766 -29.143706) (xy 448.15125 -29.459936) (xy 448.166998 -29.467556)
			(xy 448.175634 -29.468318) (xy 448.218514 -29.4734) (xy 448.303091 -29.490822) (xy 448.385583 -29.516358)
			(xy 448.465212 -29.549766) (xy 448.54123 -29.590731) (xy 448.612921 -29.63887) (xy 448.679611 -29.693727)
			(xy 448.740673 -29.754789) (xy 448.79553 -29.821479) (xy 448.843669 -29.89317) (xy 448.884634 -29.969188)
			(xy 448.918042 -30.048817) (xy 448.943578 -30.131309) (xy 448.961 -30.215886) (xy 448.966082 -30.258766)
			(xy 448.966844 -30.267402) (xy 448.974464 -30.28315) (xy 450.73062 -32.03956) (xy 450.74078 -32.04591)
			(xy 450.746622 -32.047688) (xy 450.786044 -32.061146) (xy 450.862416 -32.094425) (xy 450.935342 -32.134697)
			(xy 451.004184 -32.18161) (xy 451.06834 -32.234753) (xy 451.127247 -32.29366) (xy 451.18039 -32.357816)
			(xy 451.227303 -32.426658) (xy 451.267575 -32.499584) (xy 451.300854 -32.575956) (xy 451.314312 -32.615378)
			(xy 451.31609 -32.62122) (xy 451.32244 -32.63138) (xy 453.118474 -34.427414) (xy 453.125872 -34.434258)
			(xy 453.144472 -34.441979) (xy 453.154542 -34.4424) (xy 460.502 -34.4424) (xy 460.53526 -34.442921)
			(xy 460.60121 -34.451609) (xy 460.665461 -34.468834) (xy 460.726912 -34.494303) (xy 460.784511 -34.527579)
			(xy 460.837271 -34.568092) (xy 460.861156 -34.591244) (xy 467.338156 -41.068244) (xy 467.361312 -41.092124)
			(xy 467.401818 -41.144888) (xy 467.435089 -41.202489) (xy 467.460553 -41.26394) (xy 467.477775 -41.328191)
			(xy 467.486461 -41.394141) (xy 467.487 -41.4274) (xy 467.487 -55.989982) (xy 468.668617 -55.989982)
			(xy 468.672606 -55.877017) (xy 468.684554 -55.764614) (xy 468.704401 -55.653334) (xy 468.732047 -55.543732)
			(xy 468.767357 -55.436352) (xy 468.810152 -55.331731) (xy 468.860221 -55.230389) (xy 468.917314 -55.132831)
			(xy 468.981147 -55.039544) (xy 469.0514 -54.950991) (xy 469.127725 -54.867615) (xy 469.209741 -54.789831)
			(xy 469.29704 -54.718025) (xy 469.389186 -54.652556) (xy 469.485721 -54.593751) (xy 469.586164 -54.541901)
			(xy 469.690014 -54.497266) (xy 469.796753 -54.460067) (xy 469.905851 -54.43049) (xy 470.016763 -54.408682)
			(xy 470.128937 -54.394753) (xy 470.241815 -54.38877) (xy 470.354833 -54.390765) (xy 470.467429 -54.400727)
			(xy 470.579042 -54.418607) (xy 470.689115 -54.444315) (xy 470.797101 -54.477724) (xy 470.902461 -54.518667)
			(xy 471.004671 -54.566939) (xy 471.103221 -54.622302) (xy 471.197621 -54.684477) (xy 471.287399 -54.753157)
			(xy 471.372109 -54.827999) (xy 471.451329 -54.90863) (xy 471.524664 -54.994647) (xy 471.591749 -55.085624)
			(xy 471.652249 -55.181106) (xy 471.705863 -55.280618) (xy 471.752325 -55.383664) (xy 471.791402 -55.48973)
			(xy 471.822899 -55.598289) (xy 471.846661 -55.708799) (xy 471.862568 -55.82071) (xy 471.870541 -55.933464)
			(xy 471.87104 -55.989982) (xy 471.870541 -56.0465) (xy 471.862568 -56.159254) (xy 471.846661 -56.271165)
			(xy 471.822899 -56.381675) (xy 471.791402 -56.490234) (xy 471.752325 -56.5963) (xy 471.705863 -56.699346)
			(xy 471.652249 -56.798858) (xy 471.591749 -56.89434) (xy 471.524664 -56.985317) (xy 471.451329 -57.071334)
			(xy 471.372109 -57.151965) (xy 471.287399 -57.226807) (xy 471.197621 -57.295487) (xy 471.103221 -57.357662)
			(xy 471.004671 -57.413025) (xy 470.902461 -57.461297) (xy 470.797101 -57.50224) (xy 470.689115 -57.535649)
			(xy 470.579042 -57.561357) (xy 470.467429 -57.579237) (xy 470.354833 -57.589199) (xy 470.241815 -57.591194)
			(xy 470.128937 -57.585211) (xy 470.016763 -57.571282) (xy 469.905851 -57.549474) (xy 469.796753 -57.519897)
			(xy 469.690014 -57.482698) (xy 469.586164 -57.438063) (xy 469.485721 -57.386213) (xy 469.389186 -57.327408)
			(xy 469.29704 -57.261939) (xy 469.209741 -57.190133) (xy 469.127725 -57.112349) (xy 469.0514 -57.028973)
			(xy 468.981147 -56.94042) (xy 468.917314 -56.847133) (xy 468.860221 -56.749575) (xy 468.810152 -56.648233)
			(xy 468.767357 -56.543612) (xy 468.732047 -56.436232) (xy 468.704401 -56.32663) (xy 468.684554 -56.21535)
			(xy 468.672606 -56.102947) (xy 468.668617 -55.989982) (xy 467.487 -55.989982) (xy 467.487 -66.138806)
			(xy 467.487424 -66.148876) (xy 467.49514 -66.167479) (xy 467.501986 -66.174874) (xy 468.241126 -66.914014)
			(xy 468.248522 -66.920866) (xy 468.267121 -66.928604) (xy 468.277194 -66.929) (xy 472.6686 -66.929)
			(xy 472.70186 -66.929521) (xy 472.76781 -66.938209) (xy 472.832061 -66.955434) (xy 472.893512 -66.980903)
			(xy 472.951111 -67.014179) (xy 473.003871 -67.054692) (xy 473.027756 -67.077844) (xy 473.662756 -67.712844)
			(xy 473.685912 -67.736724) (xy 473.726418 -67.789488) (xy 473.759689 -67.847089) (xy 473.785153 -67.90854)
			(xy 473.802375 -67.972791) (xy 473.811061 -68.038741) (xy 473.8116 -68.072) (xy 473.8116 -76.962)
			(xy 473.811079 -76.99526) (xy 473.802391 -77.06121) (xy 473.785166 -77.125461) (xy 473.759697 -77.186912)
			(xy 473.726421 -77.244511) (xy 473.685908 -77.297271) (xy 473.662756 -77.321156) (xy 473.027756 -77.956156)
			(xy 473.003876 -77.979312) (xy 472.951112 -78.019818) (xy 472.893511 -78.053089) (xy 472.83206 -78.078553)
			(xy 472.767809 -78.095775) (xy 472.701859 -78.104461) (xy 472.6686 -78.105) (xy 419.851078 -78.105)
			(xy 419.84101 -78.105427) (xy 419.822411 -78.113147) (xy 419.81501 -78.119986) (xy 419.116002 -78.818994)
			(xy 419.109154 -78.826392) (xy 419.101417 -78.84499) (xy 419.101016 -78.855062) (xy 419.101016 -91.549982)
			(xy 470.018627 -91.549982) (xy 470.022616 -91.437017) (xy 470.034564 -91.324614) (xy 470.054411 -91.213334)
			(xy 470.082057 -91.103732) (xy 470.117367 -90.996352) (xy 470.160162 -90.891731) (xy 470.210231 -90.790389)
			(xy 470.267324 -90.692831) (xy 470.331157 -90.599544) (xy 470.40141 -90.510991) (xy 470.477735 -90.427615)
			(xy 470.559751 -90.349831) (xy 470.64705 -90.278025) (xy 470.739196 -90.212556) (xy 470.835731 -90.153751)
			(xy 470.936174 -90.101901) (xy 471.040024 -90.057266) (xy 471.146763 -90.020067) (xy 471.255861 -89.99049)
			(xy 471.366773 -89.968682) (xy 471.478947 -89.954753) (xy 471.591825 -89.94877) (xy 471.704843 -89.950765)
			(xy 471.817439 -89.960727) (xy 471.929052 -89.978607) (xy 472.039125 -90.004315) (xy 472.147111 -90.037724)
			(xy 472.252471 -90.078667) (xy 472.354681 -90.126939) (xy 472.453231 -90.182302) (xy 472.547631 -90.244477)
			(xy 472.637409 -90.313157) (xy 472.722119 -90.387999) (xy 472.801339 -90.46863) (xy 472.874674 -90.554647)
			(xy 472.941759 -90.645624) (xy 473.002259 -90.741106) (xy 473.055873 -90.840618) (xy 473.102335 -90.943664)
			(xy 473.141412 -91.04973) (xy 473.172909 -91.158289) (xy 473.196671 -91.268799) (xy 473.212578 -91.38071)
			(xy 473.220551 -91.493464) (xy 473.22105 -91.549982) (xy 473.220551 -91.6065) (xy 473.212578 -91.719254)
			(xy 473.196671 -91.831165) (xy 473.172909 -91.941675) (xy 473.141412 -92.050234) (xy 473.102335 -92.1563)
			(xy 473.055873 -92.259346) (xy 473.002259 -92.358858) (xy 472.941759 -92.45434) (xy 472.874674 -92.545317)
			(xy 472.801339 -92.631334) (xy 472.722119 -92.711965) (xy 472.637409 -92.786807) (xy 472.547631 -92.855487)
			(xy 472.453231 -92.917662) (xy 472.354681 -92.973025) (xy 472.252471 -93.021297) (xy 472.147111 -93.06224)
			(xy 472.039125 -93.095649) (xy 471.929052 -93.121357) (xy 471.817439 -93.139237) (xy 471.704843 -93.149199)
			(xy 471.591825 -93.151194) (xy 471.478947 -93.145211) (xy 471.366773 -93.131282) (xy 471.255861 -93.109474)
			(xy 471.146763 -93.079897) (xy 471.040024 -93.042698) (xy 470.936174 -92.998063) (xy 470.835731 -92.946213)
			(xy 470.739196 -92.887408) (xy 470.64705 -92.821939) (xy 470.559751 -92.750133) (xy 470.477735 -92.672349)
			(xy 470.40141 -92.588973) (xy 470.331157 -92.50042) (xy 470.267324 -92.407133) (xy 470.210231 -92.309575)
			(xy 470.160162 -92.208233) (xy 470.117367 -92.103612) (xy 470.082057 -91.996232) (xy 470.054411 -91.88663)
			(xy 470.034564 -91.77535) (xy 470.022616 -91.662947) (xy 470.018627 -91.549982) (xy 419.101016 -91.549982)
			(xy 419.101016 -104.549956) (xy 422.484046 -104.549956) (xy 422.488076 -104.407621) (xy 422.500151 -104.265741)
			(xy 422.520234 -104.124773) (xy 422.548261 -103.985166) (xy 422.584141 -103.847368) (xy 422.627759 -103.711821)
			(xy 422.678976 -103.578959) (xy 422.737627 -103.449207) (xy 422.803525 -103.322981) (xy 422.876459 -103.200685)
			(xy 422.956196 -103.082712) (xy 423.042478 -102.969439) (xy 423.135031 -102.861228) (xy 423.233558 -102.758427)
			(xy 423.337743 -102.661365) (xy 423.447252 -102.570353) (xy 423.561735 -102.485681) (xy 423.680825 -102.407623)
			(xy 423.80414 -102.336427) (xy 423.931286 -102.272321) (xy 424.061855 -102.215512) (xy 424.195429 -102.16618)
			(xy 424.33158 -102.124484) (xy 424.469871 -102.090558) (xy 424.609861 -102.06451) (xy 424.7511 -102.046424)
			(xy 424.893136 -102.036357) (xy 425.035514 -102.034342) (xy 425.177778 -102.040385) (xy 425.319472 -102.054467)
			(xy 425.460142 -102.076543) (xy 425.599339 -102.106543) (xy 425.736615 -102.144369) (xy 425.871531 -102.189901)
			(xy 426.003655 -102.242992) (xy 426.132564 -102.303474) (xy 426.257845 -102.371152) (xy 426.379096 -102.445809)
			(xy 426.495929 -102.527207) (xy 426.60797 -102.615084) (xy 426.71486 -102.709159) (xy 426.816257 -102.809131)
			(xy 426.911835 -102.914679) (xy 427.001289 -103.025465) (xy 427.084331 -103.141134) (xy 427.160697 -103.261317)
			(xy 427.230141 -103.385627) (xy 427.292441 -103.513668) (xy 427.347397 -103.645027) (xy 427.394834 -103.779286)
			(xy 427.434598 -103.916013) (xy 427.466564 -104.054771) (xy 427.490629 -104.195115) (xy 427.506715 -104.336596)
			(xy 427.51477 -104.47876) (xy 427.515274 -104.549956) (xy 427.51477 -104.621152) (xy 427.506715 -104.763316)
			(xy 427.490629 -104.904797) (xy 427.466564 -105.045141) (xy 427.434598 -105.183899) (xy 427.394834 -105.320626)
			(xy 427.347397 -105.454885) (xy 427.292441 -105.586244) (xy 427.230141 -105.714285) (xy 427.160697 -105.838595)
			(xy 427.084331 -105.958778) (xy 427.001289 -106.074447) (xy 426.911835 -106.185233) (xy 426.816257 -106.290781)
			(xy 426.71486 -106.390753) (xy 426.60797 -106.484828) (xy 426.495929 -106.572705) (xy 426.379096 -106.654103)
			(xy 426.257845 -106.72876) (xy 426.132564 -106.796438) (xy 426.003655 -106.85692) (xy 425.871531 -106.910011)
			(xy 425.736615 -106.955543) (xy 425.599339 -106.993369) (xy 425.460142 -107.023369) (xy 425.319472 -107.045445)
			(xy 425.177778 -107.059527) (xy 425.035514 -107.06557) (xy 424.893136 -107.063555) (xy 424.7511 -107.053488)
			(xy 424.609861 -107.035402) (xy 424.469871 -107.009354) (xy 424.33158 -106.975428) (xy 424.195429 -106.933732)
			(xy 424.061855 -106.8844) (xy 423.931286 -106.827591) (xy 423.80414 -106.763485) (xy 423.680825 -106.692289)
			(xy 423.561735 -106.614231) (xy 423.447252 -106.529559) (xy 423.337743 -106.438547) (xy 423.233558 -106.341485)
			(xy 423.135031 -106.238684) (xy 423.042478 -106.130473) (xy 422.956196 -106.0172) (xy 422.876459 -105.899227)
			(xy 422.803525 -105.776931) (xy 422.737627 -105.650705) (xy 422.678976 -105.520953) (xy 422.627759 -105.388091)
			(xy 422.584141 -105.252544) (xy 422.548261 -105.114746) (xy 422.520234 -104.975139) (xy 422.500151 -104.834171)
			(xy 422.488076 -104.692291) (xy 422.484046 -104.549956) (xy 419.101016 -104.549956) (xy 419.101016 -156.545788)
			(xy 419.101437 -156.555859) (xy 419.10915 -156.574465) (xy 419.116002 -156.581856) (xy 419.803072 -157.268926)
			(xy 419.810471 -157.275769) (xy 419.82907 -157.283489) (xy 419.83914 -157.283912)
		)
		(stroke
			(width 0)
			(type solid)
		)
		(fill yes)
		(layer "In4.Cu")
		(net "GND")
	)
	(gr_poly
		(pts
			(xy 116.451888 -101.984048) (xy 116.461958 -101.983626) (xy 116.480561 -101.975908) (xy 116.487956 -101.969062)
			(xy 116.507568 -101.949938) (xy 116.551293 -101.916943) (xy 116.599291 -101.890547) (xy 116.650573 -101.871294)
			(xy 116.704084 -101.859582) (xy 116.75872 -101.85565) (xy 116.813356 -101.859582) (xy 116.866867 -101.871294)
			(xy 116.918149 -101.890547) (xy 116.966147 -101.916943) (xy 117.009872 -101.949938) (xy 117.029484 -101.969062)
			(xy 117.036885 -101.975899) (xy 117.055484 -101.983609) (xy 117.065552 -101.984048) (xy 121.531888 -101.984048)
			(xy 121.541958 -101.983626) (xy 121.560561 -101.975908) (xy 121.567956 -101.969062) (xy 121.587568 -101.949938)
			(xy 121.631293 -101.916943) (xy 121.679291 -101.890547) (xy 121.730573 -101.871294) (xy 121.784084 -101.859582)
			(xy 121.83872 -101.85565) (xy 121.893356 -101.859582) (xy 121.946867 -101.871294) (xy 121.998149 -101.890547)
			(xy 122.046147 -101.916943) (xy 122.089872 -101.949938) (xy 122.109484 -101.969062) (xy 122.116885 -101.975899)
			(xy 122.135484 -101.983609) (xy 122.145552 -101.984048) (xy 126.611888 -101.984048) (xy 126.621958 -101.983626)
			(xy 126.640561 -101.975908) (xy 126.647956 -101.969062) (xy 126.667568 -101.949938) (xy 126.711293 -101.916943)
			(xy 126.759291 -101.890547) (xy 126.810573 -101.871294) (xy 126.864084 -101.859582) (xy 126.91872 -101.85565)
			(xy 126.973356 -101.859582) (xy 127.026867 -101.871294) (xy 127.078149 -101.890547) (xy 127.126147 -101.916943)
			(xy 127.169872 -101.949938) (xy 127.189484 -101.969062) (xy 127.196885 -101.975899) (xy 127.215484 -101.983609)
			(xy 127.225552 -101.984048) (xy 131.691888 -101.984048) (xy 131.701958 -101.983626) (xy 131.720561 -101.975908)
			(xy 131.727956 -101.969062) (xy 131.747568 -101.949938) (xy 131.791293 -101.916943) (xy 131.839291 -101.890547)
			(xy 131.890573 -101.871294) (xy 131.944084 -101.859582) (xy 131.99872 -101.85565) (xy 132.053356 -101.859582)
			(xy 132.106867 -101.871294) (xy 132.158149 -101.890547) (xy 132.206147 -101.916943) (xy 132.249872 -101.949938)
			(xy 132.269484 -101.969062) (xy 132.276885 -101.975899) (xy 132.295484 -101.983609) (xy 132.305552 -101.984048)
			(xy 136.771888 -101.984048) (xy 136.781958 -101.983626) (xy 136.800561 -101.975908) (xy 136.807956 -101.969062)
			(xy 136.827568 -101.949938) (xy 136.871293 -101.916943) (xy 136.919291 -101.890547) (xy 136.970573 -101.871294)
			(xy 137.024084 -101.859582) (xy 137.07872 -101.85565) (xy 137.133356 -101.859582) (xy 137.186867 -101.871294)
			(xy 137.238149 -101.890547) (xy 137.286147 -101.916943) (xy 137.329872 -101.949938) (xy 137.349484 -101.969062)
			(xy 137.356885 -101.975899) (xy 137.375484 -101.983609) (xy 137.385552 -101.984048) (xy 141.851888 -101.984048)
			(xy 141.861958 -101.983626) (xy 141.880561 -101.975908) (xy 141.887956 -101.969062) (xy 141.907568 -101.949938)
			(xy 141.951293 -101.916943) (xy 141.999291 -101.890547) (xy 142.050573 -101.871294) (xy 142.104084 -101.859582)
			(xy 142.15872 -101.85565) (xy 142.213356 -101.859582) (xy 142.266867 -101.871294) (xy 142.318149 -101.890547)
			(xy 142.366147 -101.916943) (xy 142.409872 -101.949938) (xy 142.429484 -101.969062) (xy 142.436885 -101.975899)
			(xy 142.455484 -101.983609) (xy 142.465552 -101.984048) (xy 146.931888 -101.984048) (xy 146.941958 -101.983626)
			(xy 146.960561 -101.975908) (xy 146.967956 -101.969062) (xy 146.987568 -101.949938) (xy 147.031293 -101.916943)
			(xy 147.079291 -101.890547) (xy 147.130573 -101.871294) (xy 147.184084 -101.859582) (xy 147.23872 -101.85565)
			(xy 147.293356 -101.859582) (xy 147.346867 -101.871294) (xy 147.398149 -101.890547) (xy 147.446147 -101.916943)
			(xy 147.489872 -101.949938) (xy 147.509484 -101.969062) (xy 147.516885 -101.975899) (xy 147.535484 -101.983609)
			(xy 147.545552 -101.984048) (xy 152.011888 -101.984048) (xy 152.021958 -101.983626) (xy 152.040561 -101.975908)
			(xy 152.047956 -101.969062) (xy 152.067568 -101.949938) (xy 152.111293 -101.916943) (xy 152.159291 -101.890547)
			(xy 152.210573 -101.871294) (xy 152.264084 -101.859582) (xy 152.31872 -101.85565) (xy 152.373356 -101.859582)
			(xy 152.426867 -101.871294) (xy 152.478149 -101.890547) (xy 152.526147 -101.916943) (xy 152.569872 -101.949938)
			(xy 152.589484 -101.969062) (xy 152.596885 -101.975899) (xy 152.615484 -101.983609) (xy 152.625552 -101.984048)
			(xy 157.091888 -101.984048) (xy 157.101958 -101.983626) (xy 157.120561 -101.975908) (xy 157.127956 -101.969062)
			(xy 157.147568 -101.949938) (xy 157.191293 -101.916943) (xy 157.239291 -101.890547) (xy 157.290573 -101.871294)
			(xy 157.344084 -101.859582) (xy 157.39872 -101.85565) (xy 157.453356 -101.859582) (xy 157.506867 -101.871294)
			(xy 157.558149 -101.890547) (xy 157.606147 -101.916943) (xy 157.649872 -101.949938) (xy 157.669484 -101.969062)
			(xy 157.676885 -101.975899) (xy 157.695484 -101.983609) (xy 157.705552 -101.984048) (xy 162.171888 -101.984048)
			(xy 162.181958 -101.983626) (xy 162.200561 -101.975908) (xy 162.207956 -101.969062) (xy 162.227568 -101.949938)
			(xy 162.271293 -101.916943) (xy 162.319291 -101.890547) (xy 162.370573 -101.871294) (xy 162.424084 -101.859582)
			(xy 162.47872 -101.85565) (xy 162.533356 -101.859582) (xy 162.586867 -101.871294) (xy 162.638149 -101.890547)
			(xy 162.686147 -101.916943) (xy 162.729872 -101.949938) (xy 162.749484 -101.969062) (xy 162.756885 -101.975899)
			(xy 162.775484 -101.983609) (xy 162.785552 -101.984048) (xy 167.251888 -101.984048) (xy 167.261958 -101.983626)
			(xy 167.280561 -101.975908) (xy 167.287956 -101.969062) (xy 167.307568 -101.949938) (xy 167.351293 -101.916943)
			(xy 167.399291 -101.890547) (xy 167.450573 -101.871294) (xy 167.504084 -101.859582) (xy 167.55872 -101.85565)
			(xy 167.613356 -101.859582) (xy 167.666867 -101.871294) (xy 167.718149 -101.890547) (xy 167.766147 -101.916943)
			(xy 167.809872 -101.949938) (xy 167.829484 -101.969062) (xy 167.836885 -101.975899) (xy 167.855484 -101.983609)
			(xy 167.865552 -101.984048) (xy 172.331888 -101.984048) (xy 172.341958 -101.983626) (xy 172.360561 -101.975908)
			(xy 172.367956 -101.969062) (xy 172.387568 -101.949938) (xy 172.431293 -101.916943) (xy 172.479291 -101.890547)
			(xy 172.530573 -101.871294) (xy 172.584084 -101.859582) (xy 172.63872 -101.85565) (xy 172.693356 -101.859582)
			(xy 172.746867 -101.871294) (xy 172.798149 -101.890547) (xy 172.846147 -101.916943) (xy 172.889872 -101.949938)
			(xy 172.909484 -101.969062) (xy 172.916885 -101.975899) (xy 172.935484 -101.983609) (xy 172.945552 -101.984048)
			(xy 177.411888 -101.984048) (xy 177.421958 -101.983626) (xy 177.440561 -101.975908) (xy 177.447956 -101.969062)
			(xy 177.467568 -101.949938) (xy 177.511293 -101.916943) (xy 177.559291 -101.890547) (xy 177.610573 -101.871294)
			(xy 177.664084 -101.859582) (xy 177.71872 -101.85565) (xy 177.773356 -101.859582) (xy 177.826867 -101.871294)
			(xy 177.878149 -101.890547) (xy 177.926147 -101.916943) (xy 177.969872 -101.949938) (xy 177.989484 -101.969062)
			(xy 177.996885 -101.975899) (xy 178.015484 -101.983609) (xy 178.025552 -101.984048) (xy 182.491888 -101.984048)
			(xy 182.501958 -101.983626) (xy 182.520561 -101.975908) (xy 182.527956 -101.969062) (xy 182.547568 -101.949938)
			(xy 182.591293 -101.916943) (xy 182.639291 -101.890547) (xy 182.690573 -101.871294) (xy 182.744084 -101.859582)
			(xy 182.79872 -101.85565) (xy 182.853356 -101.859582) (xy 182.906867 -101.871294) (xy 182.958149 -101.890547)
			(xy 183.006147 -101.916943) (xy 183.049872 -101.949938) (xy 183.069484 -101.969062) (xy 183.076885 -101.975899)
			(xy 183.095484 -101.983609) (xy 183.105552 -101.984048) (xy 187.571888 -101.984048) (xy 187.581958 -101.983626)
			(xy 187.600561 -101.975908) (xy 187.607956 -101.969062) (xy 187.627568 -101.949938) (xy 187.671293 -101.916943)
			(xy 187.719291 -101.890547) (xy 187.770573 -101.871294) (xy 187.824084 -101.859582) (xy 187.87872 -101.85565)
			(xy 187.933356 -101.859582) (xy 187.986867 -101.871294) (xy 188.038149 -101.890547) (xy 188.086147 -101.916943)
			(xy 188.129872 -101.949938) (xy 188.149484 -101.969062) (xy 188.156885 -101.975899) (xy 188.175484 -101.983609)
			(xy 188.185552 -101.984048) (xy 192.651888 -101.984048) (xy 192.661958 -101.983626) (xy 192.680561 -101.975908)
			(xy 192.687956 -101.969062) (xy 192.707568 -101.949938) (xy 192.751293 -101.916943) (xy 192.799291 -101.890547)
			(xy 192.850573 -101.871294) (xy 192.904084 -101.859582) (xy 192.95872 -101.85565) (xy 193.013356 -101.859582)
			(xy 193.066867 -101.871294) (xy 193.118149 -101.890547) (xy 193.166147 -101.916943) (xy 193.209872 -101.949938)
			(xy 193.229484 -101.969062) (xy 193.236885 -101.975899) (xy 193.255484 -101.983609) (xy 193.265552 -101.984048)
			(xy 197.731888 -101.984048) (xy 197.741958 -101.983626) (xy 197.760561 -101.975908) (xy 197.767956 -101.969062)
			(xy 197.787568 -101.949938) (xy 197.831293 -101.916943) (xy 197.879291 -101.890547) (xy 197.930573 -101.871294)
			(xy 197.984084 -101.859582) (xy 198.03872 -101.85565) (xy 198.093356 -101.859582) (xy 198.146867 -101.871294)
			(xy 198.198149 -101.890547) (xy 198.246147 -101.916943) (xy 198.289872 -101.949938) (xy 198.309484 -101.969062)
			(xy 198.316885 -101.975899) (xy 198.335484 -101.983609) (xy 198.345552 -101.984048) (xy 202.811888 -101.984048)
			(xy 202.821958 -101.983626) (xy 202.840561 -101.975908) (xy 202.847956 -101.969062) (xy 202.867568 -101.949938)
			(xy 202.911293 -101.916943) (xy 202.959291 -101.890547) (xy 203.010573 -101.871294) (xy 203.064084 -101.859582)
			(xy 203.11872 -101.85565) (xy 203.173356 -101.859582) (xy 203.226867 -101.871294) (xy 203.278149 -101.890547)
			(xy 203.326147 -101.916943) (xy 203.369872 -101.949938) (xy 203.389484 -101.969062) (xy 203.396885 -101.975899)
			(xy 203.415484 -101.983609) (xy 203.425552 -101.984048) (xy 207.891888 -101.984048) (xy 207.901958 -101.983626)
			(xy 207.920561 -101.975908) (xy 207.927956 -101.969062) (xy 207.947568 -101.949938) (xy 207.991293 -101.916943)
			(xy 208.039291 -101.890547) (xy 208.090573 -101.871294) (xy 208.144084 -101.859582) (xy 208.19872 -101.85565)
			(xy 208.253356 -101.859582) (xy 208.306867 -101.871294) (xy 208.358149 -101.890547) (xy 208.406147 -101.916943)
			(xy 208.449872 -101.949938) (xy 208.469484 -101.969062) (xy 208.476885 -101.975899) (xy 208.495484 -101.983609)
			(xy 208.505552 -101.984048) (xy 212.971888 -101.984048) (xy 212.981958 -101.983626) (xy 213.000561 -101.975908)
			(xy 213.007956 -101.969062) (xy 213.027568 -101.949938) (xy 213.071293 -101.916943) (xy 213.119291 -101.890547)
			(xy 213.170573 -101.871294) (xy 213.224084 -101.859582) (xy 213.27872 -101.85565) (xy 213.333356 -101.859582)
			(xy 213.386867 -101.871294) (xy 213.438149 -101.890547) (xy 213.486147 -101.916943) (xy 213.529872 -101.949938)
			(xy 213.549484 -101.969062) (xy 213.556885 -101.975899) (xy 213.575484 -101.983609) (xy 213.585552 -101.984048)
			(xy 218.051888 -101.984048) (xy 218.061958 -101.983626) (xy 218.080561 -101.975908) (xy 218.087956 -101.969062)
			(xy 218.107568 -101.949938) (xy 218.151293 -101.916943) (xy 218.199291 -101.890547) (xy 218.250573 -101.871294)
			(xy 218.304084 -101.859582) (xy 218.35872 -101.85565) (xy 218.413356 -101.859582) (xy 218.466867 -101.871294)
			(xy 218.518149 -101.890547) (xy 218.566147 -101.916943) (xy 218.609872 -101.949938) (xy 218.629484 -101.969062)
			(xy 218.636885 -101.975899) (xy 218.655484 -101.983609) (xy 218.665552 -101.984048) (xy 223.131888 -101.984048)
			(xy 223.141958 -101.983626) (xy 223.160561 -101.975908) (xy 223.167956 -101.969062) (xy 223.187568 -101.949938)
			(xy 223.231293 -101.916943) (xy 223.279291 -101.890547) (xy 223.330573 -101.871294) (xy 223.384084 -101.859582)
			(xy 223.43872 -101.85565) (xy 223.493356 -101.859582) (xy 223.546867 -101.871294) (xy 223.598149 -101.890547)
			(xy 223.646147 -101.916943) (xy 223.689872 -101.949938) (xy 223.709484 -101.969062) (xy 223.716885 -101.975899)
			(xy 223.735484 -101.983609) (xy 223.745552 -101.984048) (xy 228.211888 -101.984048) (xy 228.221958 -101.983626)
			(xy 228.240561 -101.975908) (xy 228.247956 -101.969062) (xy 228.267568 -101.949938) (xy 228.311293 -101.916943)
			(xy 228.359291 -101.890547) (xy 228.410573 -101.871294) (xy 228.464084 -101.859582) (xy 228.51872 -101.85565)
			(xy 228.573356 -101.859582) (xy 228.626867 -101.871294) (xy 228.678149 -101.890547) (xy 228.726147 -101.916943)
			(xy 228.769872 -101.949938) (xy 228.789484 -101.969062) (xy 228.796885 -101.975899) (xy 228.815484 -101.983609)
			(xy 228.825552 -101.984048) (xy 233.291888 -101.984048) (xy 233.301958 -101.983626) (xy 233.320561 -101.975908)
			(xy 233.327956 -101.969062) (xy 233.347568 -101.949938) (xy 233.391293 -101.916943) (xy 233.439291 -101.890547)
			(xy 233.490573 -101.871294) (xy 233.544084 -101.859582) (xy 233.59872 -101.85565) (xy 233.653356 -101.859582)
			(xy 233.706867 -101.871294) (xy 233.758149 -101.890547) (xy 233.806147 -101.916943) (xy 233.849872 -101.949938)
			(xy 233.869484 -101.969062) (xy 233.876885 -101.975899) (xy 233.895484 -101.983609) (xy 233.905552 -101.984048)
			(xy 238.371888 -101.984048) (xy 238.381958 -101.983626) (xy 238.400561 -101.975908) (xy 238.407956 -101.969062)
			(xy 238.427568 -101.949938) (xy 238.471293 -101.916943) (xy 238.519291 -101.890547) (xy 238.570573 -101.871294)
			(xy 238.624084 -101.859582) (xy 238.67872 -101.85565) (xy 238.733356 -101.859582) (xy 238.786867 -101.871294)
			(xy 238.838149 -101.890547) (xy 238.886147 -101.916943) (xy 238.929872 -101.949938) (xy 238.949484 -101.969062)
			(xy 238.956885 -101.975899) (xy 238.975484 -101.983609) (xy 238.985552 -101.984048) (xy 243.451888 -101.984048)
			(xy 243.461958 -101.983626) (xy 243.480561 -101.975908) (xy 243.487956 -101.969062) (xy 243.507568 -101.949938)
			(xy 243.551293 -101.916943) (xy 243.599291 -101.890547) (xy 243.650573 -101.871294) (xy 243.704084 -101.859582)
			(xy 243.75872 -101.85565) (xy 243.813356 -101.859582) (xy 243.866867 -101.871294) (xy 243.918149 -101.890547)
			(xy 243.966147 -101.916943) (xy 244.009872 -101.949938) (xy 244.029484 -101.969062) (xy 244.036885 -101.975899)
			(xy 244.055484 -101.983609) (xy 244.065552 -101.984048) (xy 248.531888 -101.984048) (xy 248.541958 -101.983626)
			(xy 248.560561 -101.975908) (xy 248.567956 -101.969062) (xy 248.587568 -101.949938) (xy 248.631293 -101.916943)
			(xy 248.679291 -101.890547) (xy 248.730573 -101.871294) (xy 248.784084 -101.859582) (xy 248.83872 -101.85565)
			(xy 248.893356 -101.859582) (xy 248.946867 -101.871294) (xy 248.998149 -101.890547) (xy 249.046147 -101.916943)
			(xy 249.089872 -101.949938) (xy 249.109484 -101.969062) (xy 249.116885 -101.975899) (xy 249.135484 -101.983609)
			(xy 249.145552 -101.984048) (xy 253.611888 -101.984048) (xy 253.621958 -101.983626) (xy 253.640561 -101.975908)
			(xy 253.647956 -101.969062) (xy 253.667568 -101.949938) (xy 253.711293 -101.916943) (xy 253.759291 -101.890547)
			(xy 253.810573 -101.871294) (xy 253.864084 -101.859582) (xy 253.91872 -101.85565) (xy 253.973356 -101.859582)
			(xy 254.026867 -101.871294) (xy 254.078149 -101.890547) (xy 254.126147 -101.916943) (xy 254.169872 -101.949938)
			(xy 254.189484 -101.969062) (xy 254.196885 -101.975899) (xy 254.215484 -101.983609) (xy 254.225552 -101.984048)
			(xy 258.691888 -101.984048) (xy 258.701958 -101.983626) (xy 258.720561 -101.975908) (xy 258.727956 -101.969062)
			(xy 258.747568 -101.949938) (xy 258.791293 -101.916943) (xy 258.839291 -101.890547) (xy 258.890573 -101.871294)
			(xy 258.944084 -101.859582) (xy 258.99872 -101.85565) (xy 259.053356 -101.859582) (xy 259.106867 -101.871294)
			(xy 259.158149 -101.890547) (xy 259.206147 -101.916943) (xy 259.249872 -101.949938) (xy 259.269484 -101.969062)
			(xy 259.276885 -101.975899) (xy 259.295484 -101.983609) (xy 259.305552 -101.984048) (xy 263.771888 -101.984048)
			(xy 263.781958 -101.983626) (xy 263.800561 -101.975908) (xy 263.807956 -101.969062) (xy 263.827568 -101.949938)
			(xy 263.871293 -101.916943) (xy 263.919291 -101.890547) (xy 263.970573 -101.871294) (xy 264.024084 -101.859582)
			(xy 264.07872 -101.85565) (xy 264.133356 -101.859582) (xy 264.186867 -101.871294) (xy 264.238149 -101.890547)
			(xy 264.286147 -101.916943) (xy 264.329872 -101.949938) (xy 264.349484 -101.969062) (xy 264.356885 -101.975899)
			(xy 264.375484 -101.983609) (xy 264.385552 -101.984048) (xy 268.851888 -101.984048) (xy 268.861958 -101.983626)
			(xy 268.880561 -101.975908) (xy 268.887956 -101.969062) (xy 268.907568 -101.949938) (xy 268.951293 -101.916943)
			(xy 268.999291 -101.890547) (xy 269.050573 -101.871294) (xy 269.104084 -101.859582) (xy 269.15872 -101.85565)
			(xy 269.213356 -101.859582) (xy 269.266867 -101.871294) (xy 269.318149 -101.890547) (xy 269.366147 -101.916943)
			(xy 269.409872 -101.949938) (xy 269.429484 -101.969062) (xy 269.436885 -101.975899) (xy 269.455484 -101.983609)
			(xy 269.465552 -101.984048) (xy 273.931888 -101.984048) (xy 273.941958 -101.983626) (xy 273.960561 -101.975908)
			(xy 273.967956 -101.969062) (xy 273.987568 -101.949938) (xy 274.031293 -101.916943) (xy 274.079291 -101.890547)
			(xy 274.130573 -101.871294) (xy 274.184084 -101.859582) (xy 274.23872 -101.85565) (xy 274.293356 -101.859582)
			(xy 274.346867 -101.871294) (xy 274.398149 -101.890547) (xy 274.446147 -101.916943) (xy 274.489872 -101.949938)
			(xy 274.509484 -101.969062) (xy 274.516885 -101.975899) (xy 274.535484 -101.983609) (xy 274.545552 -101.984048)
			(xy 279.011888 -101.984048) (xy 279.021958 -101.983626) (xy 279.040561 -101.975908) (xy 279.047956 -101.969062)
			(xy 279.067568 -101.949938) (xy 279.111293 -101.916943) (xy 279.159291 -101.890547) (xy 279.210573 -101.871294)
			(xy 279.264084 -101.859582) (xy 279.31872 -101.85565) (xy 279.373356 -101.859582) (xy 279.426867 -101.871294)
			(xy 279.478149 -101.890547) (xy 279.526147 -101.916943) (xy 279.569872 -101.949938) (xy 279.589484 -101.969062)
			(xy 279.596885 -101.975899) (xy 279.615484 -101.983609) (xy 279.625552 -101.984048) (xy 284.091888 -101.984048)
			(xy 284.101958 -101.983626) (xy 284.120561 -101.975908) (xy 284.127956 -101.969062) (xy 284.147568 -101.949938)
			(xy 284.191293 -101.916943) (xy 284.239291 -101.890547) (xy 284.290573 -101.871294) (xy 284.344084 -101.859582)
			(xy 284.39872 -101.85565) (xy 284.453356 -101.859582) (xy 284.506867 -101.871294) (xy 284.558149 -101.890547)
			(xy 284.606147 -101.916943) (xy 284.649872 -101.949938) (xy 284.669484 -101.969062) (xy 284.676885 -101.975899)
			(xy 284.695484 -101.983609) (xy 284.705552 -101.984048) (xy 289.171888 -101.984048) (xy 289.181958 -101.983626)
			(xy 289.200561 -101.975908) (xy 289.207956 -101.969062) (xy 289.227568 -101.949938) (xy 289.271293 -101.916943)
			(xy 289.319291 -101.890547) (xy 289.370573 -101.871294) (xy 289.424084 -101.859582) (xy 289.47872 -101.85565)
			(xy 289.533356 -101.859582) (xy 289.586867 -101.871294) (xy 289.638149 -101.890547) (xy 289.686147 -101.916943)
			(xy 289.729872 -101.949938) (xy 289.749484 -101.969062) (xy 289.756885 -101.975899) (xy 289.775484 -101.983609)
			(xy 289.785552 -101.984048) (xy 294.251888 -101.984048) (xy 294.261958 -101.983626) (xy 294.280561 -101.975908)
			(xy 294.287956 -101.969062) (xy 294.307568 -101.949938) (xy 294.351293 -101.916943) (xy 294.399291 -101.890547)
			(xy 294.450573 -101.871294) (xy 294.504084 -101.859582) (xy 294.55872 -101.85565) (xy 294.613356 -101.859582)
			(xy 294.666867 -101.871294) (xy 294.718149 -101.890547) (xy 294.766147 -101.916943) (xy 294.809872 -101.949938)
			(xy 294.829484 -101.969062) (xy 294.836885 -101.975899) (xy 294.855484 -101.983609) (xy 294.865552 -101.984048)
			(xy 299.331888 -101.984048) (xy 299.341958 -101.983626) (xy 299.360561 -101.975908) (xy 299.367956 -101.969062)
			(xy 299.387568 -101.949938) (xy 299.431293 -101.916943) (xy 299.479291 -101.890547) (xy 299.530573 -101.871294)
			(xy 299.584084 -101.859582) (xy 299.63872 -101.85565) (xy 299.693356 -101.859582) (xy 299.746867 -101.871294)
			(xy 299.798149 -101.890547) (xy 299.846147 -101.916943) (xy 299.889872 -101.949938) (xy 299.909484 -101.969062)
			(xy 299.916885 -101.975899) (xy 299.935484 -101.983609) (xy 299.945552 -101.984048) (xy 304.411888 -101.984048)
			(xy 304.421958 -101.983626) (xy 304.440561 -101.975908) (xy 304.447956 -101.969062) (xy 304.467568 -101.949938)
			(xy 304.511293 -101.916943) (xy 304.559291 -101.890547) (xy 304.610573 -101.871294) (xy 304.664084 -101.859582)
			(xy 304.71872 -101.85565) (xy 304.773356 -101.859582) (xy 304.826867 -101.871294) (xy 304.878149 -101.890547)
			(xy 304.926147 -101.916943) (xy 304.969872 -101.949938) (xy 304.989484 -101.969062) (xy 304.996885 -101.975899)
			(xy 305.015484 -101.983609) (xy 305.025552 -101.984048) (xy 309.491888 -101.984048) (xy 309.501958 -101.983626)
			(xy 309.520561 -101.975908) (xy 309.527956 -101.969062) (xy 309.547568 -101.949938) (xy 309.591293 -101.916943)
			(xy 309.639291 -101.890547) (xy 309.690573 -101.871294) (xy 309.744084 -101.859582) (xy 309.79872 -101.85565)
			(xy 309.853356 -101.859582) (xy 309.906867 -101.871294) (xy 309.958149 -101.890547) (xy 310.006147 -101.916943)
			(xy 310.049872 -101.949938) (xy 310.069484 -101.969062) (xy 310.076885 -101.975899) (xy 310.095484 -101.983609)
			(xy 310.105552 -101.984048) (xy 314.571888 -101.984048) (xy 314.581958 -101.983626) (xy 314.600561 -101.975908)
			(xy 314.607956 -101.969062) (xy 314.627568 -101.949938) (xy 314.671293 -101.916943) (xy 314.719291 -101.890547)
			(xy 314.770573 -101.871294) (xy 314.824084 -101.859582) (xy 314.87872 -101.85565) (xy 314.933356 -101.859582)
			(xy 314.986867 -101.871294) (xy 315.038149 -101.890547) (xy 315.086147 -101.916943) (xy 315.129872 -101.949938)
			(xy 315.149484 -101.969062) (xy 315.156885 -101.975899) (xy 315.175484 -101.983609) (xy 315.185552 -101.984048)
			(xy 319.651888 -101.984048) (xy 319.661958 -101.983626) (xy 319.680561 -101.975908) (xy 319.687956 -101.969062)
			(xy 319.707568 -101.949938) (xy 319.751293 -101.916943) (xy 319.799291 -101.890547) (xy 319.850573 -101.871294)
			(xy 319.904084 -101.859582) (xy 319.95872 -101.85565) (xy 320.013356 -101.859582) (xy 320.066867 -101.871294)
			(xy 320.118149 -101.890547) (xy 320.166147 -101.916943) (xy 320.209872 -101.949938) (xy 320.229484 -101.969062)
			(xy 320.236885 -101.975899) (xy 320.255484 -101.983609) (xy 320.265552 -101.984048) (xy 324.731888 -101.984048)
			(xy 324.741958 -101.983626) (xy 324.760561 -101.975908) (xy 324.767956 -101.969062) (xy 324.787568 -101.949938)
			(xy 324.831293 -101.916943) (xy 324.879291 -101.890547) (xy 324.930573 -101.871294) (xy 324.984084 -101.859582)
			(xy 325.03872 -101.85565) (xy 325.093356 -101.859582) (xy 325.146867 -101.871294) (xy 325.198149 -101.890547)
			(xy 325.246147 -101.916943) (xy 325.289872 -101.949938) (xy 325.309484 -101.969062) (xy 325.316885 -101.975899)
			(xy 325.335484 -101.983609) (xy 325.345552 -101.984048) (xy 328.422 -101.984048) (xy 328.432011 -101.983561)
			(xy 328.450511 -101.975903) (xy 328.464676 -101.961752) (xy 328.472351 -101.943259) (xy 328.4728 -101.933248)
			(xy 328.4728 -89.202006) (xy 328.472382 -89.191984) (xy 328.464713 -89.173465) (xy 328.45054 -89.159291)
			(xy 328.432022 -89.15162) (xy 328.422 -89.151206) (xy 299.912532 -89.151206) (xy 299.907434 -89.151315)
			(xy 299.897445 -89.153356) (xy 299.89272 -89.15527) (xy 299.866304 -89.166446) (xy 299.859446 -89.17305)
			(xy 299.839927 -89.19146) (xy 299.796654 -89.223182) (xy 299.749364 -89.248529) (xy 299.698989 -89.266999)
			(xy 299.646522 -89.278229) (xy 299.593 -89.281997) (xy 299.539478 -89.278229) (xy 299.487011 -89.266999)
			(xy 299.436636 -89.248529) (xy 299.389346 -89.223182) (xy 299.346073 -89.19146) (xy 299.326554 -89.17305)
			(xy 299.319696 -89.166446) (xy 299.29328 -89.15527) (xy 299.28854 -89.153403) (xy 299.27856 -89.151362)
			(xy 299.273468 -89.151206) (xy 299.023532 -89.151206) (xy 299.018434 -89.151315) (xy 299.008445 -89.153356)
			(xy 299.00372 -89.15527) (xy 298.977304 -89.166446) (xy 298.970446 -89.17305) (xy 298.950927 -89.19146)
			(xy 298.907654 -89.223182) (xy 298.860364 -89.248529) (xy 298.809989 -89.266999) (xy 298.757522 -89.278229)
			(xy 298.704 -89.281997) (xy 298.650478 -89.278229) (xy 298.598011 -89.266999) (xy 298.547636 -89.248529)
			(xy 298.500346 -89.223182) (xy 298.457073 -89.19146) (xy 298.437554 -89.17305) (xy 298.430696 -89.166446)
			(xy 298.40428 -89.15527) (xy 298.39954 -89.153403) (xy 298.38956 -89.151362) (xy 298.384468 -89.151206)
			(xy 297.903392 -89.151206) (xy 297.898918 -89.151278) (xy 297.890102 -89.152812) (xy 297.885866 -89.154254)
			(xy 297.86961 -89.16035) (xy 297.865644 -89.161905) (xy 297.858241 -89.166117) (xy 297.854878 -89.168732)
			(xy 297.834296 -89.185172) (xy 297.789462 -89.212825) (xy 297.741246 -89.234038) (xy 297.690567 -89.248407)
			(xy 297.638392 -89.255658) (xy 297.612054 -89.256108) (xy 297.611546 -89.256108) (xy 297.585211 -89.255643)
			(xy 297.533046 -89.24836) (xy 297.482375 -89.233981) (xy 297.434159 -89.21278) (xy 297.389313 -89.185157)
			(xy 297.368722 -89.168732) (xy 297.365375 -89.166094) (xy 297.357967 -89.161881) (xy 297.35399 -89.16035)
			(xy 297.337734 -89.154254) (xy 297.333493 -89.15283) (xy 297.324681 -89.1513) (xy 297.320208 -89.151206)
			(xy 296.938192 -89.151206) (xy 296.924984 -89.152984) (xy 296.907966 -89.157556) (xy 296.902632 -89.16035)
			(xy 296.902378 -89.16035) (xy 296.87859 -89.172534) (xy 296.828386 -89.190866) (xy 296.776115 -89.202011)
			(xy 296.7228 -89.20575) (xy 296.669485 -89.202011) (xy 296.617214 -89.190866) (xy 296.56701 -89.172534)
			(xy 296.543222 -89.16035) (xy 296.542968 -89.16035) (xy 296.537634 -89.157556) (xy 296.520616 -89.152984)
			(xy 296.507408 -89.151206) (xy 263.66343 -89.151206) (xy 263.630169 -89.150687) (xy 263.564217 -89.142003)
			(xy 263.499964 -89.124781) (xy 263.43851 -89.099314) (xy 263.380908 -89.066041) (xy 263.328145 -89.025529)
			(xy 263.304274 -89.002362) (xy 260.154674 -85.852762) (xy 260.131516 -85.828883) (xy 260.091007 -85.77612)
			(xy 260.057734 -85.71852) (xy 260.032268 -85.657067) (xy 260.015044 -85.592816) (xy 260.006357 -85.526866)
			(xy 260.00583 -85.493606) (xy 260.00583 -58.30951) (xy 260.006351 -58.276249) (xy 260.015036 -58.210297)
			(xy 260.032258 -58.146044) (xy 260.057724 -58.08459) (xy 260.090996 -58.026988) (xy 260.131505 -57.974223)
			(xy 260.154674 -57.950354) (xy 261.418324 -56.686704) (xy 261.442202 -56.663544) (xy 261.494964 -56.623031)
			(xy 261.552564 -56.589755) (xy 261.614016 -56.564285) (xy 261.678268 -56.547058) (xy 261.744219 -56.538369)
			(xy 261.77748 -56.53786) (xy 272.766536 -56.53786) (xy 272.799795 -56.538384) (xy 272.865744 -56.547074)
			(xy 272.929993 -56.564303) (xy 272.991442 -56.589773) (xy 273.049039 -56.62305) (xy 273.101797 -56.663562)
			(xy 273.125692 -56.686704) (xy 273.78152 -57.342532) (xy 273.804678 -57.366411) (xy 273.845189 -57.419173)
			(xy 273.878462 -57.476774) (xy 273.90393 -57.538226) (xy 273.921155 -57.602477) (xy 273.929843 -57.668428)
			(xy 273.930364 -57.701688) (xy 273.930364 -62.804294) (xy 273.929843 -62.837555) (xy 273.921157 -62.903506)
			(xy 273.903934 -62.967759) (xy 273.878468 -63.029212) (xy 273.845196 -63.086814) (xy 273.804686 -63.139578)
			(xy 273.78152 -63.16345) (xy 269.59941 -67.34556) (xy 269.592149 -67.353594) (xy 269.584535 -67.373847)
			(xy 269.584678 -67.384676) (xy 269.589504 -67.460622) (xy 269.589758 -67.462908) (xy 269.590365 -67.467686)
			(xy 269.593179 -67.476895) (xy 269.595346 -67.481196) (xy 269.600426 -67.490594) (xy 269.609062 -67.497452)
			(xy 269.609316 -67.497706) (xy 269.640886 -67.522919) (xy 269.699818 -67.578199) (xy 269.753494 -67.638595)
			(xy 269.801472 -67.703609) (xy 269.843357 -67.772707) (xy 269.878803 -67.845317) (xy 269.907519 -67.920843)
			(xy 269.929268 -67.998662) (xy 269.943871 -68.078133) (xy 269.951207 -68.1586) (xy 269.951708 -68.199)
			(xy 269.951227 -68.24054) (xy 269.94348 -68.323257) (xy 269.928052 -68.404892) (xy 269.905078 -68.484732)
			(xy 269.874759 -68.562082) (xy 269.837358 -68.636267) (xy 269.793203 -68.706641) (xy 269.742676 -68.77259)
			(xy 269.68622 -68.83354) (xy 269.624326 -68.88896) (xy 269.557533 -68.938366) (xy 269.486424 -68.981327)
			(xy 269.411619 -69.017471) (xy 269.372842 -69.032374) (xy 269.363369 -69.03644) (xy 269.348469 -69.050659)
			(xy 269.340323 -69.069576) (xy 269.339822 -69.079872) (xy 269.339822 -70.137528) (xy 269.340292 -70.147837)
			(xy 269.348405 -70.166789) (xy 269.363341 -70.180999) (xy 269.372842 -70.185026) (xy 269.411594 -70.199983)
			(xy 269.486388 -70.23613) (xy 269.557485 -70.279093) (xy 269.624266 -70.328499) (xy 269.68615 -70.383917)
			(xy 269.742596 -70.444864) (xy 269.793113 -70.51081) (xy 269.83726 -70.581178) (xy 269.874654 -70.655356)
			(xy 269.904967 -70.732698) (xy 269.927936 -70.81253) (xy 269.943361 -70.894156) (xy 269.951107 -70.976865)
			(xy 269.951107 -71.059935) (xy 269.943361 -71.142644) (xy 269.927936 -71.22427) (xy 269.904967 -71.304102)
			(xy 269.874654 -71.381444) (xy 269.83726 -71.455622) (xy 269.793113 -71.52599) (xy 269.742596 -71.591936)
			(xy 269.68615 -71.652883) (xy 269.624266 -71.708301) (xy 269.557485 -71.757707) (xy 269.486388 -71.80067)
			(xy 269.411594 -71.836817) (xy 269.372842 -71.851774) (xy 269.363369 -71.85584) (xy 269.348469 -71.870059)
			(xy 269.340323 -71.888976) (xy 269.339822 -71.899272) (xy 269.339822 -72.122284) (xy 269.340129 -72.130478)
			(xy 269.345309 -72.146026) (xy 269.349982 -72.152764) (xy 269.354808 -72.158352) (xy 270.786606 -73.59015)
			(xy 270.792194 -73.594976) (xy 270.798934 -73.599646) (xy 270.81448 -73.604832) (xy 270.822674 -73.605136)
			(xy 271.63903 -73.605136) (xy 271.646758 -73.604862) (xy 271.661493 -73.600194) (xy 271.667986 -73.595992)
			(xy 271.670272 -73.594468) (xy 271.671288 -73.593706) (xy 271.693649 -73.577027) (xy 271.742281 -73.549696)
			(xy 271.794377 -73.529746) (xy 271.848824 -73.517603) (xy 271.90446 -73.513527) (xy 271.960096 -73.517603)
			(xy 272.014543 -73.529746) (xy 272.066639 -73.549696) (xy 272.115271 -73.577027) (xy 272.137632 -73.593706)
			(xy 272.138648 -73.594468) (xy 272.140934 -73.595992) (xy 272.147449 -73.600141) (xy 272.162173 -73.604778)
			(xy 272.16989 -73.605136) (xy 303.883314 -73.605136) (xy 303.884838 -73.605136) (xy 303.910746 -73.604628)
			(xy 303.911254 -73.604628) (xy 303.937162 -73.605136) (xy 305.153314 -73.605136) (xy 305.154838 -73.605136)
			(xy 305.180746 -73.604628) (xy 305.181254 -73.604628) (xy 305.207162 -73.605136) (xy 310.16321 -73.605136)
			(xy 310.173219 -73.604647) (xy 310.191714 -73.596987) (xy 310.205872 -73.582835) (xy 310.213542 -73.564345)
			(xy 310.21401 -73.554336) (xy 310.21401 -68.489068) (xy 310.213875 -68.484177) (xy 310.211961 -68.474583)
			(xy 310.2102 -68.470018) (xy 310.20639 -68.460366) (xy 310.199024 -68.453254) (xy 309.613046 -67.867276)
			(xy 309.607458 -67.86245) (xy 309.600716 -67.857785) (xy 309.58517 -67.852611) (xy 309.576978 -67.85229)
			(xy 308.29758 -67.85229) (xy 308.288421 -67.852723) (xy 308.27129 -67.859227) (xy 308.257508 -67.871303)
			(xy 308.252876 -67.879214) (xy 308.23281 -67.915996) (xy 308.186744 -67.985991) (xy 308.134301 -68.051344)
			(xy 308.075945 -68.111477) (xy 308.012194 -68.165856) (xy 307.943612 -68.214001) (xy 307.870808 -68.255483)
			(xy 307.794425 -68.289937) (xy 307.715142 -68.317056) (xy 307.633659 -68.3366) (xy 307.550701 -68.348396)
			(xy 307.467 -68.35234) (xy 307.383299 -68.348396) (xy 307.300341 -68.3366) (xy 307.218858 -68.317056)
			(xy 307.139575 -68.289937) (xy 307.063192 -68.255483) (xy 306.990388 -68.214001) (xy 306.921806 -68.165856)
			(xy 306.858055 -68.111477) (xy 306.799699 -68.051344) (xy 306.747256 -67.985991) (xy 306.70119 -67.915996)
			(xy 306.681124 -67.879214) (xy 306.676497 -67.871284) (xy 306.66275 -67.859134) (xy 306.645593 -67.852635)
			(xy 306.63642 -67.85229) (xy 305.487578 -67.85229) (xy 305.478972 -67.852618) (xy 305.462731 -67.858318)
			(xy 305.455828 -67.863466) (xy 305.449399 -67.868975) (xy 305.440311 -67.883248) (xy 305.438048 -67.891406)
			(xy 305.438048 -67.89166) (xy 305.429011 -67.92873) (xy 305.405433 -68.001303) (xy 305.375738 -68.071594)
			(xy 305.358292 -68.105528) (xy 305.355498 -68.110862) (xy 305.35245 -68.122292) (xy 305.351025 -68.128564)
			(xy 305.351023 -68.141421) (xy 305.35245 -68.147692) (xy 305.355498 -68.159122) (xy 305.358292 -68.164456)
			(xy 305.378041 -68.202935) (xy 305.410839 -68.28297) (xy 305.435723 -68.365808) (xy 305.452456 -68.450669)
			(xy 305.460882 -68.536753) (xy 305.461416 -68.58) (xy 305.461416 -68.580508) (xy 305.460899 -68.623585)
			(xy 305.452546 -68.709334) (xy 305.435939 -68.793872) (xy 305.411234 -68.876409) (xy 305.378662 -68.956169)
			(xy 305.359054 -68.994528) (xy 305.356006 -69.000116) (xy 305.353212 -69.011546) (xy 305.351688 -69.017896)
			(xy 305.351688 -69.030342) (xy 305.35626 -69.047868) (xy 305.359054 -69.053202) (xy 305.378763 -69.091665)
			(xy 305.411492 -69.171661) (xy 305.436319 -69.25445) (xy 305.453012 -69.339254) (xy 305.461412 -69.425276)
			(xy 305.461924 -69.468492) (xy 305.461924 -69.469) (xy 305.461368 -69.51276) (xy 305.45275 -69.599855)
			(xy 305.435638 -69.685685) (xy 305.410196 -69.769426) (xy 305.376668 -69.850269) (xy 305.356514 -69.889116)
			(xy 305.353466 -69.894704) (xy 305.350418 -69.906642) (xy 305.350418 -69.920358) (xy 305.353466 -69.932296)
			(xy 305.356514 -69.937884) (xy 305.376716 -69.976709) (xy 305.410264 -70.05755) (xy 305.435713 -70.141295)
			(xy 305.452817 -70.227134) (xy 305.461411 -70.314237) (xy 305.461924 -70.358) (xy 305.46142 -70.400397)
			(xy 305.45336 -70.484807) (xy 305.437312 -70.568068) (xy 305.413423 -70.649427) (xy 305.381908 -70.728147)
			(xy 305.343054 -70.803515) (xy 305.297211 -70.874848) (xy 305.244795 -70.9415) (xy 305.18628 -71.002868)
			(xy 305.122198 -71.058396) (xy 305.053127 -71.107581) (xy 304.979693 -71.149978) (xy 304.902562 -71.185203)
			(xy 304.822432 -71.212936) (xy 304.740028 -71.232927) (xy 304.656098 -71.244994) (xy 304.5714 -71.249029)
			(xy 304.486702 -71.244994) (xy 304.402772 -71.232927) (xy 304.320368 -71.212936) (xy 304.240238 -71.185203)
			(xy 304.163107 -71.149978) (xy 304.089673 -71.107581) (xy 304.020602 -71.058396) (xy 303.95652 -71.002868)
			(xy 303.898005 -70.9415) (xy 303.845589 -70.874848) (xy 303.799746 -70.803515) (xy 303.760892 -70.728147)
			(xy 303.729377 -70.649427) (xy 303.705488 -70.568068) (xy 303.68944 -70.484807) (xy 303.68138 -70.400397)
			(xy 303.680876 -70.358) (xy 303.681432 -70.31424) (xy 303.69005 -70.227145) (xy 303.707162 -70.141315)
			(xy 303.732604 -70.057574) (xy 303.766132 -69.976731) (xy 303.786286 -69.937884) (xy 303.789334 -69.932296)
			(xy 303.792382 -69.920358) (xy 303.792382 -69.906642) (xy 303.789334 -69.894704) (xy 303.786286 -69.889116)
			(xy 303.766084 -69.850291) (xy 303.732536 -69.76945) (xy 303.707087 -69.685705) (xy 303.689983 -69.599866)
			(xy 303.681389 -69.512763) (xy 303.680876 -69.469) (xy 303.680876 -69.468492) (xy 303.681397 -69.425276)
			(xy 303.68979 -69.339252) (xy 303.706475 -69.254446) (xy 303.731296 -69.171655) (xy 303.76402 -69.091657)
			(xy 303.783746 -69.053202) (xy 303.78654 -69.047868) (xy 303.791112 -69.030342) (xy 303.791112 -69.017896)
			(xy 303.789588 -69.011546) (xy 303.786794 -69.000116) (xy 303.783746 -68.994528) (xy 303.764141 -68.956169)
			(xy 303.731591 -68.876403) (xy 303.706898 -68.793865) (xy 303.690293 -68.709329) (xy 303.681932 -68.623584)
			(xy 303.681384 -68.580508) (xy 303.681384 -68.58) (xy 303.681908 -68.536752) (xy 303.690323 -68.450665)
			(xy 303.707053 -68.365802) (xy 303.73194 -68.282963) (xy 303.76475 -68.202931) (xy 303.784508 -68.164456)
			(xy 303.787302 -68.159122) (xy 303.79035 -68.147692) (xy 303.791773 -68.141421) (xy 303.791772 -68.128564)
			(xy 303.79035 -68.122292) (xy 303.787302 -68.110862) (xy 303.784508 -68.105528) (xy 303.767053 -68.071598)
			(xy 303.737344 -68.001311) (xy 303.713778 -67.928733) (xy 303.704752 -67.89166) (xy 303.704752 -67.891406)
			(xy 303.702437 -67.883269) (xy 303.693369 -67.869001) (xy 303.686972 -67.863466) (xy 303.680049 -67.858351)
			(xy 303.663823 -67.852636) (xy 303.655222 -67.85229) (xy 302.50638 -67.85229) (xy 302.497221 -67.852723)
			(xy 302.48009 -67.859227) (xy 302.466308 -67.871303) (xy 302.461676 -67.879214) (xy 302.44161 -67.915996)
			(xy 302.395544 -67.985991) (xy 302.343101 -68.051344) (xy 302.284745 -68.111477) (xy 302.220994 -68.165856)
			(xy 302.152412 -68.214001) (xy 302.079608 -68.255483) (xy 302.003225 -68.289937) (xy 301.923942 -68.317056)
			(xy 301.842459 -68.3366) (xy 301.759501 -68.348396) (xy 301.6758 -68.35234) (xy 301.592099 -68.348396)
			(xy 301.509141 -68.3366) (xy 301.427658 -68.317056) (xy 301.348375 -68.289937) (xy 301.271992 -68.255483)
			(xy 301.199188 -68.214001) (xy 301.130606 -68.165856) (xy 301.066855 -68.111477) (xy 301.008499 -68.051344)
			(xy 300.956056 -67.985991) (xy 300.90999 -67.915996) (xy 300.889924 -67.879214) (xy 300.885297 -67.871284)
			(xy 300.87155 -67.859134) (xy 300.854393 -67.852635) (xy 300.84522 -67.85229) (xy 298.591224 -67.85229)
			(xy 298.584866 -67.852458) (xy 298.572532 -67.855548) (xy 298.56684 -67.858386) (xy 298.561506 -67.861434)
			(xy 298.552362 -67.869816) (xy 298.548806 -67.875404) (xy 298.502324 -67.946524) (xy 298.496065 -67.957513)
			(xy 298.494065 -67.982692) (xy 298.498514 -67.99453) (xy 298.498514 -67.994784) (xy 298.516529 -68.037175)
			(xy 298.544722 -68.124868) (xy 298.563719 -68.215002) (xy 298.573317 -68.306614) (xy 298.573952 -68.35267)
			(xy 298.573952 -68.35394) (xy 298.573465 -68.396338) (xy 298.565402 -68.480749) (xy 298.549344 -68.564011)
			(xy 298.525437 -68.645366) (xy 298.493898 -68.724078) (xy 298.455012 -68.799432) (xy 298.409133 -68.870744)
			(xy 298.356676 -68.937366) (xy 298.298119 -68.998696) (xy 298.266358 -69.026786) (xy 298.26585 -69.027294)
			(xy 298.258044 -69.034827) (xy 298.249083 -69.05456) (xy 298.248578 -69.065394) (xy 298.248578 -69.14261)
			(xy 298.249106 -69.153534) (xy 298.258206 -69.173396) (xy 298.266104 -69.180964) (xy 298.297869 -69.209077)
			(xy 298.35647 -69.270418) (xy 298.408966 -69.337057) (xy 298.45488 -69.408391) (xy 298.493796 -69.483771)
			(xy 298.52536 -69.562513) (xy 298.549286 -69.643902) (xy 298.565357 -69.727199) (xy 298.573425 -69.811647)
			(xy 298.573952 -69.854064) (xy 298.573448 -69.896412) (xy 298.565397 -69.980726) (xy 298.549368 -70.063892)
			(xy 298.525507 -70.145159) (xy 298.494028 -70.223789) (xy 298.455217 -70.29907) (xy 298.409427 -70.370322)
			(xy 298.357071 -70.436898) (xy 298.298623 -70.498196) (xy 298.234613 -70.553661) (xy 298.165621 -70.60279)
			(xy 298.092271 -70.645139) (xy 298.015228 -70.680323) (xy 297.935189 -70.708025) (xy 297.85288 -70.727993)
			(xy 297.769045 -70.740046) (xy 297.684444 -70.744077) (xy 297.599843 -70.740046) (xy 297.516008 -70.727993)
			(xy 297.433699 -70.708025) (xy 297.35366 -70.680323) (xy 297.276617 -70.645139) (xy 297.203267 -70.60279)
			(xy 297.134275 -70.553661) (xy 297.070265 -70.498196) (xy 297.011817 -70.436898) (xy 296.959461 -70.370322)
			(xy 296.913671 -70.29907) (xy 296.87486 -70.223789) (xy 296.843381 -70.145159) (xy 296.81952 -70.063892)
			(xy 296.803491 -69.980726) (xy 296.79544 -69.896412) (xy 296.794936 -69.854064) (xy 296.795429 -69.811648)
			(xy 296.803506 -69.7272) (xy 296.819585 -69.643905) (xy 296.843519 -69.562518) (xy 296.87509 -69.483779)
			(xy 296.914013 -69.408402) (xy 296.959933 -69.337072) (xy 297.012434 -69.270436) (xy 297.071038 -69.2091)
			(xy 297.102784 -69.180964) (xy 297.110699 -69.173412) (xy 297.119792 -69.153537) (xy 297.12031 -69.14261)
			(xy 297.12031 -69.065394) (xy 297.119818 -69.054552) (xy 297.110875 -69.034801) (xy 297.103038 -69.027294)
			(xy 297.102784 -69.02704) (xy 297.071019 -68.998926) (xy 297.012419 -68.937586) (xy 296.959923 -68.870946)
			(xy 296.914009 -68.799613) (xy 296.875094 -68.724232) (xy 296.843529 -68.64549) (xy 296.819603 -68.564101)
			(xy 296.803533 -68.480805) (xy 296.795464 -68.396356) (xy 296.794936 -68.35394) (xy 296.795413 -68.312104)
			(xy 296.803264 -68.228802) (xy 296.818902 -68.146605) (xy 296.842186 -68.066239) (xy 296.872913 -67.988414)
			(xy 296.91081 -67.913818) (xy 296.955543 -67.843108) (xy 297.006717 -67.776911) (xy 297.063879 -67.71581)
			(xy 297.126525 -67.660345) (xy 297.194101 -67.611006) (xy 297.266011 -67.56823) (xy 297.34162 -67.532393)
			(xy 297.420258 -67.503813) (xy 297.501233 -67.482741) (xy 297.542458 -67.475608) (xy 297.542712 -67.475608)
			(xy 297.54962 -67.474265) (xy 297.56238 -67.468341) (xy 297.567858 -67.463924) (xy 297.572938 -67.459606)
			(xy 297.580558 -67.448176) (xy 297.61053 -67.354958) (xy 297.612979 -67.345949) (xy 297.611963 -67.327324)
			(xy 297.604391 -67.310277) (xy 297.598084 -67.303396) (xy 296.185844 -65.891156) (xy 296.162688 -65.867276)
			(xy 296.122182 -65.814512) (xy 296.088911 -65.756911) (xy 296.063447 -65.69546) (xy 296.046225 -65.631209)
			(xy 296.037539 -65.565259) (xy 296.037 -65.532) (xy 296.037 -62.18174) (xy 296.036863 -62.17685)
			(xy 296.034943 -62.167258) (xy 296.03319 -62.16269) (xy 296.02938 -62.153038) (xy 296.022014 -62.145926)
			(xy 293.200074 -59.323986) (xy 293.194486 -59.31916) (xy 293.187746 -59.314491) (xy 293.1722 -59.309307)
			(xy 293.164006 -59.309) (xy 282.2956 -59.309) (xy 282.26234 -59.308479) (xy 282.19639 -59.299791)
			(xy 282.132139 -59.282566) (xy 282.070688 -59.257097) (xy 282.013089 -59.223821) (xy 281.960329 -59.183308)
			(xy 281.936444 -59.160156) (xy 267.774674 -44.998386) (xy 267.769086 -44.99356) (xy 267.762346 -44.988891)
			(xy 267.7468 -44.983707) (xy 267.738606 -44.9834) (xy 258.5212 -44.9834) (xy 258.48794 -44.982879)
			(xy 258.42199 -44.974191) (xy 258.357739 -44.956966) (xy 258.296288 -44.931497) (xy 258.238689 -44.898221)
			(xy 258.185929 -44.857708) (xy 258.162044 -44.834556) (xy 255.700022 -42.372534) (xy 255.694434 -42.367708)
			(xy 255.687691 -42.363049) (xy 255.672145 -42.357887) (xy 255.663954 -42.357548) (xy 254.899668 -42.357548)
			(xy 254.889349 -42.358091) (xy 254.870415 -42.366319) (xy 254.856231 -42.381319) (xy 254.85217 -42.390822)
			(xy 254.82169 -42.47388) (xy 254.82039 -42.477628) (xy 254.818861 -42.485413) (xy 254.818642 -42.489374)
			(xy 254.81915 -42.499026) (xy 254.819779 -42.502704) (xy 254.82194 -42.509846) (xy 254.823468 -42.51325)
			(xy 254.834644 -42.536618) (xy 254.842518 -42.54373) (xy 254.867156 -42.566844) (xy 258.550156 -46.249844)
			(xy 258.573312 -46.273724) (xy 258.613818 -46.326488) (xy 258.647089 -46.384089) (xy 258.672553 -46.44554)
			(xy 258.689775 -46.509791) (xy 258.698461 -46.575741) (xy 258.699 -46.609) (xy 258.699 -47.032361)
			(xy 259.359142 -47.032361) (xy 259.359142 -46.947639) (xy 259.367195 -46.863302) (xy 259.383229 -46.780112)
			(xy 259.407097 -46.698822) (xy 259.438585 -46.62017) (xy 259.477407 -46.544867) (xy 259.52321 -46.473595)
			(xy 259.575581 -46.406999) (xy 259.634046 -46.345684) (xy 259.698074 -46.290203) (xy 259.767086 -46.24106)
			(xy 259.840456 -46.1987) (xy 259.917521 -46.163505) (xy 259.997583 -46.135796) (xy 260.079916 -46.115822)
			(xy 260.163775 -46.103765) (xy 260.2484 -46.099734) (xy 260.333025 -46.103765) (xy 260.416884 -46.115822)
			(xy 260.499217 -46.135796) (xy 260.579279 -46.163505) (xy 260.656344 -46.1987) (xy 260.729714 -46.24106)
			(xy 260.798726 -46.290203) (xy 260.862754 -46.345684) (xy 260.921219 -46.406999) (xy 260.97359 -46.473595)
			(xy 261.019393 -46.544867) (xy 261.058215 -46.62017) (xy 261.089703 -46.698822) (xy 261.113571 -46.780112)
			(xy 261.129605 -46.863302) (xy 261.137658 -46.947639) (xy 261.138162 -46.99) (xy 261.137658 -47.032361)
			(xy 261.129605 -47.116698) (xy 261.113571 -47.199888) (xy 261.089703 -47.281178) (xy 261.058215 -47.35983)
			(xy 261.019393 -47.435133) (xy 260.97359 -47.506405) (xy 260.921219 -47.573001) (xy 260.862754 -47.634316)
			(xy 260.798726 -47.689797) (xy 260.729714 -47.73894) (xy 260.656344 -47.7813) (xy 260.579279 -47.816495)
			(xy 260.499217 -47.844204) (xy 260.416884 -47.864178) (xy 260.333025 -47.876235) (xy 260.2484 -47.880267)
			(xy 260.163775 -47.876235) (xy 260.079916 -47.864178) (xy 259.997583 -47.844204) (xy 259.917521 -47.816495)
			(xy 259.840456 -47.7813) (xy 259.767086 -47.73894) (xy 259.698074 -47.689797) (xy 259.634046 -47.634316)
			(xy 259.575581 -47.573001) (xy 259.52321 -47.506405) (xy 259.477407 -47.435133) (xy 259.438585 -47.35983)
			(xy 259.407097 -47.281178) (xy 259.383229 -47.199888) (xy 259.367195 -47.116698) (xy 259.359142 -47.032361)
			(xy 258.699 -47.032361) (xy 258.699 -50.894996) (xy 258.698479 -50.928256) (xy 258.689792 -50.994207)
			(xy 258.672567 -51.058458) (xy 258.647098 -51.119909) (xy 258.613823 -51.177508) (xy 258.57331 -51.230269)
			(xy 258.550156 -51.254152) (xy 257.878072 -51.926236) (xy 257.854193 -51.949394) (xy 257.80143 -51.989903)
			(xy 257.74383 -52.023177) (xy 257.682378 -52.048644) (xy 257.618126 -52.065869) (xy 257.552176 -52.074557)
			(xy 257.518916 -52.07508) (xy 247.302782 -52.07508) (xy 247.269523 -52.074557) (xy 247.203574 -52.065868)
			(xy 247.139325 -52.04864) (xy 247.077876 -52.023169) (xy 247.02028 -51.989891) (xy 246.967523 -51.949375)
			(xy 246.943626 -51.926236) (xy 246.398796 -51.381406) (xy 246.375635 -51.357528) (xy 246.33512 -51.304767)
			(xy 246.30184 -51.247167) (xy 246.276368 -51.185715) (xy 246.259137 -51.121463) (xy 246.250444 -51.055511)
			(xy 246.249952 -51.02225) (xy 246.249952 -46.654466) (xy 246.250475 -46.621207) (xy 246.259166 -46.555258)
			(xy 246.276394 -46.491009) (xy 246.301864 -46.429559) (xy 246.33514 -46.371961) (xy 246.375652 -46.319202)
			(xy 246.398796 -46.29531) (xy 250.127262 -42.566844) (xy 250.1519 -42.54373) (xy 250.159774 -42.536618)
			(xy 250.17095 -42.51325) (xy 250.172495 -42.509852) (xy 250.174657 -42.502708) (xy 250.175268 -42.499026)
			(xy 250.175776 -42.489374) (xy 250.175539 -42.485415) (xy 250.174013 -42.477632) (xy 250.172728 -42.47388)
			(xy 250.142248 -42.390822) (xy 250.138248 -42.381274) (xy 250.124064 -42.366224) (xy 250.105089 -42.357999)
			(xy 250.09475 -42.357548) (xy 249.224546 -42.357548) (xy 249.219655 -42.357685) (xy 249.210062 -42.359601)
			(xy 249.205496 -42.361358) (xy 249.195844 -42.365168) (xy 249.188732 -42.372534) (xy 243.32311 -48.238156)
			(xy 243.299231 -48.261315) (xy 243.246469 -48.301827) (xy 243.188869 -48.335103) (xy 243.127417 -48.360574)
			(xy 243.063166 -48.377803) (xy 242.997215 -48.386496) (xy 242.963954 -48.387) (xy 230.251 -48.387)
			(xy 230.21774 -48.386479) (xy 230.15179 -48.377791) (xy 230.087539 -48.360566) (xy 230.026088 -48.335097)
			(xy 229.968489 -48.301821) (xy 229.915729 -48.261308) (xy 229.891844 -48.238156) (xy 229.002844 -47.349156)
			(xy 228.979688 -47.325276) (xy 228.939182 -47.272512) (xy 228.905911 -47.214911) (xy 228.880447 -47.15346)
			(xy 228.863225 -47.089209) (xy 228.854539 -47.023259) (xy 228.854 -46.99) (xy 228.854 -30.226) (xy 228.854521 -30.19274)
			(xy 228.863209 -30.12679) (xy 228.880434 -30.062539) (xy 228.905903 -30.001088) (xy 228.939179 -29.943489)
			(xy 228.979692 -29.890729) (xy 229.002844 -29.866844) (xy 230.780844 -28.088844) (xy 230.804724 -28.065688)
			(xy 230.857488 -28.025182) (xy 230.915089 -27.991911) (xy 230.97654 -27.966447) (xy 231.040791 -27.949225)
			(xy 231.106741 -27.940539) (xy 231.14 -27.94) (xy 278.156924 -27.94) (xy 278.165052 -27.939238) (xy 278.16556 -27.939238)
			(xy 278.173078 -27.937635) (xy 278.186764 -27.930657) (xy 278.192484 -27.925522) (xy 279.131014 -26.986992)
			(xy 279.13584 -26.981404) (xy 279.140512 -26.974665) (xy 279.145702 -26.959119) (xy 279.146 -26.950924)
			(xy 279.146 -16.146018) (xy 279.14652 -16.112758) (xy 279.155205 -16.046806) (xy 279.172429 -15.982554)
			(xy 279.197896 -15.921101) (xy 279.231171 -15.863501) (xy 279.271684 -15.810739) (xy 279.294844 -15.786862)
			(xy 282.994862 -12.086844) (xy 283.018742 -12.063689) (xy 283.071506 -12.023184) (xy 283.129108 -11.989916)
			(xy 283.190559 -11.964454) (xy 283.25481 -11.947234) (xy 283.320759 -11.938551) (xy 283.354018 -11.938)
			(xy 323.977 -11.938) (xy 323.997574 -11.938508) (xy 324.007873 -11.938505) (xy 324.027145 -11.9313)
			(xy 324.034912 -11.924538) (xy 324.088252 -11.873738) (xy 324.095366 -11.866312) (xy 324.103477 -11.847434)
			(xy 324.104 -11.837162) (xy 324.104 -10.336784) (xy 324.103867 -10.331893) (xy 324.101955 -10.322297)
			(xy 324.10019 -10.317734) (xy 324.09638 -10.308082) (xy 324.089014 -10.30097) (xy 322.94703 -9.158986)
			(xy 322.941442 -9.15416) (xy 322.9347 -9.149497) (xy 322.919154 -9.144326) (xy 322.910962 -9.144)
			(xy 258.794758 -9.144) (xy 258.786722 -9.144364) (xy 258.771458 -9.149412) (xy 258.764786 -9.153906)
			(xy 258.738426 -9.172834) (xy 258.681815 -9.204563) (xy 258.621624 -9.228823) (xy 258.558833 -9.245221)
			(xy 258.494466 -9.253488) (xy 258.462018 -9.253982) (xy 123.3932 -9.253982) (xy 123.383191 -9.25447)
			(xy 123.364696 -9.262129) (xy 123.350539 -9.276281) (xy 123.342873 -9.294773) (xy 123.3424 -9.304782)
			(xy 123.3424 -11.836908) (xy 123.342876 -11.847247) (xy 123.350987 -11.866268) (xy 123.358148 -11.873738)
			(xy 123.411488 -11.924792) (xy 123.415301 -11.928203) (xy 123.424 -11.933585) (xy 123.42876 -11.93546)
			(xy 123.438158 -11.939016) (xy 123.448826 -11.938508) (xy 123.4694 -11.938) (xy 156.980382 -11.938)
			(xy 157.013642 -11.93852) (xy 157.079594 -11.947205) (xy 157.143846 -11.964429) (xy 157.205299 -11.989896)
			(xy 157.262899 -12.023171) (xy 157.315661 -12.063684) (xy 157.339538 -12.086844) (xy 161.039556 -15.786862)
			(xy 161.062711 -15.810742) (xy 161.103216 -15.863506) (xy 161.136484 -15.921108) (xy 161.161946 -15.982559)
			(xy 161.179166 -16.04681) (xy 161.187849 -16.112759) (xy 161.1884 -16.146018) (xy 161.1884 -22.560114)
			(xy 205.177635 -22.560114) (xy 205.177635 -22.389758) (xy 205.18562 -22.21959) (xy 205.201572 -22.049983)
			(xy 205.225457 -21.881311) (xy 205.257221 -21.713943) (xy 205.296796 -21.548248) (xy 205.344093 -21.38459)
			(xy 205.39901 -21.223329) (xy 205.461425 -21.064819) (xy 205.531201 -20.909409) (xy 205.608184 -20.757441)
			(xy 205.692206 -20.609247) (xy 205.783082 -20.465155) (xy 205.880612 -20.325481) (xy 205.984582 -20.190532)
			(xy 206.094763 -20.060604) (xy 206.210912 -19.935984) (xy 206.332776 -19.816945) (xy 206.460084 -19.703749)
			(xy 206.592559 -19.596644) (xy 206.729909 -19.495867) (xy 206.871831 -19.401638) (xy 207.018013 -19.314165)
			(xy 207.168136 -19.23364) (xy 207.321867 -19.16024) (xy 207.47887 -19.094126) (xy 207.6388 -19.035444)
			(xy 207.801304 -18.984323) (xy 207.966025 -18.940875) (xy 208.132603 -18.905196) (xy 208.300669 -18.877364)
			(xy 208.469855 -18.85744) (xy 208.639789 -18.845468) (xy 208.810098 -18.841475) (xy 208.980407 -18.845468)
			(xy 209.150341 -18.85744) (xy 209.319527 -18.877364) (xy 209.487593 -18.905196) (xy 209.654171 -18.940875)
			(xy 209.818892 -18.984323) (xy 209.981396 -19.035444) (xy 210.141326 -19.094126) (xy 210.298329 -19.16024)
			(xy 210.45206 -19.23364) (xy 210.602183 -19.314165) (xy 210.748365 -19.401638) (xy 210.890287 -19.495867)
			(xy 211.027637 -19.596644) (xy 211.160112 -19.703749) (xy 211.28742 -19.816945) (xy 211.409284 -19.935984)
			(xy 211.525433 -20.060604) (xy 211.635614 -20.190532) (xy 211.739584 -20.325481) (xy 211.837114 -20.465155)
			(xy 211.92799 -20.609247) (xy 212.012012 -20.757441) (xy 212.088995 -20.909409) (xy 212.158771 -21.064819)
			(xy 212.221186 -21.223329) (xy 212.276103 -21.38459) (xy 212.3234 -21.548248) (xy 212.362975 -21.713943)
			(xy 212.394739 -21.881311) (xy 212.418624 -22.049983) (xy 212.434576 -22.21959) (xy 212.442561 -22.389758)
			(xy 212.44306 -22.474936) (xy 212.442561 -22.560114) (xy 235.177575 -22.560114) (xy 235.177575 -22.389758)
			(xy 235.18556 -22.21959) (xy 235.201512 -22.049983) (xy 235.225397 -21.881311) (xy 235.257161 -21.713943)
			(xy 235.296736 -21.548248) (xy 235.344033 -21.38459) (xy 235.39895 -21.223329) (xy 235.461365 -21.064819)
			(xy 235.531141 -20.909409) (xy 235.608124 -20.757441) (xy 235.692146 -20.609247) (xy 235.783022 -20.465155)
			(xy 235.880552 -20.325481) (xy 235.984522 -20.190532) (xy 236.094703 -20.060604) (xy 236.210852 -19.935984)
			(xy 236.332716 -19.816945) (xy 236.460024 -19.703749) (xy 236.592499 -19.596644) (xy 236.729849 -19.495867)
			(xy 236.871771 -19.401638) (xy 237.017953 -19.314165) (xy 237.168076 -19.23364) (xy 237.321807 -19.16024)
			(xy 237.47881 -19.094126) (xy 237.63874 -19.035444) (xy 237.801244 -18.984323) (xy 237.965965 -18.940875)
			(xy 238.132543 -18.905196) (xy 238.300609 -18.877364) (xy 238.469795 -18.85744) (xy 238.639729 -18.845468)
			(xy 238.810038 -18.841475) (xy 238.980347 -18.845468) (xy 239.150281 -18.85744) (xy 239.319467 -18.877364)
			(xy 239.487533 -18.905196) (xy 239.654111 -18.940875) (xy 239.818832 -18.984323) (xy 239.981336 -19.035444)
			(xy 240.141266 -19.094126) (xy 240.298269 -19.16024) (xy 240.452 -19.23364) (xy 240.602123 -19.314165)
			(xy 240.748305 -19.401638) (xy 240.890227 -19.495867) (xy 241.027577 -19.596644) (xy 241.160052 -19.703749)
			(xy 241.28736 -19.816945) (xy 241.409224 -19.935984) (xy 241.525373 -20.060604) (xy 241.635554 -20.190532)
			(xy 241.739524 -20.325481) (xy 241.837054 -20.465155) (xy 241.92793 -20.609247) (xy 242.011952 -20.757441)
			(xy 242.088935 -20.909409) (xy 242.158711 -21.064819) (xy 242.221126 -21.223329) (xy 242.276043 -21.38459)
			(xy 242.32334 -21.548248) (xy 242.362915 -21.713943) (xy 242.394679 -21.881311) (xy 242.418564 -22.049983)
			(xy 242.434516 -22.21959) (xy 242.442501 -22.389758) (xy 242.443 -22.474936) (xy 242.442501 -22.560114)
			(xy 242.434516 -22.730282) (xy 242.418564 -22.899889) (xy 242.394679 -23.068561) (xy 242.362915 -23.235929)
			(xy 242.32334 -23.401624) (xy 242.276043 -23.565282) (xy 242.221126 -23.726543) (xy 242.158711 -23.885053)
			(xy 242.088935 -24.040463) (xy 242.011952 -24.192431) (xy 241.92793 -24.340625) (xy 241.837054 -24.484717)
			(xy 241.739524 -24.624391) (xy 241.635554 -24.75934) (xy 241.525373 -24.889268) (xy 241.409224 -25.013888)
			(xy 241.28736 -25.132927) (xy 241.160052 -25.246123) (xy 241.027577 -25.353228) (xy 240.890227 -25.454005)
			(xy 240.748305 -25.548234) (xy 240.602123 -25.635707) (xy 240.452 -25.716232) (xy 240.298269 -25.789632)
			(xy 240.141266 -25.855746) (xy 239.981336 -25.914428) (xy 239.818832 -25.965549) (xy 239.654111 -26.008997)
			(xy 239.487533 -26.044676) (xy 239.319467 -26.072508) (xy 239.150281 -26.092432) (xy 238.980347 -26.104404)
			(xy 238.810038 -26.108398) (xy 238.639729 -26.104404) (xy 238.469795 -26.092432) (xy 238.300609 -26.072508)
			(xy 238.132543 -26.044676) (xy 237.965965 -26.008997) (xy 237.801244 -25.965549) (xy 237.63874 -25.914428)
			(xy 237.47881 -25.855746) (xy 237.321807 -25.789632) (xy 237.168076 -25.716232) (xy 237.017953 -25.635707)
			(xy 236.871771 -25.548234) (xy 236.729849 -25.454005) (xy 236.592499 -25.353228) (xy 236.460024 -25.246123)
			(xy 236.332716 -25.132927) (xy 236.210852 -25.013888) (xy 236.094703 -24.889268) (xy 235.984522 -24.75934)
			(xy 235.880552 -24.624391) (xy 235.783022 -24.484717) (xy 235.692146 -24.340625) (xy 235.608124 -24.192431)
			(xy 235.531141 -24.040463) (xy 235.461365 -23.885053) (xy 235.39895 -23.726543) (xy 235.344033 -23.565282)
			(xy 235.296736 -23.401624) (xy 235.257161 -23.235929) (xy 235.225397 -23.068561) (xy 235.201512 -22.899889)
			(xy 235.18556 -22.730282) (xy 235.177575 -22.560114) (xy 212.442561 -22.560114) (xy 212.434576 -22.730282)
			(xy 212.418624 -22.899889) (xy 212.394739 -23.068561) (xy 212.362975 -23.235929) (xy 212.3234 -23.401624)
			(xy 212.276103 -23.565282) (xy 212.221186 -23.726543) (xy 212.158771 -23.885053) (xy 212.088995 -24.040463)
			(xy 212.012012 -24.192431) (xy 211.92799 -24.340625) (xy 211.837114 -24.484717) (xy 211.739584 -24.624391)
			(xy 211.635614 -24.75934) (xy 211.525433 -24.889268) (xy 211.409284 -25.013888) (xy 211.28742 -25.132927)
			(xy 211.160112 -25.246123) (xy 211.027637 -25.353228) (xy 210.890287 -25.454005) (xy 210.748365 -25.548234)
			(xy 210.602183 -25.635707) (xy 210.45206 -25.716232) (xy 210.298329 -25.789632) (xy 210.141326 -25.855746)
			(xy 209.981396 -25.914428) (xy 209.818892 -25.965549) (xy 209.654171 -26.008997) (xy 209.487593 -26.044676)
			(xy 209.319527 -26.072508) (xy 209.150341 -26.092432) (xy 208.980407 -26.104404) (xy 208.810098 -26.108398)
			(xy 208.639789 -26.104404) (xy 208.469855 -26.092432) (xy 208.300669 -26.072508) (xy 208.132603 -26.044676)
			(xy 207.966025 -26.008997) (xy 207.801304 -25.965549) (xy 207.6388 -25.914428) (xy 207.47887 -25.855746)
			(xy 207.321867 -25.789632) (xy 207.168136 -25.716232) (xy 207.018013 -25.635707) (xy 206.871831 -25.548234)
			(xy 206.729909 -25.454005) (xy 206.592559 -25.353228) (xy 206.460084 -25.246123) (xy 206.332776 -25.132927)
			(xy 206.210912 -25.013888) (xy 206.094763 -24.889268) (xy 205.984582 -24.75934) (xy 205.880612 -24.624391)
			(xy 205.783082 -24.484717) (xy 205.692206 -24.340625) (xy 205.608184 -24.192431) (xy 205.531201 -24.040463)
			(xy 205.461425 -23.885053) (xy 205.39901 -23.726543) (xy 205.344093 -23.565282) (xy 205.296796 -23.401624)
			(xy 205.257221 -23.235929) (xy 205.225457 -23.068561) (xy 205.201572 -22.899889) (xy 205.18562 -22.730282)
			(xy 205.177635 -22.560114) (xy 161.1884 -22.560114) (xy 161.1884 -26.950924) (xy 161.188713 -26.959116)
			(xy 161.193901 -26.974658) (xy 161.19856 -26.981404) (xy 161.203386 -26.986992) (xy 162.141408 -27.925014)
			(xy 162.146996 -27.92984) (xy 162.153735 -27.934512) (xy 162.169281 -27.939702) (xy 162.177476 -27.94)
			(xy 209.1944 -27.94) (xy 209.22766 -27.940521) (xy 209.29361 -27.949209) (xy 209.357861 -27.966434)
			(xy 209.419312 -27.991903) (xy 209.476911 -28.025179) (xy 209.529671 -28.065692) (xy 209.553556 -28.088844)
			(xy 211.331556 -29.866844) (xy 211.354712 -29.890724) (xy 211.395218 -29.943488) (xy 211.428489 -30.001089)
			(xy 211.453953 -30.06254) (xy 211.471175 -30.126791) (xy 211.479861 -30.192741) (xy 211.4804 -30.226)
			(xy 211.4804 -46.99) (xy 211.479879 -47.02326) (xy 211.471191 -47.08921) (xy 211.453966 -47.153461)
			(xy 211.428497 -47.214912) (xy 211.395221 -47.272511) (xy 211.354708 -47.325271) (xy 211.331556 -47.349156)
			(xy 210.442556 -48.238156) (xy 210.418676 -48.261312) (xy 210.365912 -48.301818) (xy 210.308311 -48.335089)
			(xy 210.24686 -48.360553) (xy 210.182609 -48.377775) (xy 210.116659 -48.386461) (xy 210.0834 -48.387)
			(xy 197.797166 -48.387) (xy 197.763907 -48.386476) (xy 197.697959 -48.377785) (xy 197.633711 -48.360556)
			(xy 197.572262 -48.335084) (xy 197.514667 -48.301806) (xy 197.461911 -48.261291) (xy 197.43801 -48.238156)
			(xy 191.552068 -42.352214) (xy 191.54648 -42.347388) (xy 191.53974 -42.342717) (xy 191.524194 -42.337532)
			(xy 191.516 -42.337228) (xy 190.21425 -42.337228) (xy 190.207392 -42.337736) (xy 190.19808 -42.339465)
			(xy 190.181542 -42.348658) (xy 190.16944 -42.363205) (xy 190.16599 -42.372026) (xy 190.13551 -42.463466)
			(xy 190.13424 -42.468292) (xy 190.132516 -42.477913) (xy 190.135637 -42.497191) (xy 190.145736 -42.513906)
			(xy 190.15329 -42.520108) (xy 190.16746 -42.530951) (xy 190.19441 -42.55434) (xy 190.207138 -42.566844)
			(xy 193.935604 -46.29531) (xy 193.958764 -46.319188) (xy 193.999278 -46.37195) (xy 194.032555 -46.42955)
			(xy 194.058026 -46.491002) (xy 194.075255 -46.555254) (xy 194.083946 -46.621205) (xy 194.084448 -46.654466)
			(xy 194.084448 -51.02225) (xy 194.084017 -51.049936) (xy 207.409803 -51.049936) (xy 207.413813 -50.944033)
			(xy 207.425821 -50.838737) (xy 207.445758 -50.734651) (xy 207.47351 -50.632371) (xy 207.508918 -50.532482)
			(xy 207.551779 -50.435558) (xy 207.601847 -50.342152) (xy 207.658837 -50.252801) (xy 207.72242 -50.168015)
			(xy 207.792234 -50.088281) (xy 207.867878 -50.014056) (xy 207.948918 -49.945763) (xy 208.034892 -49.883796)
			(xy 208.125306 -49.828508) (xy 208.219642 -49.780216) (xy 208.317361 -49.739197) (xy 208.417901 -49.705686)
			(xy 208.520689 -49.679874) (xy 208.625133 -49.66191) (xy 208.730638 -49.651897) (xy 208.836597 -49.649891)
			(xy 208.942405 -49.655905) (xy 209.047455 -49.669904) (xy 209.151145 -49.691807) (xy 209.252882 -49.72149)
			(xy 209.352083 -49.758781) (xy 209.448179 -49.803469) (xy 209.54062 -49.855296) (xy 209.628877 -49.913966)
			(xy 209.712444 -49.979143) (xy 209.790843 -50.050453) (xy 209.863624 -50.127487) (xy 209.93037 -50.209806)
			(xy 209.9907 -50.296937) (xy 210.044267 -50.388381) (xy 210.090765 -50.483614) (xy 210.129927 -50.582091)
			(xy 210.16153 -50.683248) (xy 210.185391 -50.786506) (xy 210.201376 -50.891272) (xy 210.209391 -50.996947)
			(xy 210.209892 -51.049936) (xy 237.409743 -51.049936) (xy 237.413753 -50.944033) (xy 237.425761 -50.838737)
			(xy 237.445698 -50.734651) (xy 237.47345 -50.632371) (xy 237.508858 -50.532482) (xy 237.551719 -50.435558)
			(xy 237.601787 -50.342152) (xy 237.658777 -50.252801) (xy 237.72236 -50.168015) (xy 237.792174 -50.088281)
			(xy 237.867818 -50.014056) (xy 237.948858 -49.945763) (xy 238.034832 -49.883796) (xy 238.125246 -49.828508)
			(xy 238.219582 -49.780216) (xy 238.317301 -49.739197) (xy 238.417841 -49.705686) (xy 238.520629 -49.679874)
			(xy 238.625073 -49.66191) (xy 238.730578 -49.651897) (xy 238.836537 -49.649891) (xy 238.942345 -49.655905)
			(xy 239.047395 -49.669904) (xy 239.151085 -49.691807) (xy 239.252822 -49.72149) (xy 239.352023 -49.758781)
			(xy 239.448119 -49.803469) (xy 239.54056 -49.855296) (xy 239.628817 -49.913966) (xy 239.712384 -49.979143)
			(xy 239.790783 -50.050453) (xy 239.863564 -50.127487) (xy 239.93031 -50.209806) (xy 239.99064 -50.296937)
			(xy 240.044207 -50.388381) (xy 240.090705 -50.483614) (xy 240.129867 -50.582091) (xy 240.16147 -50.683248)
			(xy 240.185331 -50.786506) (xy 240.201316 -50.891272) (xy 240.209331 -50.996947) (xy 240.209832 -51.049936)
			(xy 240.209331 -51.102925) (xy 240.201316 -51.2086) (xy 240.185331 -51.313366) (xy 240.16147 -51.416624)
			(xy 240.129867 -51.517781) (xy 240.090705 -51.616258) (xy 240.044207 -51.711491) (xy 239.99064 -51.802935)
			(xy 239.93031 -51.890066) (xy 239.863564 -51.972385) (xy 239.790783 -52.049419) (xy 239.712384 -52.120729)
			(xy 239.628817 -52.185906) (xy 239.54056 -52.244576) (xy 239.448119 -52.296403) (xy 239.352023 -52.341091)
			(xy 239.252822 -52.378382) (xy 239.151085 -52.408065) (xy 239.047395 -52.429968) (xy 238.942345 -52.443967)
			(xy 238.836537 -52.449981) (xy 238.730578 -52.447975) (xy 238.625073 -52.437962) (xy 238.520629 -52.419998)
			(xy 238.417841 -52.394186) (xy 238.317301 -52.360675) (xy 238.219582 -52.319656) (xy 238.125246 -52.271364)
			(xy 238.034832 -52.216076) (xy 237.948858 -52.154109) (xy 237.867818 -52.085816) (xy 237.792174 -52.011591)
			(xy 237.72236 -51.931857) (xy 237.658777 -51.847071) (xy 237.601787 -51.75772) (xy 237.551719 -51.664314)
			(xy 237.508858 -51.56739) (xy 237.47345 -51.467501) (xy 237.445698 -51.365221) (xy 237.425761 -51.261135)
			(xy 237.413753 -51.155839) (xy 237.409743 -51.049936) (xy 210.209892 -51.049936) (xy 210.209391 -51.102925)
			(xy 210.201376 -51.2086) (xy 210.185391 -51.313366) (xy 210.16153 -51.416624) (xy 210.129927 -51.517781)
			(xy 210.090765 -51.616258) (xy 210.044267 -51.711491) (xy 209.9907 -51.802935) (xy 209.93037 -51.890066)
			(xy 209.863624 -51.972385) (xy 209.790843 -52.049419) (xy 209.712444 -52.120729) (xy 209.628877 -52.185906)
			(xy 209.54062 -52.244576) (xy 209.448179 -52.296403) (xy 209.352083 -52.341091) (xy 209.252882 -52.378382)
			(xy 209.151145 -52.408065) (xy 209.047455 -52.429968) (xy 208.942405 -52.443967) (xy 208.836597 -52.449981)
			(xy 208.730638 -52.447975) (xy 208.625133 -52.437962) (xy 208.520689 -52.419998) (xy 208.417901 -52.394186)
			(xy 208.317361 -52.360675) (xy 208.219642 -52.319656) (xy 208.125306 -52.271364) (xy 208.034892 -52.216076)
			(xy 207.948918 -52.154109) (xy 207.867878 -52.085816) (xy 207.792234 -52.011591) (xy 207.72242 -51.931857)
			(xy 207.658837 -51.847071) (xy 207.601847 -51.75772) (xy 207.551779 -51.664314) (xy 207.508918 -51.56739)
			(xy 207.47351 -51.467501) (xy 207.445758 -51.365221) (xy 207.425821 -51.261135) (xy 207.413813 -51.155839)
			(xy 207.409803 -51.049936) (xy 194.084017 -51.049936) (xy 194.08393 -51.055512) (xy 194.075249 -51.121466)
			(xy 194.05803 -51.185722) (xy 194.032567 -51.247179) (xy 193.999297 -51.304784) (xy 193.958789 -51.357551)
			(xy 193.935604 -51.381406) (xy 193.390774 -51.926236) (xy 193.366895 -51.949394) (xy 193.314132 -51.989904)
			(xy 193.256532 -52.023177) (xy 193.19508 -52.048645) (xy 193.130828 -52.06587) (xy 193.064878 -52.074558)
			(xy 193.031618 -52.07508) (xy 182.815484 -52.07508) (xy 182.782225 -52.074558) (xy 182.716276 -52.065868)
			(xy 182.652026 -52.04864) (xy 182.590577 -52.023169) (xy 182.532981 -51.989891) (xy 182.480224 -51.949376)
			(xy 182.456328 -51.926236) (xy 181.784244 -51.254152) (xy 181.761088 -51.230272) (xy 181.720582 -51.177508)
			(xy 181.687312 -51.119907) (xy 181.661849 -51.058455) (xy 181.644627 -50.994205) (xy 181.635942 -50.928255)
			(xy 181.6354 -50.894996) (xy 181.6354 -46.609) (xy 181.635921 -46.57574) (xy 181.644609 -46.50979)
			(xy 181.661834 -46.445539) (xy 181.687303 -46.384088) (xy 181.720579 -46.326489) (xy 181.761092 -46.273729)
			(xy 181.784244 -46.249844) (xy 185.467244 -42.566844) (xy 185.479975 -42.554343) (xy 185.506924 -42.530954)
			(xy 185.521092 -42.520108) (xy 185.528616 -42.513934) (xy 185.538707 -42.497314) (xy 185.541856 -42.478125)
			(xy 185.540142 -42.468546) (xy 185.538872 -42.463466) (xy 185.508392 -42.372026) (xy 185.504527 -42.362103)
			(xy 185.490225 -42.346358) (xy 185.470768 -42.337762) (xy 185.460132 -42.337228) (xy 174.146972 -42.337228)
			(xy 174.142081 -42.337363) (xy 174.132487 -42.339278) (xy 174.127922 -42.341038) (xy 174.11827 -42.344848)
			(xy 174.111158 -42.352214) (xy 172.697648 -43.765724) (xy 172.692822 -43.771312) (xy 172.688155 -43.778053)
			(xy 172.682975 -43.793599) (xy 172.682662 -43.801792) (xy 172.682662 -47.032361) (xy 177.987702 -47.032361)
			(xy 177.987702 -46.947639) (xy 177.995755 -46.863302) (xy 178.011789 -46.780112) (xy 178.035657 -46.698822)
			(xy 178.067145 -46.62017) (xy 178.105967 -46.544867) (xy 178.15177 -46.473595) (xy 178.204141 -46.406999)
			(xy 178.262606 -46.345684) (xy 178.326634 -46.290203) (xy 178.395646 -46.24106) (xy 178.469016 -46.1987)
			(xy 178.546081 -46.163505) (xy 178.626143 -46.135796) (xy 178.708476 -46.115822) (xy 178.792335 -46.103765)
			(xy 178.87696 -46.099734) (xy 178.961585 -46.103765) (xy 179.045444 -46.115822) (xy 179.127777 -46.135796)
			(xy 179.207839 -46.163505) (xy 179.284904 -46.1987) (xy 179.358274 -46.24106) (xy 179.427286 -46.290203)
			(xy 179.491314 -46.345684) (xy 179.549779 -46.406999) (xy 179.60215 -46.473595) (xy 179.647953 -46.544867)
			(xy 179.686775 -46.62017) (xy 179.718263 -46.698822) (xy 179.742131 -46.780112) (xy 179.758165 -46.863302)
			(xy 179.766218 -46.947639) (xy 179.766722 -46.99) (xy 179.766218 -47.032361) (xy 179.758165 -47.116698)
			(xy 179.742131 -47.199888) (xy 179.718263 -47.281178) (xy 179.686775 -47.35983) (xy 179.647953 -47.435133)
			(xy 179.60215 -47.506405) (xy 179.549779 -47.573001) (xy 179.491314 -47.634316) (xy 179.427286 -47.689797)
			(xy 179.358274 -47.73894) (xy 179.284904 -47.7813) (xy 179.207839 -47.816495) (xy 179.127777 -47.844204)
			(xy 179.045444 -47.864178) (xy 178.961585 -47.876235) (xy 178.87696 -47.880267) (xy 178.792335 -47.876235)
			(xy 178.708476 -47.864178) (xy 178.626143 -47.844204) (xy 178.546081 -47.816495) (xy 178.469016 -47.7813)
			(xy 178.395646 -47.73894) (xy 178.326634 -47.689797) (xy 178.262606 -47.634316) (xy 178.204141 -47.573001)
			(xy 178.15177 -47.506405) (xy 178.105967 -47.435133) (xy 178.067145 -47.35983) (xy 178.035657 -47.281178)
			(xy 178.011789 -47.199888) (xy 177.995755 -47.116698) (xy 177.987702 -47.032361) (xy 172.682662 -47.032361)
			(xy 172.682662 -50.465228) (xy 172.682975 -50.47342) (xy 172.688161 -50.488963) (xy 172.692822 -50.495708)
			(xy 172.697648 -50.501296) (xy 172.778674 -50.582322) (xy 172.784262 -50.587148) (xy 172.791004 -50.59181)
			(xy 172.80655 -50.596979) (xy 172.814742 -50.597308) (xy 173.980348 -50.597308) (xy 174.013609 -50.597826)
			(xy 174.079563 -50.606507) (xy 174.143818 -50.623728) (xy 174.205273 -50.649193) (xy 174.262876 -50.682466)
			(xy 174.315641 -50.722977) (xy 174.339504 -50.746152) (xy 176.661318 -53.067966) (xy 176.684475 -53.091846)
			(xy 176.724982 -53.144609) (xy 176.758252 -53.20221) (xy 176.783715 -53.263662) (xy 176.800936 -53.327913)
			(xy 176.80962 -53.393863) (xy 176.810162 -53.427122) (xy 176.810162 -54.679088) (xy 176.809641 -54.712349)
			(xy 176.800957 -54.778301) (xy 176.783734 -54.842554) (xy 176.758268 -54.904008) (xy 176.724996 -54.96161)
			(xy 176.684487 -55.014375) (xy 176.661318 -55.038244) (xy 175.970438 -55.729124) (xy 175.946558 -55.752281)
			(xy 175.893795 -55.792787) (xy 175.836194 -55.826058) (xy 175.774742 -55.851521) (xy 175.710491 -55.868743)
			(xy 175.644541 -55.877426) (xy 175.611282 -55.877968) (xy 160.84423 -55.877968) (xy 160.83934 -55.878106)
			(xy 160.829748 -55.880026) (xy 160.82518 -55.881778) (xy 160.815528 -55.885588) (xy 160.808416 -55.892954)
			(xy 153.131012 -63.570358) (xy 153.126186 -63.575946) (xy 153.121519 -63.582687) (xy 153.116342 -63.598233)
			(xy 153.116026 -63.606426) (xy 153.116026 -75.190858) (xy 153.116329 -75.199054) (xy 153.121503 -75.214606)
			(xy 153.126186 -75.221338) (xy 153.131012 -75.226926) (xy 153.5811 -75.677014) (xy 153.586688 -75.68184)
			(xy 153.593427 -75.686513) (xy 153.608973 -75.691705) (xy 153.617168 -75.692) (xy 164.741606 -75.692)
			(xy 164.749734 -75.691238) (xy 164.750242 -75.691238) (xy 164.757761 -75.689637) (xy 164.771451 -75.682663)
			(xy 164.777166 -75.677522) (xy 165.085014 -75.369674) (xy 165.08984 -75.364086) (xy 165.094509 -75.357346)
			(xy 165.099693 -75.3418) (xy 165.1 -75.333606) (xy 165.1 -67.851782) (xy 165.099872 -67.847235) (xy 165.098204 -67.838294)
			(xy 165.096698 -67.834002) (xy 165.088062 -67.810634) (xy 165.082728 -67.80403) (xy 165.065 -67.781256)
			(xy 165.03589 -67.731425) (xy 165.014611 -67.677781) (xy 165.001646 -67.621546) (xy 164.997291 -67.564)
			(xy 165.001646 -67.506454) (xy 165.014611 -67.450219) (xy 165.03589 -67.396575) (xy 165.065 -67.346744)
			(xy 165.082728 -67.32397) (xy 165.088062 -67.317366) (xy 165.096952 -67.293744) (xy 165.098399 -67.289443)
			(xy 165.099929 -67.280501) (xy 165.1 -67.275964) (xy 165.1 -64.30645) (xy 165.1 -64.303148) (xy 165.098677 -64.291915)
			(xy 165.087716 -64.272164) (xy 165.069352 -64.25901) (xy 165.058344 -64.256412) (xy 165.05809 -64.256412)
			(xy 165.030616 -64.251007) (xy 164.977527 -64.233214) (xy 164.92761 -64.207849) (xy 164.881938 -64.175457)
			(xy 164.841494 -64.136735) (xy 164.807147 -64.092515) (xy 164.779636 -64.043748) (xy 164.759551 -63.991482)
			(xy 164.747325 -63.936841) (xy 164.74322 -63.881) (xy 164.747325 -63.825159) (xy 164.759551 -63.770518)
			(xy 164.779636 -63.718252) (xy 164.807147 -63.669485) (xy 164.841494 -63.625265) (xy 164.881938 -63.586543)
			(xy 164.92761 -63.554151) (xy 164.977527 -63.528786) (xy 165.030616 -63.510993) (xy 165.05809 -63.505588)
			(xy 165.058344 -63.505588) (xy 165.069344 -63.502973) (xy 165.087696 -63.489816) (xy 165.098667 -63.470079)
			(xy 165.1 -63.458852) (xy 165.1 -59.944) (xy 165.100521 -59.91074) (xy 165.109209 -59.84479) (xy 165.126434 -59.780539)
			(xy 165.151903 -59.719088) (xy 165.185179 -59.661489) (xy 165.225692 -59.608729) (xy 165.248844 -59.584844)
			(xy 165.782498 -59.05119) (xy 165.806376 -59.02803) (xy 165.859137 -58.987515) (xy 165.916737 -58.954237)
			(xy 165.978189 -58.928764) (xy 166.042441 -58.911535) (xy 166.108393 -58.902842) (xy 166.141654 -58.902346)
			(xy 169.577512 -58.902346) (xy 169.610772 -58.902868) (xy 169.676722 -58.911556) (xy 169.740973 -58.928781)
			(xy 169.802425 -58.954249) (xy 169.860025 -58.987523) (xy 169.912787 -59.028034) (xy 169.936668 -59.05119)
			(xy 170.640502 -59.755024) (xy 170.663661 -59.778903) (xy 170.704174 -59.831664) (xy 170.73745 -59.889264)
			(xy 170.762919 -59.950716) (xy 170.780146 -60.014968) (xy 170.788835 -60.080919) (xy 170.789346 -60.11418)
			(xy 170.789346 -66.3194) (xy 178.683872 -66.3194) (xy 178.687902 -66.234795) (xy 178.699957 -66.150957)
			(xy 178.719926 -66.068644) (xy 178.74763 -65.988602) (xy 178.782817 -65.911556) (xy 178.825168 -65.838204)
			(xy 178.8743 -65.769209) (xy 178.929768 -65.705198) (xy 178.99107 -65.646749) (xy 179.057651 -65.594392)
			(xy 179.128907 -65.548601) (xy 179.204193 -65.509791) (xy 179.282827 -65.478314) (xy 179.364098 -65.454453)
			(xy 179.447268 -65.438427) (xy 179.531586 -65.430378) (xy 179.573936 -65.429892) (xy 179.574698 -65.429892)
			(xy 179.613046 -65.430288) (xy 179.689453 -65.436923) (xy 179.765005 -65.450117) (xy 179.839139 -65.469774)
			(xy 179.911302 -65.495746) (xy 179.9463 -65.511426) (xy 179.956573 -65.515566) (xy 179.978699 -65.515566)
			(xy 179.988972 -65.511426) (xy 180.023978 -65.49577) (xy 180.096146 -65.469818) (xy 180.170278 -65.45017)
			(xy 180.245826 -65.436971) (xy 180.322228 -65.430321) (xy 180.360574 -65.429892) (xy 180.361336 -65.429892)
			(xy 180.403683 -65.430397) (xy 180.487994 -65.438451) (xy 180.571158 -65.454483) (xy 180.652421 -65.478347)
			(xy 180.731048 -65.509827) (xy 180.806327 -65.548639) (xy 180.877576 -65.59443) (xy 180.944149 -65.646786)
			(xy 181.005444 -65.705234) (xy 181.060907 -65.769243) (xy 181.110033 -65.838234) (xy 181.15238 -65.911582)
			(xy 181.187562 -65.988624) (xy 181.215263 -66.068661) (xy 181.23523 -66.150968) (xy 181.247283 -66.234801)
			(xy 181.251313 -66.3194) (xy 181.247283 -66.403999) (xy 181.23523 -66.487832) (xy 181.215263 -66.570139)
			(xy 181.187562 -66.650176) (xy 181.15238 -66.727218) (xy 181.110033 -66.800566) (xy 181.060907 -66.869557)
			(xy 181.005444 -66.933566) (xy 180.944149 -66.992014) (xy 180.877576 -67.04437) (xy 180.806327 -67.090161)
			(xy 180.731048 -67.128973) (xy 180.652421 -67.160453) (xy 180.571158 -67.184317) (xy 180.487994 -67.200349)
			(xy 180.403683 -67.208403) (xy 180.361336 -67.208908) (xy 180.360574 -67.208908) (xy 180.322227 -67.208485)
			(xy 180.24582 -67.201857) (xy 180.170269 -67.188668) (xy 180.096135 -67.169018) (xy 180.02397 -67.143051)
			(xy 179.988972 -67.127374) (xy 179.978699 -67.123234) (xy 179.956573 -67.123234) (xy 179.9463 -67.127374)
			(xy 179.911298 -67.14304) (xy 179.839129 -67.16899) (xy 179.764996 -67.188636) (xy 179.689447 -67.201832)
			(xy 179.613044 -67.20848) (xy 179.574698 -67.208908) (xy 179.573936 -67.208908) (xy 179.531586 -67.208422)
			(xy 179.447268 -67.200373) (xy 179.364098 -67.184347) (xy 179.282827 -67.160486) (xy 179.204193 -67.129009)
			(xy 179.128907 -67.090199) (xy 179.057651 -67.044408) (xy 178.99107 -66.992051) (xy 178.929768 -66.933602)
			(xy 178.8743 -66.869591) (xy 178.825168 -66.800596) (xy 178.782817 -66.727244) (xy 178.74763 -66.650198)
			(xy 178.719926 -66.570156) (xy 178.699957 -66.487843) (xy 178.687902 -66.404005) (xy 178.683872 -66.3194)
			(xy 170.789346 -66.3194) (xy 170.789346 -67.812412) (xy 170.788824 -67.845672) (xy 170.780136 -67.911622)
			(xy 170.76291 -67.975873) (xy 170.737442 -68.037325) (xy 170.704167 -68.094924) (xy 170.663656 -68.147685)
			(xy 170.640502 -68.171568) (xy 169.62247 -69.1896) (xy 177.667872 -69.1896) (xy 177.671902 -69.104995)
			(xy 177.683957 -69.021157) (xy 177.703926 -68.938844) (xy 177.73163 -68.858802) (xy 177.766817 -68.781756)
			(xy 177.809168 -68.708404) (xy 177.8583 -68.639409) (xy 177.913768 -68.575398) (xy 177.97507 -68.516949)
			(xy 178.041651 -68.464592) (xy 178.112907 -68.418801) (xy 178.188193 -68.379991) (xy 178.266827 -68.348514)
			(xy 178.348098 -68.324653) (xy 178.431268 -68.308627) (xy 178.515586 -68.300578) (xy 178.557936 -68.300092)
			(xy 178.558444 -68.300092) (xy 178.597192 -68.300509) (xy 178.674394 -68.307273) (xy 178.750714 -68.320729)
			(xy 178.825573 -68.340774) (xy 178.898405 -68.367256) (xy 178.968657 -68.399975) (xy 179.002436 -68.418964)
			(xy 179.01031 -68.423123) (xy 179.027836 -68.426217) (xy 179.045362 -68.423123) (xy 179.053236 -68.418964)
			(xy 179.087017 -68.399978) (xy 179.157269 -68.367265) (xy 179.230101 -68.340786) (xy 179.304961 -68.320743)
			(xy 179.38128 -68.307289) (xy 179.45848 -68.300524) (xy 179.497228 -68.300092) (xy 179.497736 -68.300092)
			(xy 179.540083 -68.300597) (xy 179.624394 -68.308651) (xy 179.707558 -68.324683) (xy 179.788821 -68.348547)
			(xy 179.867448 -68.380027) (xy 179.942727 -68.418839) (xy 180.013976 -68.46463) (xy 180.080549 -68.516986)
			(xy 180.141844 -68.575434) (xy 180.197307 -68.639443) (xy 180.246433 -68.708434) (xy 180.28878 -68.781782)
			(xy 180.323962 -68.858824) (xy 180.351663 -68.938861) (xy 180.37163 -69.021168) (xy 180.383683 -69.105001)
			(xy 180.387713 -69.1896) (xy 180.383683 -69.274199) (xy 180.37163 -69.358032) (xy 180.351663 -69.440339)
			(xy 180.323962 -69.520376) (xy 180.28878 -69.597418) (xy 180.246433 -69.670766) (xy 180.197307 -69.739757)
			(xy 180.141844 -69.803766) (xy 180.080549 -69.862214) (xy 180.013976 -69.91457) (xy 179.942727 -69.960361)
			(xy 179.867448 -69.999173) (xy 179.788821 -70.030653) (xy 179.707558 -70.054517) (xy 179.624394 -70.070549)
			(xy 179.540083 -70.078603) (xy 179.497736 -70.079108) (xy 179.497228 -70.079108) (xy 179.45848 -70.078658)
			(xy 179.38128 -70.0719) (xy 179.304961 -70.058451) (xy 179.230101 -70.038412) (xy 179.157268 -70.011936)
			(xy 179.087016 -69.979222) (xy 179.053236 -69.960236) (xy 179.045362 -69.956077) (xy 179.027836 -69.952983)
			(xy 179.01031 -69.956077) (xy 179.002436 -69.960236) (xy 178.968662 -69.979233) (xy 178.898407 -70.011945)
			(xy 178.825574 -70.038422) (xy 178.750713 -70.058462) (xy 178.674393 -70.071915) (xy 178.597192 -70.078678)
			(xy 178.558444 -70.079108) (xy 178.557936 -70.079108) (xy 178.515586 -70.078622) (xy 178.431268 -70.070573)
			(xy 178.348098 -70.054547) (xy 178.266827 -70.030686) (xy 178.188193 -69.999209) (xy 178.112907 -69.960399)
			(xy 178.041651 -69.914608) (xy 177.97507 -69.862251) (xy 177.913768 -69.803802) (xy 177.8583 -69.739791)
			(xy 177.809168 -69.670796) (xy 177.766817 -69.597444) (xy 177.73163 -69.520398) (xy 177.703926 -69.440356)
			(xy 177.683957 -69.358043) (xy 177.671902 -69.274205) (xy 177.667872 -69.1896) (xy 169.62247 -69.1896)
			(xy 168.543986 -70.268084) (xy 168.53916 -70.273672) (xy 168.534485 -70.28041) (xy 168.529288 -70.295956)
			(xy 168.529 -70.304152) (xy 168.529 -71.050404) (xy 168.529174 -71.056412) (xy 168.532008 -71.068088)
			(xy 168.534588 -71.073518) (xy 168.547677 -71.100502) (xy 168.566222 -71.157534) (xy 168.575637 -71.216761)
			(xy 168.576244 -71.246746) (xy 168.576244 -71.247254) (xy 168.575673 -71.277201) (xy 168.566266 -71.336354)
			(xy 168.547709 -71.393302) (xy 168.534588 -71.420228) (xy 168.534588 -71.420482) (xy 168.534334 -71.42099)
			(xy 168.531877 -71.426317) (xy 168.529193 -71.437733) (xy 168.529 -71.443596) (xy 168.529 -72.009)
			(xy 177.667872 -72.009) (xy 177.671902 -71.924395) (xy 177.683957 -71.840557) (xy 177.703926 -71.758244)
			(xy 177.73163 -71.678202) (xy 177.766817 -71.601156) (xy 177.809168 -71.527804) (xy 177.8583 -71.458809)
			(xy 177.913768 -71.394798) (xy 177.97507 -71.336349) (xy 178.041651 -71.283992) (xy 178.112907 -71.238201)
			(xy 178.188193 -71.199391) (xy 178.266827 -71.167914) (xy 178.348098 -71.144053) (xy 178.431268 -71.128027)
			(xy 178.515586 -71.119978) (xy 178.557936 -71.119492) (xy 178.558444 -71.119492) (xy 178.597192 -71.119909)
			(xy 178.674394 -71.126673) (xy 178.750714 -71.140129) (xy 178.825573 -71.160174) (xy 178.898405 -71.186656)
			(xy 178.968657 -71.219375) (xy 179.002436 -71.238364) (xy 179.01031 -71.242523) (xy 179.027836 -71.245617)
			(xy 179.045362 -71.242523) (xy 179.053236 -71.238364) (xy 179.087017 -71.219378) (xy 179.157269 -71.186665)
			(xy 179.230101 -71.160186) (xy 179.304961 -71.140143) (xy 179.38128 -71.126689) (xy 179.45848 -71.119924)
			(xy 179.497228 -71.119492) (xy 179.497736 -71.119492) (xy 179.540083 -71.119997) (xy 179.624394 -71.128051)
			(xy 179.707558 -71.144083) (xy 179.788821 -71.167947) (xy 179.867448 -71.199427) (xy 179.942727 -71.238239)
			(xy 180.013976 -71.28403) (xy 180.080549 -71.336386) (xy 180.141844 -71.394834) (xy 180.197307 -71.458843)
			(xy 180.246433 -71.527834) (xy 180.28878 -71.601182) (xy 180.323962 -71.678224) (xy 180.351663 -71.758261)
			(xy 180.37163 -71.840568) (xy 180.383683 -71.924401) (xy 180.387713 -72.009) (xy 180.383683 -72.093599)
			(xy 180.37163 -72.177432) (xy 180.351663 -72.259739) (xy 180.323962 -72.339776) (xy 180.28878 -72.416818)
			(xy 180.246433 -72.490166) (xy 180.197307 -72.559157) (xy 180.141844 -72.623166) (xy 180.080549 -72.681614)
			(xy 180.013976 -72.73397) (xy 179.942727 -72.779761) (xy 179.867448 -72.818573) (xy 179.788821 -72.850053)
			(xy 179.707558 -72.873917) (xy 179.624394 -72.889949) (xy 179.540083 -72.898003) (xy 179.497736 -72.898508)
			(xy 179.497228 -72.898508) (xy 179.45848 -72.898058) (xy 179.38128 -72.8913) (xy 179.304961 -72.877851)
			(xy 179.230101 -72.857812) (xy 179.157268 -72.831336) (xy 179.087016 -72.798622) (xy 179.053236 -72.779636)
			(xy 179.045362 -72.775477) (xy 179.027836 -72.772383) (xy 179.01031 -72.775477) (xy 179.002436 -72.779636)
			(xy 178.968662 -72.798633) (xy 178.898407 -72.831345) (xy 178.825574 -72.857822) (xy 178.750713 -72.877862)
			(xy 178.674393 -72.891315) (xy 178.597192 -72.898078) (xy 178.558444 -72.898508) (xy 178.557936 -72.898508)
			(xy 178.515586 -72.898022) (xy 178.431268 -72.889973) (xy 178.348098 -72.873947) (xy 178.266827 -72.850086)
			(xy 178.188193 -72.818609) (xy 178.112907 -72.779799) (xy 178.041651 -72.734008) (xy 177.97507 -72.681651)
			(xy 177.913768 -72.623202) (xy 177.8583 -72.559191) (xy 177.809168 -72.490196) (xy 177.766817 -72.416844)
			(xy 177.73163 -72.339798) (xy 177.703926 -72.259756) (xy 177.683957 -72.177443) (xy 177.671902 -72.093605)
			(xy 177.667872 -72.009) (xy 168.529 -72.009) (xy 168.529 -72.066404) (xy 168.529174 -72.072412) (xy 168.532008 -72.084088)
			(xy 168.534588 -72.089518) (xy 168.547677 -72.116502) (xy 168.566222 -72.173534) (xy 168.575637 -72.232761)
			(xy 168.576244 -72.262746) (xy 168.576244 -72.263254) (xy 168.575673 -72.293201) (xy 168.566266 -72.352354)
			(xy 168.547709 -72.409302) (xy 168.534588 -72.436228) (xy 168.534588 -72.436482) (xy 168.534334 -72.43699)
			(xy 168.531877 -72.442317) (xy 168.529193 -72.453733) (xy 168.529 -72.459596) (xy 168.529 -73.082404)
			(xy 168.529174 -73.088412) (xy 168.532008 -73.100088) (xy 168.534588 -73.105518) (xy 168.547677 -73.132502)
			(xy 168.566222 -73.189534) (xy 168.575637 -73.248761) (xy 168.576244 -73.278746) (xy 168.576244 -73.279254)
			(xy 168.575673 -73.309201) (xy 168.566266 -73.368354) (xy 168.547709 -73.425302) (xy 168.534588 -73.452228)
			(xy 168.534588 -73.452482) (xy 168.534334 -73.45299) (xy 168.531877 -73.458317) (xy 168.529193 -73.469733)
			(xy 168.529 -73.475596) (xy 168.529 -75.460606) (xy 168.52931 -75.468799) (xy 168.534494 -75.484344)
			(xy 168.53916 -75.491086) (xy 168.543986 -75.496674) (xy 168.784778 -75.737466) (xy 168.790366 -75.742292)
			(xy 168.797109 -75.746951) (xy 168.812655 -75.752113) (xy 168.820846 -75.752452) (xy 182.7022 -75.752452)
			(xy 182.712218 -75.752032) (xy 182.730726 -75.74436) (xy 182.744887 -75.730186) (xy 182.752541 -75.71167)
			(xy 182.753 -75.701652) (xy 182.753 -71.820278) (xy 182.753 -71.817738) (xy 182.752443 -71.810447)
			(xy 182.747679 -71.796629) (xy 182.743602 -71.79056) (xy 182.73903 -71.785226) (xy 182.718456 -71.763636)
			(xy 182.715133 -71.760282) (xy 182.707459 -71.754786) (xy 182.703216 -71.752714) (xy 182.695088 -71.748904)
			(xy 182.685436 -71.748142) (xy 182.643894 -71.744677) (xy 182.561664 -71.730966) (xy 182.481077 -71.709621)
			(xy 182.40284 -71.680829) (xy 182.327641 -71.644843) (xy 182.256139 -71.601979) (xy 182.188961 -71.552613)
			(xy 182.126697 -71.497177) (xy 182.069893 -71.436159) (xy 182.019047 -71.370094) (xy 181.974606 -71.299562)
			(xy 181.936959 -71.22518) (xy 181.906437 -71.147602) (xy 181.883308 -71.067509) (xy 181.867774 -70.985603)
			(xy 181.859972 -70.902603) (xy 181.859428 -70.86092) (xy 181.859428 -70.860158) (xy 181.86002 -70.814912)
			(xy 181.869266 -70.724893) (xy 181.887598 -70.636276) (xy 181.914826 -70.549977) (xy 181.950669 -70.466885)
			(xy 181.972204 -70.427088) (xy 181.974998 -70.422008) (xy 181.9783 -70.411594) (xy 181.978554 -70.406006)
			(xy 181.97879 -70.400576) (xy 181.977247 -70.389819) (xy 181.975506 -70.38467) (xy 181.948074 -70.311518)
			(xy 181.945978 -70.306423) (xy 181.939956 -70.2972) (xy 181.936136 -70.29323) (xy 181.928262 -70.28561)
			(xy 181.917594 -70.2818) (xy 181.878121 -70.267251) (xy 181.801861 -70.231718) (xy 181.729298 -70.189141)
			(xy 181.661079 -70.139902) (xy 181.597817 -70.08444) (xy 181.540074 -70.023252) (xy 181.488369 -69.956883)
			(xy 181.443162 -69.885929) (xy 181.404859 -69.811022) (xy 181.373801 -69.732832) (xy 181.350266 -69.652059)
			(xy 181.334464 -69.569424) (xy 181.326538 -69.485666) (xy 181.326028 -69.4436) (xy 181.326488 -69.402497)
			(xy 181.334073 -69.320643) (xy 181.349179 -69.239838) (xy 181.371676 -69.160771) (xy 181.401373 -69.084117)
			(xy 181.438015 -69.010531) (xy 181.481292 -68.940639) (xy 181.530833 -68.875039) (xy 181.586215 -68.814289)
			(xy 181.646966 -68.75891) (xy 181.712569 -68.709371) (xy 181.782462 -68.666098) (xy 181.85605 -68.629458)
			(xy 181.932705 -68.599764) (xy 182.011773 -68.577271) (xy 182.092579 -68.562168) (xy 182.174433 -68.554586)
			(xy 182.215536 -68.554092) (xy 182.216298 -68.554092) (xy 182.256184 -68.554537) (xy 182.335635 -68.561679)
			(xy 182.414128 -68.575904) (xy 182.491032 -68.5971) (xy 182.56573 -68.625095) (xy 182.60187 -68.641976)
			(xy 182.60695 -68.644516) (xy 182.61965 -68.64731) (xy 182.629383 -68.649029) (xy 182.648854 -68.645756)
			(xy 182.657496 -68.64096) (xy 182.72887 -68.59651) (xy 182.736037 -68.591681) (xy 182.746882 -68.578241)
			(xy 182.752654 -68.561964) (xy 182.753 -68.55333) (xy 182.753 -68.072) (xy 182.753521 -68.03874)
			(xy 182.762209 -67.97279) (xy 182.779434 -67.908539) (xy 182.804903 -67.847088) (xy 182.838179 -67.789489)
			(xy 182.878692 -67.736729) (xy 182.901844 -67.712844) (xy 183.536844 -67.077844) (xy 183.560724 -67.054688)
			(xy 183.613488 -67.014182) (xy 183.671089 -66.980911) (xy 183.73254 -66.955447) (xy 183.796791 -66.938225)
			(xy 183.862741 -66.929539) (xy 183.896 -66.929) (xy 185.801 -66.929) (xy 185.83426 -66.929521) (xy 185.90021 -66.938209)
			(xy 185.964461 -66.955434) (xy 186.025912 -66.980903) (xy 186.083511 -67.014179) (xy 186.136271 -67.054692)
			(xy 186.160156 -67.077844) (xy 187.176156 -68.093844) (xy 187.199312 -68.117724) (xy 187.239818 -68.170488)
			(xy 187.273089 -68.228089) (xy 187.298553 -68.28954) (xy 187.315775 -68.353791) (xy 187.324461 -68.419741)
			(xy 187.325 -68.453) (xy 187.325 -77.613002) (xy 187.325195 -77.619669) (xy 187.328671 -77.632542)
			(xy 187.331858 -77.638402) (xy 187.351125 -77.672361) (xy 187.38432 -77.743038) (xy 187.411192 -77.816352)
			(xy 187.431535 -77.891739) (xy 187.445192 -77.968619) (xy 187.452059 -78.0464) (xy 187.452508 -78.085442)
			(xy 187.452508 -78.08595) (xy 187.45207 -78.125049) (xy 187.445183 -78.202944) (xy 187.431492 -78.279934)
			(xy 187.411102 -78.355428) (xy 187.384171 -78.428843) (xy 187.367926 -78.46441) (xy 187.36369 -78.474797)
			(xy 187.36369 -78.497203) (xy 187.367926 -78.50759) (xy 187.384189 -78.543151) (xy 187.411141 -78.616561)
			(xy 187.431539 -78.692056) (xy 187.445228 -78.76905) (xy 187.452102 -78.846949) (xy 187.452508 -78.88605)
			(xy 187.452508 -78.886558) (xy 187.452075 -78.9256) (xy 187.445207 -79.003382) (xy 187.431547 -79.080262)
			(xy 187.4112 -79.155649) (xy 187.384321 -79.228961) (xy 187.35112 -79.299635) (xy 187.331858 -79.333598)
			(xy 187.328709 -79.339474) (xy 187.325224 -79.352336) (xy 187.325 -79.358998) (xy 187.325 -79.710114)
			(xy 205.177635 -79.710114) (xy 205.177635 -79.539758) (xy 205.18562 -79.36959) (xy 205.201572 -79.199983)
			(xy 205.225457 -79.031311) (xy 205.257221 -78.863943) (xy 205.296796 -78.698248) (xy 205.344093 -78.53459)
			(xy 205.39901 -78.373329) (xy 205.461425 -78.214819) (xy 205.531201 -78.059409) (xy 205.608184 -77.907441)
			(xy 205.692206 -77.759247) (xy 205.783082 -77.615155) (xy 205.880612 -77.475481) (xy 205.984582 -77.340532)
			(xy 206.094763 -77.210604) (xy 206.210912 -77.085984) (xy 206.332776 -76.966945) (xy 206.460084 -76.853749)
			(xy 206.592559 -76.746644) (xy 206.729909 -76.645867) (xy 206.871831 -76.551638) (xy 207.018013 -76.464165)
			(xy 207.168136 -76.38364) (xy 207.321867 -76.31024) (xy 207.47887 -76.244126) (xy 207.6388 -76.185444)
			(xy 207.801304 -76.134323) (xy 207.966025 -76.090875) (xy 208.132603 -76.055196) (xy 208.300669 -76.027364)
			(xy 208.469855 -76.00744) (xy 208.639789 -75.995468) (xy 208.810098 -75.991475) (xy 208.980407 -75.995468)
			(xy 209.150341 -76.00744) (xy 209.319527 -76.027364) (xy 209.487593 -76.055196) (xy 209.654171 -76.090875)
			(xy 209.818892 -76.134323) (xy 209.981396 -76.185444) (xy 210.141326 -76.244126) (xy 210.298329 -76.31024)
			(xy 210.45206 -76.38364) (xy 210.602183 -76.464165) (xy 210.748365 -76.551638) (xy 210.890287 -76.645867)
			(xy 211.027637 -76.746644) (xy 211.160112 -76.853749) (xy 211.28742 -76.966945) (xy 211.409284 -77.085984)
			(xy 211.525433 -77.210604) (xy 211.635614 -77.340532) (xy 211.739584 -77.475481) (xy 211.837114 -77.615155)
			(xy 211.92799 -77.759247) (xy 212.012012 -77.907441) (xy 212.088995 -78.059409) (xy 212.158771 -78.214819)
			(xy 212.221186 -78.373329) (xy 212.276103 -78.53459) (xy 212.3234 -78.698248) (xy 212.362975 -78.863943)
			(xy 212.394739 -79.031311) (xy 212.418624 -79.199983) (xy 212.434576 -79.36959) (xy 212.442561 -79.539758)
			(xy 212.44306 -79.624936) (xy 212.442561 -79.710114) (xy 235.177575 -79.710114) (xy 235.177575 -79.539758)
			(xy 235.18556 -79.36959) (xy 235.201512 -79.199983) (xy 235.225397 -79.031311) (xy 235.257161 -78.863943)
			(xy 235.296736 -78.698248) (xy 235.344033 -78.53459) (xy 235.39895 -78.373329) (xy 235.461365 -78.214819)
			(xy 235.531141 -78.059409) (xy 235.608124 -77.907441) (xy 235.692146 -77.759247) (xy 235.783022 -77.615155)
			(xy 235.880552 -77.475481) (xy 235.984522 -77.340532) (xy 236.094703 -77.210604) (xy 236.210852 -77.085984)
			(xy 236.332716 -76.966945) (xy 236.460024 -76.853749) (xy 236.592499 -76.746644) (xy 236.729849 -76.645867)
			(xy 236.871771 -76.551638) (xy 237.017953 -76.464165) (xy 237.168076 -76.38364) (xy 237.321807 -76.31024)
			(xy 237.47881 -76.244126) (xy 237.63874 -76.185444) (xy 237.801244 -76.134323) (xy 237.965965 -76.090875)
			(xy 238.132543 -76.055196) (xy 238.300609 -76.027364) (xy 238.469795 -76.00744) (xy 238.639729 -75.995468)
			(xy 238.810038 -75.991475) (xy 238.980347 -75.995468) (xy 239.150281 -76.00744) (xy 239.319467 -76.027364)
			(xy 239.487533 -76.055196) (xy 239.654111 -76.090875) (xy 239.818832 -76.134323) (xy 239.981336 -76.185444)
			(xy 240.141266 -76.244126) (xy 240.298269 -76.31024) (xy 240.452 -76.38364) (xy 240.602123 -76.464165)
			(xy 240.748305 -76.551638) (xy 240.890227 -76.645867) (xy 241.027577 -76.746644) (xy 241.160052 -76.853749)
			(xy 241.28736 -76.966945) (xy 241.409224 -77.085984) (xy 241.525373 -77.210604) (xy 241.635554 -77.340532)
			(xy 241.739524 -77.475481) (xy 241.837054 -77.615155) (xy 241.92793 -77.759247) (xy 242.011952 -77.907441)
			(xy 242.088935 -78.059409) (xy 242.158711 -78.214819) (xy 242.221126 -78.373329) (xy 242.276043 -78.53459)
			(xy 242.32334 -78.698248) (xy 242.362915 -78.863943) (xy 242.394679 -79.031311) (xy 242.418564 -79.199983)
			(xy 242.434516 -79.36959) (xy 242.442501 -79.539758) (xy 242.443 -79.624936) (xy 242.442501 -79.710114)
			(xy 242.434516 -79.880282) (xy 242.418564 -80.049889) (xy 242.394679 -80.218561) (xy 242.362915 -80.385929)
			(xy 242.32334 -80.551624) (xy 242.276043 -80.715282) (xy 242.221126 -80.876543) (xy 242.158711 -81.035053)
			(xy 242.088935 -81.190463) (xy 242.011952 -81.342431) (xy 241.92793 -81.490625) (xy 241.837054 -81.634717)
			(xy 241.739524 -81.774391) (xy 241.635554 -81.90934) (xy 241.525373 -82.039268) (xy 241.409224 -82.163888)
			(xy 241.28736 -82.282927) (xy 241.160052 -82.396123) (xy 241.027577 -82.503228) (xy 240.890227 -82.604005)
			(xy 240.748305 -82.698234) (xy 240.602123 -82.785707) (xy 240.452 -82.866232) (xy 240.298269 -82.939632)
			(xy 240.141266 -83.005746) (xy 239.981336 -83.064428) (xy 239.818832 -83.115549) (xy 239.654111 -83.158997)
			(xy 239.487533 -83.194676) (xy 239.319467 -83.222508) (xy 239.150281 -83.242432) (xy 238.980347 -83.254404)
			(xy 238.810038 -83.258398) (xy 238.639729 -83.254404) (xy 238.469795 -83.242432) (xy 238.300609 -83.222508)
			(xy 238.132543 -83.194676) (xy 237.965965 -83.158997) (xy 237.801244 -83.115549) (xy 237.63874 -83.064428)
			(xy 237.47881 -83.005746) (xy 237.321807 -82.939632) (xy 237.168076 -82.866232) (xy 237.017953 -82.785707)
			(xy 236.871771 -82.698234) (xy 236.729849 -82.604005) (xy 236.592499 -82.503228) (xy 236.460024 -82.396123)
			(xy 236.332716 -82.282927) (xy 236.210852 -82.163888) (xy 236.094703 -82.039268) (xy 235.984522 -81.90934)
			(xy 235.880552 -81.774391) (xy 235.783022 -81.634717) (xy 235.692146 -81.490625) (xy 235.608124 -81.342431)
			(xy 235.531141 -81.190463) (xy 235.461365 -81.035053) (xy 235.39895 -80.876543) (xy 235.344033 -80.715282)
			(xy 235.296736 -80.551624) (xy 235.257161 -80.385929) (xy 235.225397 -80.218561) (xy 235.201512 -80.049889)
			(xy 235.18556 -79.880282) (xy 235.177575 -79.710114) (xy 212.442561 -79.710114) (xy 212.434576 -79.880282)
			(xy 212.418624 -80.049889) (xy 212.394739 -80.218561) (xy 212.362975 -80.385929) (xy 212.3234 -80.551624)
			(xy 212.276103 -80.715282) (xy 212.221186 -80.876543) (xy 212.158771 -81.035053) (xy 212.088995 -81.190463)
			(xy 212.012012 -81.342431) (xy 211.92799 -81.490625) (xy 211.837114 -81.634717) (xy 211.739584 -81.774391)
			(xy 211.635614 -81.90934) (xy 211.525433 -82.039268) (xy 211.409284 -82.163888) (xy 211.28742 -82.282927)
			(xy 211.160112 -82.396123) (xy 211.027637 -82.503228) (xy 210.890287 -82.604005) (xy 210.748365 -82.698234)
			(xy 210.602183 -82.785707) (xy 210.45206 -82.866232) (xy 210.298329 -82.939632) (xy 210.141326 -83.005746)
			(xy 209.981396 -83.064428) (xy 209.818892 -83.115549) (xy 209.654171 -83.158997) (xy 209.487593 -83.194676)
			(xy 209.319527 -83.222508) (xy 209.150341 -83.242432) (xy 208.980407 -83.254404) (xy 208.810098 -83.258398)
			(xy 208.639789 -83.254404) (xy 208.469855 -83.242432) (xy 208.300669 -83.222508) (xy 208.132603 -83.194676)
			(xy 207.966025 -83.158997) (xy 207.801304 -83.115549) (xy 207.6388 -83.064428) (xy 207.47887 -83.005746)
			(xy 207.321867 -82.939632) (xy 207.168136 -82.866232) (xy 207.018013 -82.785707) (xy 206.871831 -82.698234)
			(xy 206.729909 -82.604005) (xy 206.592559 -82.503228) (xy 206.460084 -82.396123) (xy 206.332776 -82.282927)
			(xy 206.210912 -82.163888) (xy 206.094763 -82.039268) (xy 205.984582 -81.90934) (xy 205.880612 -81.774391)
			(xy 205.783082 -81.634717) (xy 205.692206 -81.490625) (xy 205.608184 -81.342431) (xy 205.531201 -81.190463)
			(xy 205.461425 -81.035053) (xy 205.39901 -80.876543) (xy 205.344093 -80.715282) (xy 205.296796 -80.551624)
			(xy 205.257221 -80.385929) (xy 205.225457 -80.218561) (xy 205.201572 -80.049889) (xy 205.18562 -79.880282)
			(xy 205.177635 -79.710114) (xy 187.325 -79.710114) (xy 187.325 -83.439) (xy 187.324479 -83.47226)
			(xy 187.315791 -83.53821) (xy 187.298566 -83.602461) (xy 187.273097 -83.663912) (xy 187.239821 -83.721511)
			(xy 187.199308 -83.774271) (xy 187.176156 -83.798156) (xy 185.487056 -85.487256) (xy 185.463176 -85.510412)
			(xy 185.410412 -85.550918) (xy 185.352811 -85.584189) (xy 185.29136 -85.609653) (xy 185.227109 -85.626875)
			(xy 185.161159 -85.635561) (xy 185.1279 -85.6361) (xy 161.503614 -85.6361) (xy 161.493653 -85.63659)
			(xy 161.475234 -85.644183) (xy 161.4678 -85.650832) (xy 161.461958 -85.657944) (xy 161.41446 -85.72627)
			(xy 161.411091 -85.731453) (xy 161.406729 -85.743015) (xy 161.405824 -85.74913) (xy 161.4043 -85.761322)
			(xy 161.408618 -85.773006) (xy 161.422069 -85.810334) (xy 161.443065 -85.886856) (xy 161.457174 -85.964942)
			(xy 161.464286 -86.043973) (xy 161.464752 -86.083648) (xy 161.464752 -86.084918) (xy 161.464248 -86.127266)
			(xy 161.456197 -86.21158) (xy 161.440168 -86.294746) (xy 161.416307 -86.376013) (xy 161.384828 -86.454643)
			(xy 161.346017 -86.529924) (xy 161.300227 -86.601176) (xy 161.247871 -86.667752) (xy 161.189423 -86.72905)
			(xy 161.125413 -86.784515) (xy 161.056421 -86.833644) (xy 160.983071 -86.875993) (xy 160.906028 -86.911177)
			(xy 160.825989 -86.938879) (xy 160.74368 -86.958847) (xy 160.659845 -86.9709) (xy 160.575244 -86.974931)
			(xy 160.490643 -86.9709) (xy 160.406808 -86.958847) (xy 160.324499 -86.938879) (xy 160.24446 -86.911177)
			(xy 160.167417 -86.875993) (xy 160.094067 -86.833644) (xy 160.025075 -86.784515) (xy 159.961065 -86.72905)
			(xy 159.902617 -86.667752) (xy 159.850261 -86.601176) (xy 159.804471 -86.529924) (xy 159.76566 -86.454643)
			(xy 159.734181 -86.376013) (xy 159.71032 -86.294746) (xy 159.694291 -86.21158) (xy 159.68624 -86.127266)
			(xy 159.685736 -86.084918) (xy 159.685736 -86.083648) (xy 159.686181 -86.043972) (xy 159.693273 -85.964937)
			(xy 159.707387 -85.886849) (xy 159.728409 -85.810332) (xy 159.74187 -85.773006) (xy 159.743846 -85.767256)
			(xy 159.745248 -85.755182) (xy 159.744664 -85.74913) (xy 159.74314 -85.736684) (xy 159.68853 -85.657944)
			(xy 159.682688 -85.650832) (xy 159.675279 -85.644146) (xy 159.656843 -85.636564) (xy 159.646874 -85.6361)
			(xy 136.28624 -85.6361) (xy 136.28135 -85.636237) (xy 136.271758 -85.638157) (xy 136.26719 -85.63991)
			(xy 136.257538 -85.64372) (xy 136.250426 -85.651086) (xy 133.556756 -88.344756) (xy 133.532876 -88.367912)
			(xy 133.480112 -88.408418) (xy 133.422511 -88.441689) (xy 133.36106 -88.467153) (xy 133.296809 -88.484375)
			(xy 133.230859 -88.493061) (xy 133.1976 -88.4936) (xy 126.7587 -88.4936) (xy 126.72544 -88.493079)
			(xy 126.65949 -88.484391) (xy 126.595239 -88.467166) (xy 126.533788 -88.441697) (xy 126.476189 -88.408421)
			(xy 126.423429 -88.367908) (xy 126.399544 -88.344756) (xy 123.705874 -85.651086) (xy 123.700286 -85.64626)
			(xy 123.693546 -85.641591) (xy 123.678 -85.636407) (xy 123.669806 -85.6361) (xy 115.264184 -85.6361)
			(xy 115.254178 -85.636591) (xy 115.235692 -85.644253) (xy 115.221544 -85.658406) (xy 115.213888 -85.676894)
			(xy 115.213384 -85.6869) (xy 115.213384 -96.308361) (xy 157.479742 -96.308361) (xy 157.479742 -96.223639)
			(xy 157.487795 -96.139302) (xy 157.503829 -96.056112) (xy 157.527697 -95.974822) (xy 157.559185 -95.89617)
			(xy 157.598007 -95.820867) (xy 157.64381 -95.749595) (xy 157.696181 -95.682999) (xy 157.754646 -95.621684)
			(xy 157.818674 -95.566203) (xy 157.887686 -95.51706) (xy 157.961056 -95.4747) (xy 158.038121 -95.439505)
			(xy 158.118183 -95.411796) (xy 158.200516 -95.391822) (xy 158.284375 -95.379765) (xy 158.369 -95.375734)
			(xy 158.453625 -95.379765) (xy 158.537484 -95.391822) (xy 158.619817 -95.411796) (xy 158.699879 -95.439505)
			(xy 158.776944 -95.4747) (xy 158.850314 -95.51706) (xy 158.919326 -95.566203) (xy 158.983354 -95.621684)
			(xy 159.041819 -95.682999) (xy 159.09419 -95.749595) (xy 159.139993 -95.820867) (xy 159.178815 -95.89617)
			(xy 159.210303 -95.974822) (xy 159.234171 -96.056112) (xy 159.250205 -96.139302) (xy 159.258258 -96.223639)
			(xy 159.258762 -96.266) (xy 159.258258 -96.308361) (xy 159.250205 -96.392698) (xy 159.234171 -96.475888)
			(xy 159.210303 -96.557178) (xy 159.178815 -96.63583) (xy 159.139993 -96.711133) (xy 159.09419 -96.782405)
			(xy 159.041819 -96.849001) (xy 158.983354 -96.910316) (xy 158.919326 -96.965797) (xy 158.850314 -97.01494)
			(xy 158.776944 -97.0573) (xy 158.699879 -97.092495) (xy 158.619817 -97.120204) (xy 158.537484 -97.140178)
			(xy 158.453625 -97.152235) (xy 158.369 -97.156267) (xy 158.284375 -97.152235) (xy 158.200516 -97.140178)
			(xy 158.118183 -97.120204) (xy 158.038121 -97.092495) (xy 157.961056 -97.0573) (xy 157.887686 -97.01494)
			(xy 157.818674 -96.965797) (xy 157.754646 -96.910316) (xy 157.696181 -96.849001) (xy 157.64381 -96.782405)
			(xy 157.598007 -96.711133) (xy 157.559185 -96.63583) (xy 157.527697 -96.557178) (xy 157.503829 -96.475888)
			(xy 157.487795 -96.392698) (xy 157.479742 -96.308361) (xy 115.213384 -96.308361) (xy 115.213384 -101.933248)
			(xy 115.21388 -101.94325) (xy 115.221547 -101.961729) (xy 115.235698 -101.975871) (xy 115.254181 -101.983526)
			(xy 115.264184 -101.984048)
		)
		(stroke
			(width 0)
			(type solid)
		)
		(fill yes)
		(layer "In4.Cu")
		(net "GND")
	)
	(gr_poly
		(pts
			(xy 38.423596 -170.633898) (xy 38.434128 -170.633372) (xy 38.453415 -170.624903) (xy 38.467668 -170.609393)
			(xy 38.471602 -170.599608) (xy 38.471602 -170.599354) (xy 38.485985 -170.55869) (xy 38.521557 -170.480107)
			(xy 38.564563 -170.405333) (xy 38.6146 -170.33507) (xy 38.671199 -170.269976) (xy 38.733828 -170.210662)
			(xy 38.801901 -170.157683) (xy 38.87478 -170.111538) (xy 38.95178 -170.072658) (xy 38.991794 -170.056556)
			(xy 39.00551 -170.051222) (xy 39.023036 -170.027854) (xy 39.031672 -169.922444) (xy 39.032088 -169.912898)
			(xy 39.026626 -169.894603) (xy 39.014824 -169.879595) (xy 39.00678 -169.874438) (xy 38.965393 -169.849379)
			(xy 38.886327 -169.7936) (xy 38.811952 -169.731703) (xy 38.742742 -169.664083) (xy 38.679134 -169.591166)
			(xy 38.621533 -169.513418) (xy 38.570304 -169.431331) (xy 38.525773 -169.345426) (xy 38.488222 -169.256248)
			(xy 38.45789 -169.164364) (xy 38.434969 -169.070357) (xy 38.419604 -168.974824) (xy 38.411894 -168.87837)
			(xy 38.411404 -168.82999) (xy 38.411871 -168.782334) (xy 38.419347 -168.687315) (xy 38.43425 -168.593174)
			(xy 38.456491 -168.500493) (xy 38.485931 -168.409841) (xy 38.522389 -168.321776) (xy 38.565641 -168.236843)
			(xy 38.615421 -168.155562) (xy 38.671421 -168.078436) (xy 38.733298 -168.005939) (xy 38.800668 -167.938517)
			(xy 38.8366 -167.907208) (xy 38.844625 -167.899637) (xy 38.853848 -167.87962) (xy 38.85438 -167.8686)
			(xy 38.85438 -167.791384) (xy 38.853836 -167.780368) (xy 38.84461 -167.76036) (xy 38.8366 -167.752776)
			(xy 38.798977 -167.719952) (xy 38.728658 -167.649058) (xy 38.664401 -167.572628) (xy 38.60664 -167.491177)
			(xy 38.555765 -167.405256) (xy 38.512122 -167.315445) (xy 38.476004 -167.222353) (xy 38.447655 -167.126609)
			(xy 38.427269 -167.028859) (xy 38.414982 -166.929765) (xy 38.410877 -166.829996) (xy 38.414982 -166.730227)
			(xy 38.42727 -166.631133) (xy 38.447657 -166.533384) (xy 38.476006 -166.437639) (xy 38.512125 -166.344547)
			(xy 38.555769 -166.254738) (xy 38.606644 -166.168817) (xy 38.664405 -166.087366) (xy 38.728663 -166.010936)
			(xy 38.798983 -165.940043) (xy 38.8366 -165.907212) (xy 38.844626 -165.899641) (xy 38.853851 -165.879624)
			(xy 38.85438 -165.868604) (xy 38.85438 -165.791388) (xy 38.853837 -165.780371) (xy 38.844612 -165.760362)
			(xy 38.8366 -165.75278) (xy 38.798977 -165.719956) (xy 38.728658 -165.649062) (xy 38.6644 -165.572632)
			(xy 38.606638 -165.49118) (xy 38.555764 -165.405259) (xy 38.51212 -165.315449) (xy 38.476001 -165.222357)
			(xy 38.447653 -165.126612) (xy 38.427266 -165.028862) (xy 38.414979 -164.929768) (xy 38.410874 -164.829999)
			(xy 38.414979 -164.73023) (xy 38.427267 -164.631135) (xy 38.447654 -164.533385) (xy 38.476002 -164.437641)
			(xy 38.512121 -164.344549) (xy 38.555765 -164.254738) (xy 38.60664 -164.168817) (xy 38.664401 -164.087366)
			(xy 38.728659 -164.010936) (xy 38.798979 -163.940043) (xy 38.8366 -163.907216) (xy 38.844626 -163.899645)
			(xy 38.853853 -163.879628) (xy 38.85438 -163.868608) (xy 38.85438 -163.791392) (xy 38.853837 -163.780375)
			(xy 38.844614 -163.760364) (xy 38.8366 -163.752784) (xy 38.798977 -163.71996) (xy 38.728657 -163.649066)
			(xy 38.664399 -163.572636) (xy 38.606637 -163.491184) (xy 38.555762 -163.405263) (xy 38.512118 -163.315453)
			(xy 38.475999 -163.22236) (xy 38.447651 -163.126615) (xy 38.427264 -163.028865) (xy 38.414976 -162.92977)
			(xy 38.410871 -162.830001) (xy 38.414976 -162.730232) (xy 38.427263 -162.631137) (xy 38.44765 -162.533387)
			(xy 38.475999 -162.437642) (xy 38.512117 -162.34455) (xy 38.555761 -162.254739) (xy 38.606636 -162.168818)
			(xy 38.664397 -162.087366) (xy 38.728655 -162.010936) (xy 38.798975 -161.940042) (xy 38.8366 -161.90722)
			(xy 38.844627 -161.899649) (xy 38.853855 -161.879633) (xy 38.85438 -161.868612) (xy 38.85438 -161.791396)
			(xy 38.853838 -161.780379) (xy 38.844616 -161.760367) (xy 38.8366 -161.752788) (xy 38.798977 -161.719964)
			(xy 38.728657 -161.64907) (xy 38.664398 -161.57264) (xy 38.606636 -161.491188) (xy 38.555761 -161.405267)
			(xy 38.512116 -161.315456) (xy 38.475997 -161.222364) (xy 38.447648 -161.126619) (xy 38.427261 -161.028868)
			(xy 38.414973 -160.929773) (xy 38.410868 -160.830004) (xy 38.414973 -160.730234) (xy 38.42726 -160.63114)
			(xy 38.447647 -160.533389) (xy 38.475995 -160.437644) (xy 38.512113 -160.344551) (xy 38.555757 -160.25474)
			(xy 38.606632 -160.168818) (xy 38.664393 -160.087367) (xy 38.728651 -160.010935) (xy 38.798971 -159.940042)
			(xy 38.8366 -159.907224) (xy 38.844628 -159.899654) (xy 38.853857 -159.879637) (xy 38.85438 -159.868616)
			(xy 38.85438 -159.7914) (xy 38.853839 -159.780382) (xy 38.844618 -159.760369) (xy 38.8366 -159.752792)
			(xy 38.798976 -159.719968) (xy 38.728656 -159.649074) (xy 38.664397 -159.572643) (xy 38.606635 -159.491192)
			(xy 38.555759 -159.40527) (xy 38.512115 -159.31546) (xy 38.475995 -159.222367) (xy 38.447646 -159.126622)
			(xy 38.427259 -159.028871) (xy 38.41497 -158.929776) (xy 38.410865 -158.830007) (xy 38.414969 -158.730237)
			(xy 38.427256 -158.631142) (xy 38.447643 -158.533391) (xy 38.475991 -158.437645) (xy 38.512109 -158.344552)
			(xy 38.555753 -158.254741) (xy 38.606628 -158.168819) (xy 38.664389 -158.087367) (xy 38.728647 -158.010935)
			(xy 38.798967 -157.940041) (xy 38.8366 -157.907228) (xy 38.844629 -157.899658) (xy 38.85386 -157.879641)
			(xy 38.85438 -157.86862) (xy 38.85438 -157.791404) (xy 38.85384 -157.780386) (xy 38.844619 -157.760372)
			(xy 38.8366 -157.752796) (xy 38.798976 -157.719972) (xy 38.728656 -157.649078) (xy 38.664397 -157.572647)
			(xy 38.606634 -157.491196) (xy 38.555758 -157.405274) (xy 38.512113 -157.315463) (xy 38.475993 -157.222371)
			(xy 38.447644 -157.126625) (xy 38.427256 -157.028874) (xy 38.414968 -156.929779) (xy 38.410862 -156.830009)
			(xy 38.414966 -156.730239) (xy 38.427253 -156.631144) (xy 38.447639 -156.533393) (xy 38.475987 -156.437647)
			(xy 38.512106 -156.344553) (xy 38.555749 -156.254742) (xy 38.606624 -156.168819) (xy 38.664385 -156.087367)
			(xy 38.728643 -156.010935) (xy 38.798963 -155.940041) (xy 38.8366 -155.907232) (xy 38.844629 -155.899662)
			(xy 38.853862 -155.879645) (xy 38.85438 -155.868624) (xy 38.85438 -155.791408) (xy 38.853841 -155.780389)
			(xy 38.844621 -155.760374) (xy 38.8366 -155.7528) (xy 38.798976 -155.719976) (xy 38.728655 -155.649082)
			(xy 38.664396 -155.572651) (xy 38.606633 -155.4912) (xy 38.555757 -155.405278) (xy 38.512111 -155.315467)
			(xy 38.475991 -155.222374) (xy 38.447642 -155.126628) (xy 38.427253 -155.028877) (xy 38.414965 -154.929782)
			(xy 38.410859 -154.830012) (xy 38.414963 -154.730242) (xy 38.42725 -154.631146) (xy 38.447636 -154.533394)
			(xy 38.475984 -154.437648) (xy 38.512102 -154.344554) (xy 38.555745 -154.254743) (xy 38.60662 -154.16882)
			(xy 38.664381 -154.087367) (xy 38.728639 -154.010935) (xy 38.798959 -153.94004) (xy 38.8366 -153.907236)
			(xy 38.84463 -153.899666) (xy 38.853864 -153.87965) (xy 38.85438 -153.868628) (xy 38.85438 -153.791412)
			(xy 38.853841 -153.780393) (xy 38.844623 -153.760376) (xy 38.8366 -153.752804) (xy 38.800676 -153.721486)
			(xy 38.7333 -153.654069) (xy 38.67142 -153.581575) (xy 38.615417 -153.504451) (xy 38.565636 -153.423172)
			(xy 38.522383 -153.338238) (xy 38.485925 -153.250174) (xy 38.456486 -153.159521) (xy 38.434249 -153.066839)
			(xy 38.419349 -152.972698) (xy 38.41188 -152.877678) (xy 38.411404 -152.830022) (xy 38.411921 -152.779843)
			(xy 38.420206 -152.679828) (xy 38.43672 -152.580839) (xy 38.461351 -152.483551) (xy 38.493931 -152.388629)
			(xy 38.534238 -152.296721) (xy 38.581995 -152.208455) (xy 38.636877 -152.124434) (xy 38.698509 -152.045231)
			(xy 38.766471 -151.971387) (xy 38.840297 -151.903407) (xy 38.919485 -151.841755) (xy 39.003492 -151.786852)
			(xy 39.091746 -151.739072) (xy 39.183644 -151.698743) (xy 39.278557 -151.666139) (xy 39.375839 -151.641483)
			(xy 39.474824 -151.624944) (xy 39.574837 -151.616634) (xy 39.625016 -151.616156) (xy 39.672677 -151.616635)
			(xy 39.767703 -151.624135) (xy 39.861849 -151.639064) (xy 39.954534 -151.661329) (xy 40.045188 -151.690794)
			(xy 40.133251 -151.727277) (xy 40.218183 -151.770554) (xy 40.299459 -151.820358) (xy 40.37658 -151.876382)
			(xy 40.44907 -151.938281) (xy 40.516482 -152.005674) (xy 40.547798 -152.041606) (xy 40.55537 -152.049629)
			(xy 40.575387 -152.058849) (xy 40.586406 -152.059386) (xy 40.663622 -152.059386) (xy 40.674638 -152.058841)
			(xy 40.694645 -152.049615) (xy 40.70223 -152.041606) (xy 40.73354 -152.005667) (xy 40.800944 -151.938261)
			(xy 40.873428 -151.876352) (xy 40.950546 -151.820319) (xy 41.031822 -151.77051) (xy 41.116755 -151.72723)
			(xy 41.204822 -151.690747) (xy 41.29548 -151.661286) (xy 41.388169 -151.639028) (xy 41.482319 -151.62411)
			(xy 41.57735 -151.616624) (xy 41.625012 -151.616156) (xy 41.675179 -151.616674) (xy 41.775172 -151.62496)
			(xy 41.874138 -151.641473) (xy 41.971404 -151.666101) (xy 42.066303 -151.698675) (xy 42.158189 -151.738974)
			(xy 42.246435 -151.786722) (xy 42.330436 -151.841594) (xy 42.40962 -151.903213) (xy 42.483446 -151.97116)
			(xy 42.55141 -152.044971) (xy 42.613047 -152.124141) (xy 42.667937 -152.20813) (xy 42.715705 -152.296364)
			(xy 42.756025 -152.388241) (xy 42.788621 -152.483134) (xy 42.813271 -152.580393) (xy 42.829806 -152.679356)
			(xy 42.838114 -152.779347) (xy 42.838624 -152.829514) (xy 42.838624 -152.830022) (xy 42.838156 -152.877678)
			(xy 42.83068 -152.972697) (xy 42.815776 -153.066837) (xy 42.793535 -153.159519) (xy 42.764095 -153.250171)
			(xy 42.727637 -153.338235) (xy 42.684385 -153.423168) (xy 42.634605 -153.504449) (xy 42.578605 -153.581575)
			(xy 42.51673 -153.654073) (xy 42.44936 -153.721495) (xy 42.413428 -153.752804) (xy 42.405401 -153.760374)
			(xy 42.396178 -153.780392) (xy 42.395648 -153.791412) (xy 42.395648 -153.868628) (xy 42.396192 -153.879645)
			(xy 42.405412 -153.899658) (xy 42.413428 -153.907236) (xy 42.451052 -153.940059) (xy 42.521374 -154.01095)
			(xy 42.585634 -154.08738) (xy 42.643398 -154.16883) (xy 42.694274 -154.25475) (xy 42.73792 -154.34456)
			(xy 42.774039 -154.437652) (xy 42.802388 -154.533397) (xy 42.822776 -154.631148) (xy 42.835063 -154.730242)
			(xy 42.839167 -154.830012) (xy 42.835061 -154.929781) (xy 42.822772 -155.028875) (xy 42.802383 -155.126625)
			(xy 42.774032 -155.22237) (xy 42.737911 -155.315461) (xy 42.694263 -155.40527) (xy 42.643385 -155.49119)
			(xy 42.58562 -155.572639) (xy 42.521359 -155.649067) (xy 42.451035 -155.719957) (xy 42.413428 -155.7528)
			(xy 42.4054 -155.76037) (xy 42.396175 -155.780387) (xy 42.395648 -155.791408) (xy 42.395648 -155.868624)
			(xy 42.396191 -155.879642) (xy 42.40541 -155.899656) (xy 42.413428 -155.907232) (xy 42.451053 -155.940055)
			(xy 42.521375 -156.010946) (xy 42.585635 -156.087376) (xy 42.643399 -156.168826) (xy 42.694276 -156.254747)
			(xy 42.737922 -156.344557) (xy 42.774041 -156.437649) (xy 42.802391 -156.533394) (xy 42.822778 -156.631145)
			(xy 42.835066 -156.73024) (xy 42.83917 -156.830009) (xy 42.835064 -156.929779) (xy 42.822775 -157.028873)
			(xy 42.802386 -157.126624) (xy 42.774036 -157.222368) (xy 42.737914 -157.31546) (xy 42.694267 -157.405269)
			(xy 42.643389 -157.491189) (xy 42.585624 -157.572639) (xy 42.521363 -157.649067) (xy 42.451039 -157.719957)
			(xy 42.413428 -157.752796) (xy 42.4054 -157.760366) (xy 42.396173 -157.780383) (xy 42.395648 -157.791404)
			(xy 42.395648 -157.86862) (xy 42.396191 -157.879638) (xy 42.405408 -157.899654) (xy 42.413428 -157.907228)
			(xy 42.451053 -157.940051) (xy 42.521375 -158.010942) (xy 42.585636 -158.087372) (xy 42.6434 -158.168822)
			(xy 42.694277 -158.254743) (xy 42.737923 -158.344553) (xy 42.774043 -158.437645) (xy 42.802393 -158.533391)
			(xy 42.822781 -158.631141) (xy 42.835068 -158.730237) (xy 42.839173 -158.830006) (xy 42.835067 -158.929776)
			(xy 42.822779 -159.028871) (xy 42.80239 -159.126622) (xy 42.774039 -159.222367) (xy 42.737918 -159.315459)
			(xy 42.694271 -159.405269) (xy 42.643393 -159.491189) (xy 42.585628 -159.572639) (xy 42.537306 -159.63011)
			(xy 71.481963 -159.63011) (xy 71.48592 -159.520564) (xy 71.497772 -159.411589) (xy 71.517456 -159.303754)
			(xy 71.54487 -159.19762) (xy 71.579871 -159.09374) (xy 71.622277 -158.992657) (xy 71.671866 -158.894898)
			(xy 71.728379 -158.800971) (xy 71.791523 -158.711368) (xy 71.860968 -158.626554) (xy 71.936352 -158.546972)
			(xy 72.017282 -158.473037) (xy 72.103336 -158.405135) (xy 72.194065 -158.343619) (xy 72.288996 -158.288811)
			(xy 72.387635 -158.240995) (xy 72.489467 -158.200421) (xy 72.593961 -158.167301) (xy 72.700573 -158.141808)
			(xy 72.808746 -158.124074) (xy 72.917917 -158.114191) (xy 73.027517 -158.112212) (xy 73.136973 -158.118147)
			(xy 73.245717 -158.131964) (xy 73.353179 -158.153592) (xy 73.458801 -158.182918) (xy 73.562031 -158.219789)
			(xy 73.662332 -158.264012) (xy 73.759181 -158.315358) (xy 73.852071 -158.373558) (xy 73.94052 -158.438309)
			(xy 74.024067 -158.509274) (xy 74.102274 -158.586083) (xy 74.174736 -158.668334) (xy 74.241074 -158.7556)
			(xy 74.300941 -158.847424) (xy 74.354027 -158.94333) (xy 74.400054 -159.042816) (xy 74.438783 -159.145364)
			(xy 74.470011 -159.250439) (xy 74.493575 -159.357494) (xy 74.509354 -159.46597) (xy 74.517263 -159.575301)
			(xy 74.517758 -159.63011) (xy 74.517263 -159.684919) (xy 74.509354 -159.79425) (xy 74.493575 -159.902726)
			(xy 74.470011 -160.009781) (xy 74.438783 -160.114856) (xy 74.400054 -160.217404) (xy 74.354027 -160.31689)
			(xy 74.300941 -160.412796) (xy 74.241074 -160.50462) (xy 74.174736 -160.591886) (xy 74.102274 -160.674137)
			(xy 74.024067 -160.750946) (xy 73.94052 -160.821911) (xy 73.852071 -160.886662) (xy 73.759181 -160.944862)
			(xy 73.662332 -160.996208) (xy 73.562031 -161.040431) (xy 73.458801 -161.077302) (xy 73.353179 -161.106628)
			(xy 73.245717 -161.128256) (xy 73.136973 -161.142073) (xy 73.027517 -161.148008) (xy 72.917917 -161.146029)
			(xy 72.808746 -161.136146) (xy 72.700573 -161.118412) (xy 72.593961 -161.092919) (xy 72.489467 -161.059799)
			(xy 72.387635 -161.019225) (xy 72.288996 -160.971409) (xy 72.194065 -160.916601) (xy 72.103336 -160.855085)
			(xy 72.017282 -160.787183) (xy 71.936352 -160.713248) (xy 71.860968 -160.633666) (xy 71.791523 -160.548852)
			(xy 71.728379 -160.459249) (xy 71.671866 -160.365322) (xy 71.622277 -160.267563) (xy 71.579871 -160.16648)
			(xy 71.54487 -160.0626) (xy 71.517456 -159.956466) (xy 71.497772 -159.848631) (xy 71.48592 -159.739656)
			(xy 71.481963 -159.63011) (xy 42.537306 -159.63011) (xy 42.521367 -159.649067) (xy 42.451043 -159.719958)
			(xy 42.413428 -159.752792) (xy 42.405399 -159.760361) (xy 42.396171 -159.780379) (xy 42.395648 -159.7914)
			(xy 42.395648 -159.868616) (xy 42.39619 -159.879634) (xy 42.405406 -159.899651) (xy 42.413428 -159.907224)
			(xy 42.451053 -159.940047) (xy 42.521376 -160.010939) (xy 42.585637 -160.087368) (xy 42.643401 -160.168818)
			(xy 42.694279 -160.254739) (xy 42.737925 -160.344549) (xy 42.774045 -160.437642) (xy 42.802395 -160.533387)
			(xy 42.822783 -160.631138) (xy 42.835071 -160.730234) (xy 42.839176 -160.830004) (xy 42.835071 -160.929774)
			(xy 42.822782 -161.028869) (xy 42.802393 -161.12662) (xy 42.774043 -161.222365) (xy 42.737922 -161.315458)
			(xy 42.694275 -161.405268) (xy 42.643397 -161.491188) (xy 42.585632 -161.572638) (xy 42.521371 -161.649067)
			(xy 42.451047 -161.719958) (xy 42.413428 -161.752788) (xy 42.405398 -161.760357) (xy 42.396168 -161.780375)
			(xy 42.395648 -161.791396) (xy 42.395648 -161.868612) (xy 42.396189 -161.879631) (xy 42.405405 -161.899649)
			(xy 42.413428 -161.90722) (xy 42.451053 -161.940043) (xy 42.521376 -162.010935) (xy 42.585638 -162.087364)
			(xy 42.643402 -162.168814) (xy 42.69428 -162.254735) (xy 42.704549 -162.275866) (xy 51.308235 -162.275866)
			(xy 51.316175 -162.167119) (xy 51.332033 -162.059242) (xy 51.355722 -161.95281) (xy 51.387118 -161.848391)
			(xy 51.426052 -161.746543) (xy 51.472316 -161.647808) (xy 51.525664 -161.552714) (xy 51.585812 -161.461768)
			(xy 51.652437 -161.375455) (xy 51.725185 -161.294235) (xy 51.803668 -161.218542) (xy 51.887467 -161.14878)
			(xy 51.976134 -161.085322) (xy 52.069197 -161.028504) (xy 52.166159 -160.978632) (xy 52.266503 -160.93597)
			(xy 52.369693 -160.900747) (xy 52.47518 -160.87315) (xy 52.582399 -160.853327) (xy 52.690779 -160.841383)
			(xy 52.799742 -160.837382) (xy 52.908706 -160.841346) (xy 53.01709 -160.853253) (xy 53.124316 -160.873039)
			(xy 53.229812 -160.9006) (xy 53.333014 -160.935789) (xy 53.433373 -160.978416) (xy 53.530352 -161.028256)
			(xy 53.623434 -161.085041) (xy 53.712123 -161.14847) (xy 53.795946 -161.218203) (xy 53.874454 -161.293869)
			(xy 53.94723 -161.375064) (xy 54.013885 -161.461355) (xy 54.074063 -161.55228) (xy 54.127444 -161.647356)
			(xy 54.173742 -161.746075) (xy 54.21271 -161.84791) (xy 54.244141 -161.952318) (xy 54.267867 -162.058742)
			(xy 54.283761 -162.166614) (xy 54.291739 -162.275358) (xy 54.292246 -162.329876) (xy 54.291757 -162.384394)
			(xy 54.283817 -162.493141) (xy 54.267959 -162.601018) (xy 54.24427 -162.70745) (xy 54.212874 -162.811869)
			(xy 54.17394 -162.913717) (xy 54.127676 -163.012452) (xy 54.074328 -163.107546) (xy 54.01418 -163.198492)
			(xy 53.947555 -163.284805) (xy 53.874807 -163.366025) (xy 53.796324 -163.441718) (xy 53.712525 -163.51148)
			(xy 53.623858 -163.574938) (xy 53.530795 -163.631756) (xy 53.433833 -163.681628) (xy 53.333489 -163.72429)
			(xy 53.230299 -163.759513) (xy 53.124812 -163.78711) (xy 53.017593 -163.806933) (xy 52.909213 -163.818877)
			(xy 52.80025 -163.822878) (xy 52.691286 -163.818914) (xy 52.582902 -163.807007) (xy 52.475676 -163.787221)
			(xy 52.37018 -163.75966) (xy 52.266978 -163.724471) (xy 52.166619 -163.681844) (xy 52.06964 -163.632004)
			(xy 51.976558 -163.575219) (xy 51.887869 -163.51179) (xy 51.804046 -163.442057) (xy 51.725538 -163.366391)
			(xy 51.652762 -163.285196) (xy 51.586107 -163.198905) (xy 51.525929 -163.10798) (xy 51.472548 -163.012904)
			(xy 51.42625 -162.914185) (xy 51.387282 -162.81235) (xy 51.355851 -162.707942) (xy 51.332125 -162.601518)
			(xy 51.316231 -162.493646) (xy 51.308253 -162.384902) (xy 51.308235 -162.275866) (xy 42.704549 -162.275866)
			(xy 42.737927 -162.344546) (xy 42.774048 -162.437639) (xy 42.802398 -162.533384) (xy 42.822786 -162.631135)
			(xy 42.835074 -162.730231) (xy 42.839179 -162.830001) (xy 42.835074 -162.929772) (xy 42.822785 -163.028867)
			(xy 42.802397 -163.126618) (xy 42.774047 -163.222364) (xy 42.737926 -163.315457) (xy 42.694279 -163.405267)
			(xy 42.643401 -163.491188) (xy 42.585636 -163.572638) (xy 42.521375 -163.649067) (xy 42.451051 -163.719959)
			(xy 42.413428 -163.752784) (xy 42.405398 -163.760353) (xy 42.396166 -163.78037) (xy 42.395648 -163.791392)
			(xy 42.395648 -163.868608) (xy 42.396188 -163.879627) (xy 42.405403 -163.899647) (xy 42.413428 -163.907216)
			(xy 42.451053 -163.940039) (xy 42.521377 -164.010931) (xy 42.585638 -164.08736) (xy 42.643404 -164.168811)
			(xy 42.694282 -164.254732) (xy 42.737929 -164.344542) (xy 42.77405 -164.437635) (xy 42.8024 -164.533381)
			(xy 42.822788 -164.631132) (xy 42.835077 -164.730228) (xy 42.839182 -164.829999) (xy 42.835077 -164.929769)
			(xy 42.822789 -165.028865) (xy 42.802401 -165.126617) (xy 42.77405 -165.222362) (xy 42.73793 -165.315455)
			(xy 42.694283 -165.405266) (xy 42.643405 -165.491187) (xy 42.58564 -165.572638) (xy 42.521379 -165.649068)
			(xy 42.451055 -165.719959) (xy 42.413428 -165.75278) (xy 42.405397 -165.760349) (xy 42.396164 -165.780366)
			(xy 42.395648 -165.791388) (xy 42.395648 -165.868604) (xy 42.396187 -165.879623) (xy 42.405401 -165.899644)
			(xy 42.413428 -165.907212) (xy 42.451053 -165.940035) (xy 42.521377 -166.010927) (xy 42.585639 -166.087356)
			(xy 42.643405 -166.168807) (xy 42.694283 -166.254728) (xy 42.73793 -166.344539) (xy 42.774052 -166.437632)
			(xy 42.802402 -166.533378) (xy 42.822791 -166.631129) (xy 42.83508 -166.730225) (xy 42.839185 -166.829996)
			(xy 42.83508 -166.929767) (xy 42.822792 -167.028863) (xy 42.802404 -167.126615) (xy 42.774054 -167.222361)
			(xy 42.737934 -167.315454) (xy 42.694287 -167.405265) (xy 42.643409 -167.491187) (xy 42.585644 -167.572638)
			(xy 42.521383 -167.649068) (xy 42.451059 -167.71996) (xy 42.413428 -167.752776) (xy 42.405397 -167.760345)
			(xy 42.396162 -167.780362) (xy 42.395648 -167.791384) (xy 42.395648 -167.8686) (xy 42.396187 -167.87962)
			(xy 42.405399 -167.899642) (xy 42.413428 -167.907208) (xy 42.449354 -167.938525) (xy 42.516732 -168.00594)
			(xy 42.578614 -168.078433) (xy 42.63462 -168.155557) (xy 42.684404 -168.236836) (xy 42.727659 -168.32177)
			(xy 42.764118 -168.409834) (xy 42.793558 -168.500488) (xy 42.815796 -168.593171) (xy 42.830695 -168.687313)
			(xy 42.838164 -168.782333) (xy 42.838624 -168.82999) (xy 42.838106 -168.880167) (xy 42.829821 -168.98018)
			(xy 42.813305 -169.079166) (xy 42.788673 -169.176451) (xy 42.756092 -169.271369) (xy 42.715785 -169.363274)
			(xy 42.668027 -169.451536) (xy 42.613144 -169.535553) (xy 42.551511 -169.614752) (xy 42.483549 -169.688592)
			(xy 42.409722 -169.756567) (xy 42.330534 -169.818215) (xy 42.246527 -169.873113) (xy 42.158273 -169.920887)
			(xy 42.066376 -169.961211) (xy 41.971464 -169.99381) (xy 41.874183 -170.01846) (xy 41.7752 -170.034993)
			(xy 41.675189 -170.043297) (xy 41.625012 -170.043856) (xy 41.577351 -170.043378) (xy 41.482323 -170.03588)
			(xy 41.388176 -170.020954) (xy 41.29549 -169.99869) (xy 41.204834 -169.969227) (xy 41.116769 -169.932745)
			(xy 41.031835 -169.88947) (xy 40.950557 -169.839667) (xy 40.873434 -169.783645) (xy 40.800942 -169.721747)
			(xy 40.733528 -169.654354) (xy 40.70223 -169.618406) (xy 40.69466 -169.610377) (xy 40.674644 -169.601144)
			(xy 40.663622 -169.600626) (xy 40.586406 -169.600626) (xy 40.575388 -169.601166) (xy 40.555374 -169.610387)
			(xy 40.547798 -169.618406) (xy 40.516411 -169.654461) (xy 40.448809 -169.72206) (xy 40.376095 -169.784126)
			(xy 40.29872 -169.840276) (xy 40.217164 -169.890159) (xy 40.131935 -169.933467) (xy 40.043561 -169.969931)
			(xy 39.95259 -169.999324) (xy 39.906194 -170.010836) (xy 39.868348 -170.04919) (xy 39.848536 -170.138344)
			(xy 39.84689 -170.147707) (xy 39.849849 -170.166473) (xy 39.859407 -170.182891) (xy 39.86657 -170.189144)
			(xy 39.899481 -170.215886) (xy 39.960592 -170.274688) (xy 40.015823 -170.339045) (xy 40.064671 -170.40837)
			(xy 40.106693 -170.482034) (xy 40.141507 -170.559366) (xy 40.155622 -170.599354) (xy 40.155622 -170.599608)
			(xy 40.159551 -170.609388) (xy 40.173823 -170.624867) (xy 40.193102 -170.63333) (xy 40.203628 -170.633898)
			(xy 43.503596 -170.633898) (xy 43.514128 -170.633372) (xy 43.533415 -170.624903) (xy 43.547668 -170.609393)
			(xy 43.551602 -170.599608) (xy 43.551602 -170.599354) (xy 43.565762 -170.559248) (xy 43.600703 -170.481699)
			(xy 43.64289 -170.407841) (xy 43.691935 -170.338347) (xy 43.747391 -170.273854) (xy 43.808752 -170.21495)
			(xy 43.875456 -170.162173) (xy 43.946894 -170.116007) (xy 44.022414 -170.076872) (xy 44.101326 -170.045126)
			(xy 44.182907 -170.021059) (xy 44.266414 -170.004891) (xy 44.351083 -169.99677) (xy 44.436141 -169.99677)
			(xy 44.52081 -170.004891) (xy 44.604317 -170.021059) (xy 44.685898 -170.045126) (xy 44.76481 -170.076872)
			(xy 44.84033 -170.116007) (xy 44.911768 -170.162173) (xy 44.978472 -170.21495) (xy 45.039833 -170.273854)
			(xy 45.095289 -170.338347) (xy 45.144334 -170.407841) (xy 45.186521 -170.481699) (xy 45.221462 -170.559248)
			(xy 45.235622 -170.599354) (xy 45.235622 -170.599608) (xy 45.239551 -170.609388) (xy 45.253823 -170.624867)
			(xy 45.273102 -170.63333) (xy 45.283628 -170.633898) (xy 48.583596 -170.633898) (xy 48.594128 -170.633372)
			(xy 48.613415 -170.624903) (xy 48.627668 -170.609393) (xy 48.631602 -170.599608) (xy 48.631602 -170.599354)
			(xy 48.646941 -170.556083) (xy 48.68532 -170.472677) (xy 48.732077 -170.393664) (xy 48.786716 -170.31988)
			(xy 48.848656 -170.25211) (xy 48.882554 -170.221148) (xy 48.894492 -170.21048) (xy 48.901858 -170.179746)
			(xy 48.861726 -170.076114) (xy 48.857533 -170.066559) (xy 48.842951 -170.051663) (xy 48.823642 -170.04381)
			(xy 48.813212 -170.043602) (xy 48.812958 -170.043602) (xy 48.800258 -170.043856) (xy 48.79975 -170.043856)
			(xy 48.749589 -170.043328) (xy 48.64961 -170.035025) (xy 48.550658 -170.018497) (xy 48.453409 -169.993856)
			(xy 48.358526 -169.961271) (xy 48.266656 -169.920964) (xy 48.178428 -169.87321) (xy 48.094444 -169.818335)
			(xy 48.015276 -169.756714) (xy 47.941466 -169.688768) (xy 47.873517 -169.614961) (xy 47.811893 -169.535795)
			(xy 47.757015 -169.451813) (xy 47.709257 -169.363587) (xy 47.668947 -169.271719) (xy 47.636358 -169.176837)
			(xy 47.611713 -169.079589) (xy 47.595181 -168.980637) (xy 47.586874 -168.880659) (xy 47.586392 -168.830498)
			(xy 47.586392 -168.82999) (xy 47.586859 -168.782334) (xy 47.594335 -168.687314) (xy 47.609238 -168.593174)
			(xy 47.631478 -168.500492) (xy 47.660918 -168.40984) (xy 47.697376 -168.321776) (xy 47.740628 -168.236841)
			(xy 47.790408 -168.155561) (xy 47.846408 -168.078434) (xy 47.908283 -168.005936) (xy 47.975654 -167.938514)
			(xy 48.011588 -167.907208) (xy 48.019615 -167.899637) (xy 48.02884 -167.87962) (xy 48.029368 -167.8686)
			(xy 48.029368 -167.791384) (xy 48.028824 -167.780368) (xy 48.019597 -167.760361) (xy 48.011588 -167.752776)
			(xy 47.973965 -167.719951) (xy 47.903647 -167.649058) (xy 47.83939 -167.572627) (xy 47.78163 -167.491176)
			(xy 47.730756 -167.405255) (xy 47.687113 -167.315445) (xy 47.650995 -167.222353) (xy 47.622647 -167.126608)
			(xy 47.602261 -167.028859) (xy 47.589974 -166.929765) (xy 47.585869 -166.829996) (xy 47.589974 -166.730228)
			(xy 47.602262 -166.631134) (xy 47.622649 -166.533384) (xy 47.650998 -166.43764) (xy 47.687116 -166.344548)
			(xy 47.73076 -166.254738) (xy 47.781634 -166.168818) (xy 47.839395 -166.087367) (xy 47.903652 -166.010936)
			(xy 47.973971 -165.940043) (xy 48.011588 -165.907212) (xy 48.019615 -165.899642) (xy 48.028842 -165.879625)
			(xy 48.029368 -165.868604) (xy 48.029368 -165.791388) (xy 48.028824 -165.780372) (xy 48.019598 -165.760364)
			(xy 48.011588 -165.75278) (xy 47.975665 -165.721462) (xy 47.908292 -165.654044) (xy 47.846414 -165.581549)
			(xy 47.790413 -165.504424) (xy 47.740633 -165.423145) (xy 47.697383 -165.338211) (xy 47.660927 -165.250147)
			(xy 47.63149 -165.159495) (xy 47.609255 -165.066813) (xy 47.594357 -164.972673) (xy 47.58689 -164.877654)
			(xy 47.586392 -164.829998) (xy 47.58691 -164.77982) (xy 47.595196 -164.679806) (xy 47.611712 -164.580817)
			(xy 47.636345 -164.483531) (xy 47.668926 -164.38861) (xy 47.709233 -164.296704) (xy 47.756991 -164.208439)
			(xy 47.811873 -164.124419) (xy 47.873505 -164.045217) (xy 47.941466 -163.971374) (xy 48.015293 -163.903395)
			(xy 48.094479 -163.841744) (xy 48.178486 -163.786841) (xy 48.266739 -163.739062) (xy 48.358636 -163.698733)
			(xy 48.453549 -163.666129) (xy 48.55083 -163.641473) (xy 48.649814 -163.624933) (xy 48.749826 -163.616622)
			(xy 48.800004 -163.616132) (xy 48.847665 -163.616611) (xy 48.942692 -163.62411) (xy 49.036839 -163.639037)
			(xy 49.129525 -163.661301) (xy 49.220179 -163.690765) (xy 49.308244 -163.727248) (xy 49.393177 -163.770523)
			(xy 49.474455 -163.820326) (xy 49.551577 -163.876349) (xy 49.624068 -163.938247) (xy 49.691483 -164.005639)
			(xy 49.722786 -164.041582) (xy 49.730356 -164.04961) (xy 49.750373 -164.058839) (xy 49.761394 -164.059362)
			(xy 49.83861 -164.059362) (xy 49.849629 -164.058822) (xy 49.869649 -164.049608) (xy 49.877218 -164.041582)
			(xy 49.908528 -164.005643) (xy 49.975932 -163.938238) (xy 50.048417 -163.876329) (xy 50.125535 -163.820297)
			(xy 50.206811 -163.770488) (xy 50.291744 -163.727208) (xy 50.379811 -163.690725) (xy 50.470468 -163.661263)
			(xy 50.563158 -163.639005) (xy 50.657308 -163.624086) (xy 50.752338 -163.6166) (xy 50.8 -163.616132)
			(xy 50.850167 -163.61665) (xy 50.950157 -163.624934) (xy 51.049122 -163.641447) (xy 51.146386 -163.666075)
			(xy 51.241284 -163.698649) (xy 51.333168 -163.738948) (xy 51.421411 -163.786697) (xy 51.50541 -163.841569)
			(xy 51.584592 -163.903189) (xy 51.658415 -163.971137) (xy 51.726375 -164.044948) (xy 51.788009 -164.124119)
			(xy 51.842895 -164.208108) (xy 51.890659 -164.296343) (xy 51.930974 -164.38822) (xy 51.963565 -164.483113)
			(xy 51.98821 -164.580372) (xy 52.00474 -164.679334) (xy 52.013041 -164.779324) (xy 52.013612 -164.82949)
			(xy 52.013612 -164.829998) (xy 52.013145 -164.877655) (xy 52.005671 -164.972674) (xy 51.990768 -165.066815)
			(xy 51.968529 -165.159498) (xy 51.93909 -165.250151) (xy 51.902632 -165.338216) (xy 51.859381 -165.423151)
			(xy 51.809602 -165.504432) (xy 51.753602 -165.58156) (xy 51.691727 -165.654058) (xy 51.624357 -165.721481)
			(xy 51.588416 -165.75278) (xy 51.580387 -165.76035) (xy 51.571156 -165.780367) (xy 51.570636 -165.791388)
			(xy 51.570636 -165.868604) (xy 51.571179 -165.879621) (xy 51.580403 -165.899631) (xy 51.588416 -165.907212)
			(xy 51.626039 -165.940037) (xy 51.696358 -166.01093) (xy 51.760616 -166.087361) (xy 51.818377 -166.168813)
			(xy 51.869252 -166.254734) (xy 51.912896 -166.344545) (xy 51.949014 -166.437637) (xy 51.977362 -166.533382)
			(xy 51.99775 -166.631132) (xy 52.010037 -166.730227) (xy 52.014143 -166.829996) (xy 52.010038 -166.929765)
			(xy 51.997751 -167.02886) (xy 51.977364 -167.12661) (xy 51.949016 -167.222355) (xy 51.912899 -167.315448)
			(xy 51.869255 -167.405259) (xy 51.818381 -167.49118) (xy 51.76062 -167.572632) (xy 51.696363 -167.649064)
			(xy 51.626045 -167.719958) (xy 51.588416 -167.752776) (xy 51.580386 -167.760345) (xy 51.571154 -167.780362)
			(xy 51.570636 -167.791384) (xy 51.570636 -167.8686) (xy 51.571178 -167.879617) (xy 51.580401 -167.899628)
			(xy 51.588416 -167.907208) (xy 51.62434 -167.938526) (xy 51.691713 -168.005944) (xy 51.753592 -168.078438)
			(xy 51.809593 -168.155563) (xy 51.859373 -168.236842) (xy 51.902625 -168.321776) (xy 51.939082 -168.40984)
			(xy 51.968519 -168.500492) (xy 51.990755 -168.593174) (xy 52.005654 -168.687315) (xy 52.013122 -168.782334)
			(xy 52.013612 -168.82999) (xy 52.013094 -168.880169) (xy 52.004809 -168.980184) (xy 51.988294 -169.079173)
			(xy 51.963662 -169.17646) (xy 51.931082 -169.271382) (xy 51.890775 -169.36329) (xy 51.843018 -169.451555)
			(xy 51.788135 -169.535576) (xy 51.726503 -169.614779) (xy 51.658542 -169.688623) (xy 51.584716 -169.756603)
			(xy 51.505529 -169.818255) (xy 51.421522 -169.873159) (xy 51.333268 -169.920939) (xy 51.241371 -169.961269)
			(xy 51.146458 -169.993874) (xy 51.049176 -170.01853) (xy 50.950191 -170.035071) (xy 50.850179 -170.043381)
			(xy 50.8 -170.043856) (xy 50.752339 -170.043377) (xy 50.657312 -170.035879) (xy 50.563165 -170.020951)
			(xy 50.470479 -169.998687) (xy 50.379825 -169.969223) (xy 50.29176 -169.932741) (xy 50.206827 -169.889465)
			(xy 50.125549 -169.839662) (xy 50.048427 -169.783639) (xy 49.975936 -169.721741) (xy 49.908522 -169.654348)
			(xy 49.877218 -169.618406) (xy 49.869648 -169.610378) (xy 49.849631 -169.60115) (xy 49.83861 -169.600626)
			(xy 49.761394 -169.600626) (xy 49.750377 -169.601168) (xy 49.730366 -169.610392) (xy 49.722786 -169.618406)
			(xy 49.690645 -169.655306) (xy 49.621304 -169.724367) (xy 49.546622 -169.787615) (xy 49.50714 -169.816526)
			(xy 49.499004 -169.822911) (xy 49.488269 -169.840567) (xy 49.485384 -169.861027) (xy 49.487582 -169.871136)
			(xy 49.516538 -169.978324) (xy 49.540922 -169.998644) (xy 49.55667 -170.000168) (xy 49.599046 -170.004639)
			(xy 49.682741 -170.020663) (xy 49.764519 -170.044621) (xy 49.84363 -170.076294) (xy 49.919347 -170.11539)
			(xy 49.990976 -170.161552) (xy 50.05786 -170.214356) (xy 50.119385 -170.273316) (xy 50.174987 -170.337893)
			(xy 50.224155 -170.407493) (xy 50.266438 -170.481479) (xy 50.301448 -170.55917) (xy 50.315622 -170.599354)
			(xy 50.315622 -170.599608) (xy 50.319551 -170.609388) (xy 50.333823 -170.624867) (xy 50.353102 -170.63333)
			(xy 50.363628 -170.633898) (xy 53.663596 -170.633898) (xy 53.674128 -170.633372) (xy 53.693415 -170.624903)
			(xy 53.707668 -170.609393) (xy 53.711602 -170.599608) (xy 53.711602 -170.599354) (xy 53.725254 -170.560595)
			(xy 53.758755 -170.485553) (xy 53.799038 -170.413923) (xy 53.84576 -170.346316) (xy 53.898522 -170.283309)
			(xy 53.956873 -170.225441) (xy 54.020316 -170.173204) (xy 54.088309 -170.127046) (xy 54.160272 -170.08736)
			(xy 54.197758 -170.070526) (xy 54.198012 -170.070526) (xy 54.206454 -170.066314) (xy 54.219769 -170.052973)
			(xy 54.227371 -170.035725) (xy 54.228238 -170.02633) (xy 54.233572 -169.921174) (xy 54.219348 -169.895774)
			(xy 54.206902 -169.888916) (xy 54.163968 -169.864281) (xy 54.081835 -169.809018) (xy 54.004476 -169.747248)
			(xy 53.932404 -169.679383) (xy 53.8661 -169.605873) (xy 53.806003 -169.527207) (xy 53.752513 -169.443908)
			(xy 53.705985 -169.35653) (xy 53.666729 -169.265652) (xy 53.635004 -169.171878) (xy 53.611023 -169.075832)
			(xy 53.594943 -168.978152) (xy 53.586873 -168.879487) (xy 53.58638 -168.82999) (xy 53.586847 -168.782334)
			(xy 53.594322 -168.687314) (xy 53.609226 -168.593174) (xy 53.631466 -168.500492) (xy 53.660906 -168.409839)
			(xy 53.697364 -168.321775) (xy 53.740615 -168.23684) (xy 53.790394 -168.155559) (xy 53.846394 -168.078432)
			(xy 53.908269 -168.005934) (xy 53.975639 -167.938511) (xy 54.011576 -167.907208) (xy 54.019604 -167.899638)
			(xy 54.028832 -167.879621) (xy 54.029356 -167.8686) (xy 54.029356 -167.791384) (xy 54.028814 -167.780366)
			(xy 54.019598 -167.760348) (xy 54.011576 -167.752776) (xy 53.973951 -167.719953) (xy 53.903628 -167.649062)
			(xy 53.839367 -167.572632) (xy 53.781602 -167.491182) (xy 53.730724 -167.405261) (xy 53.687078 -167.315451)
			(xy 53.650957 -167.222358) (xy 53.622607 -167.126613) (xy 53.602219 -167.028862) (xy 53.589931 -166.929766)
			(xy 53.585826 -166.829996) (xy 53.589932 -166.730226) (xy 53.602221 -166.631131) (xy 53.622609 -166.53338)
			(xy 53.65096 -166.437634) (xy 53.687081 -166.344542) (xy 53.730728 -166.254732) (xy 53.781606 -166.168811)
			(xy 53.839371 -166.087361) (xy 53.903633 -166.010933) (xy 53.973957 -165.940042) (xy 54.011576 -165.907212)
			(xy 54.019605 -165.899642) (xy 54.028834 -165.879625) (xy 54.029356 -165.868604) (xy 54.029356 -165.791388)
			(xy 54.028815 -165.780369) (xy 54.0196 -165.760351) (xy 54.011576 -165.75278) (xy 53.975651 -165.721463)
			(xy 53.908273 -165.654047) (xy 53.846391 -165.581554) (xy 53.790386 -165.504431) (xy 53.740603 -165.423151)
			(xy 53.697348 -165.338218) (xy 53.66089 -165.250153) (xy 53.631451 -165.1595) (xy 53.609214 -165.066817)
			(xy 53.594315 -164.972675) (xy 53.586847 -164.877655) (xy 53.58638 -164.829998) (xy 53.586898 -164.779821)
			(xy 53.595185 -164.67981) (xy 53.611701 -164.580824) (xy 53.636334 -164.48354) (xy 53.668915 -164.388623)
			(xy 53.709223 -164.296719) (xy 53.756982 -164.208458) (xy 53.811865 -164.124442) (xy 53.873498 -164.045244)
			(xy 53.94146 -163.971406) (xy 54.015287 -163.903431) (xy 54.094474 -163.841784) (xy 54.178481 -163.786887)
			(xy 54.266734 -163.739113) (xy 54.358631 -163.69879) (xy 54.453543 -163.666192) (xy 54.550822 -163.641543)
			(xy 54.649805 -163.62501) (xy 54.749815 -163.616707) (xy 54.799992 -163.616132) (xy 54.847653 -163.61661)
			(xy 54.942681 -163.624108) (xy 55.036828 -163.639035) (xy 55.129514 -163.661299) (xy 55.22017 -163.690762)
			(xy 55.308235 -163.727243) (xy 55.393169 -163.770519) (xy 55.474447 -163.820321) (xy 55.55157 -163.876343)
			(xy 55.624062 -163.938241) (xy 55.691477 -164.005633) (xy 55.722774 -164.041582) (xy 55.730343 -164.049612)
			(xy 55.75036 -164.058846) (xy 55.761382 -164.059362) (xy 55.838598 -164.059362) (xy 55.849618 -164.058824)
			(xy 55.869642 -164.049613) (xy 55.877206 -164.041582) (xy 55.908516 -164.005643) (xy 55.97592 -163.938237)
			(xy 56.048404 -163.876327) (xy 56.125522 -163.820294) (xy 56.206798 -163.770484) (xy 56.291731 -163.727204)
			(xy 56.379798 -163.69072) (xy 56.470456 -163.661257) (xy 56.563145 -163.638998) (xy 56.657295 -163.624079)
			(xy 56.752326 -163.616592) (xy 56.799988 -163.616132) (xy 56.850155 -163.616649) (xy 56.950146 -163.624933)
			(xy 57.049112 -163.641445) (xy 57.146377 -163.666072) (xy 57.241275 -163.698646) (xy 57.333161 -163.738945)
			(xy 57.421404 -163.786693) (xy 57.505404 -163.841564) (xy 57.584587 -163.903185) (xy 57.658411 -163.971132)
			(xy 57.726372 -164.044944) (xy 57.788007 -164.124115) (xy 57.842893 -164.208105) (xy 57.890658 -164.29634)
			(xy 57.930973 -164.388218) (xy 57.963565 -164.483111) (xy 57.98821 -164.580371) (xy 58.004739 -164.679333)
			(xy 58.013041 -164.779323) (xy 58.0136 -164.82949) (xy 58.0136 -164.829998) (xy 58.013133 -164.877655)
			(xy 58.005659 -164.972674) (xy 57.990756 -165.066815) (xy 57.968516 -165.159497) (xy 57.939077 -165.25015)
			(xy 57.902619 -165.338215) (xy 57.859368 -165.423149) (xy 57.809589 -165.504431) (xy 57.753589 -165.581558)
			(xy 57.691713 -165.654056) (xy 57.624342 -165.721479) (xy 57.588404 -165.75278) (xy 57.580376 -165.76035)
			(xy 57.571148 -165.780367) (xy 57.570624 -165.791388) (xy 57.570624 -165.868604) (xy 57.571166 -165.879621)
			(xy 57.580389 -165.899633) (xy 57.588404 -165.907212) (xy 57.626027 -165.940036) (xy 57.696347 -166.01093)
			(xy 57.760605 -166.087361) (xy 57.818367 -166.168812) (xy 57.869242 -166.254734) (xy 57.912887 -166.344544)
			(xy 57.949005 -166.437637) (xy 57.977354 -166.533382) (xy 57.997742 -166.631132) (xy 58.010029 -166.730227)
			(xy 58.014135 -166.829996) (xy 58.01003 -166.929765) (xy 57.997743 -167.02886) (xy 57.977356 -167.126611)
			(xy 57.949008 -167.222356) (xy 57.91289 -167.315449) (xy 57.869246 -167.40526) (xy 57.818371 -167.491181)
			(xy 57.76061 -167.572633) (xy 57.696352 -167.649064) (xy 57.626033 -167.719958) (xy 57.588404 -167.752776)
			(xy 57.580376 -167.760346) (xy 57.571146 -167.780363) (xy 57.570624 -167.791384) (xy 57.570624 -167.8686)
			(xy 57.571165 -167.879618) (xy 57.580387 -167.89963) (xy 57.588404 -167.907208) (xy 57.624328 -167.938526)
			(xy 57.691702 -168.005943) (xy 57.753581 -168.078438) (xy 57.809584 -168.155562) (xy 57.859364 -168.236842)
			(xy 57.902616 -168.321775) (xy 57.939073 -168.409839) (xy 57.968511 -168.500492) (xy 57.990747 -168.593174)
			(xy 58.005646 -168.687315) (xy 58.013114 -168.782334) (xy 58.0136 -168.82999) (xy 58.013082 -168.880169)
			(xy 58.004797 -168.980183) (xy 57.988282 -169.079172) (xy 57.96365 -169.176459) (xy 57.931069 -169.27138)
			(xy 57.890763 -169.363287) (xy 57.843005 -169.451553) (xy 57.788123 -169.535573) (xy 57.726491 -169.614775)
			(xy 57.658529 -169.688618) (xy 57.584703 -169.756598) (xy 57.505516 -169.81825) (xy 57.421509 -169.873153)
			(xy 57.333255 -169.920932) (xy 57.241358 -169.961261) (xy 57.146445 -169.993865) (xy 57.049164 -170.018521)
			(xy 56.950179 -170.03506) (xy 56.850166 -170.04337) (xy 56.799988 -170.043856) (xy 56.752327 -170.043377)
			(xy 56.6573 -170.035877) (xy 56.563154 -170.020949) (xy 56.470469 -169.998684) (xy 56.379815 -169.96922)
			(xy 56.291751 -169.932737) (xy 56.206819 -169.889461) (xy 56.125542 -169.839657) (xy 56.04842 -169.783634)
			(xy 55.97593 -169.721735) (xy 55.908517 -169.654343) (xy 55.877206 -169.618406) (xy 55.869635 -169.61038)
			(xy 55.849618 -169.601157) (xy 55.838598 -169.600626) (xy 55.761382 -169.600626) (xy 55.750366 -169.601171)
			(xy 55.730359 -169.610397) (xy 55.722774 -169.618406) (xy 55.689033 -169.657063) (xy 55.616023 -169.72917)
			(xy 55.537189 -169.79486) (xy 55.453094 -169.853664) (xy 55.364338 -169.905164) (xy 55.271553 -169.948992)
			(xy 55.175401 -169.984835) (xy 55.126128 -169.999152) (xy 55.112412 -170.002962) (xy 55.0926 -170.024298)
			(xy 55.070248 -170.1419) (xy 55.080408 -170.168824) (xy 55.092092 -170.177714) (xy 55.12674 -170.204749)
			(xy 55.19109 -170.26461) (xy 55.249223 -170.330526) (xy 55.300572 -170.401853) (xy 55.344636 -170.477897)
			(xy 55.380987 -170.557915) (xy 55.395622 -170.599354) (xy 55.395622 -170.599608) (xy 55.399551 -170.609388)
			(xy 55.413823 -170.624867) (xy 55.433102 -170.63333) (xy 55.443628 -170.633898) (xy 58.743596 -170.633898)
			(xy 58.754128 -170.633372) (xy 58.773415 -170.624903) (xy 58.787668 -170.609393) (xy 58.791602 -170.599608)
			(xy 58.791602 -170.599354) (xy 58.805762 -170.559248) (xy 58.840703 -170.481699) (xy 58.88289 -170.407841)
			(xy 58.931935 -170.338347) (xy 58.987391 -170.273854) (xy 59.048752 -170.21495) (xy 59.115456 -170.162173)
			(xy 59.186894 -170.116007) (xy 59.262414 -170.076872) (xy 59.341326 -170.045126) (xy 59.422907 -170.021059)
			(xy 59.506414 -170.004891) (xy 59.591083 -169.99677) (xy 59.676141 -169.99677) (xy 59.76081 -170.004891)
			(xy 59.844317 -170.021059) (xy 59.925898 -170.045126) (xy 60.00481 -170.076872) (xy 60.08033 -170.116007)
			(xy 60.151768 -170.162173) (xy 60.218472 -170.21495) (xy 60.279833 -170.273854) (xy 60.335289 -170.338347)
			(xy 60.384334 -170.407841) (xy 60.426521 -170.481699) (xy 60.461462 -170.559248) (xy 60.475622 -170.599354)
			(xy 60.475622 -170.599608) (xy 60.479551 -170.609388) (xy 60.493823 -170.624867) (xy 60.513102 -170.63333)
			(xy 60.523628 -170.633898) (xy 63.823596 -170.633898) (xy 63.834128 -170.633372) (xy 63.853415 -170.624903)
			(xy 63.867668 -170.609393) (xy 63.871602 -170.599608) (xy 63.871602 -170.599354) (xy 63.886066 -170.558468)
			(xy 63.921865 -170.479469) (xy 63.965181 -170.404329) (xy 64.015604 -170.33376) (xy 64.072653 -170.268433)
			(xy 64.135789 -170.208966) (xy 64.204412 -170.155926) (xy 64.27787 -170.109814) (xy 64.355466 -170.071069)
			(xy 64.436465 -170.040059) (xy 64.478154 -170.028108) (xy 64.48873 -170.024611) (xy 64.505676 -170.010192)
			(xy 64.514937 -169.989961) (xy 64.515492 -169.978832) (xy 64.515492 -169.975276) (xy 64.515075 -169.96566)
			(xy 64.507983 -169.947783) (xy 64.494805 -169.933775) (xy 64.486282 -169.929302) (xy 64.439597 -169.906919)
			(xy 64.349844 -169.855295) (xy 64.264819 -169.796206) (xy 64.185143 -169.730081) (xy 64.111396 -169.657403)
			(xy 64.077342 -169.618406) (xy 64.069773 -169.610374) (xy 64.049756 -169.601137) (xy 64.038734 -169.600626)
			(xy 63.961518 -169.600626) (xy 63.950499 -169.601163) (xy 63.930481 -169.610381) (xy 63.92291 -169.618406)
			(xy 63.8916 -169.654346) (xy 63.824197 -169.721753) (xy 63.751713 -169.783665) (xy 63.674596 -169.839699)
			(xy 63.59332 -169.889511) (xy 63.508387 -169.932793) (xy 63.42032 -169.969278) (xy 63.329662 -169.998742)
			(xy 63.236972 -170.021003) (xy 63.142822 -170.035924) (xy 63.047791 -170.043412) (xy 63.000128 -170.043856)
			(xy 62.949959 -170.043339) (xy 62.849964 -170.035057) (xy 62.750995 -170.018547) (xy 62.653726 -169.993921)
			(xy 62.558823 -169.961348) (xy 62.466934 -169.921051) (xy 62.378685 -169.873303) (xy 62.294681 -169.818433)
			(xy 62.215493 -169.756814) (xy 62.141664 -169.688867) (xy 62.073697 -169.615056) (xy 62.012057 -169.535885)
			(xy 61.957163 -169.451895) (xy 61.909393 -169.363659) (xy 61.869071 -169.27178) (xy 61.836472 -169.176886)
			(xy 61.81182 -169.079624) (xy 61.795283 -168.980659) (xy 61.786974 -168.880667) (xy 61.786516 -168.830498)
			(xy 61.786516 -168.82999) (xy 61.786983 -168.782334) (xy 61.794459 -168.687315) (xy 61.809362 -168.593175)
			(xy 61.831603 -168.500493) (xy 61.861043 -168.409841) (xy 61.897502 -168.321777) (xy 61.940754 -168.236844)
			(xy 61.990534 -168.155564) (xy 62.046535 -168.078438) (xy 62.108412 -168.005941) (xy 62.175783 -167.93852)
			(xy 62.211712 -167.907208) (xy 62.219736 -167.899636) (xy 62.228956 -167.879619) (xy 62.229492 -167.8686)
			(xy 62.229492 -167.791384) (xy 62.228948 -167.780368) (xy 62.219724 -167.760358) (xy 62.211712 -167.752776)
			(xy 62.174089 -167.719952) (xy 62.103769 -167.649059) (xy 62.039511 -167.572629) (xy 61.981749 -167.491177)
			(xy 61.930875 -167.405256) (xy 61.88723 -167.315446) (xy 61.851112 -167.222354) (xy 61.822764 -167.126609)
			(xy 61.802377 -167.028859) (xy 61.790089 -166.929765) (xy 61.785985 -166.829996) (xy 61.79009 -166.730227)
			(xy 61.802378 -166.631133) (xy 61.822766 -166.533383) (xy 61.851115 -166.437639) (xy 61.887234 -166.344547)
			(xy 61.930878 -166.254737) (xy 61.981754 -166.168816) (xy 62.039516 -166.087365) (xy 62.103774 -166.010935)
			(xy 62.174094 -165.940043) (xy 62.211712 -165.907212) (xy 62.219736 -165.89964) (xy 62.228959 -165.879623)
			(xy 62.229492 -165.868604) (xy 62.229492 -165.791388) (xy 62.228949 -165.780371) (xy 62.219726 -165.76036)
			(xy 62.211712 -165.75278) (xy 62.175788 -165.721462) (xy 62.108414 -165.654045) (xy 62.046535 -165.58155)
			(xy 61.990533 -165.504426) (xy 61.940752 -165.423147) (xy 61.897501 -165.338213) (xy 61.861044 -165.250149)
			(xy 61.831607 -165.159496) (xy 61.809371 -165.066814) (xy 61.794473 -164.972673) (xy 61.787005 -164.877654)
			(xy 61.786516 -164.829998) (xy 61.787034 -164.77982) (xy 61.79532 -164.679807) (xy 61.811836 -164.580819)
			(xy 61.836469 -164.483533) (xy 61.86905 -164.388613) (xy 61.909357 -164.296708) (xy 61.957115 -164.208444)
			(xy 62.011998 -164.124425) (xy 62.07363 -164.045224) (xy 62.141592 -163.971383) (xy 62.215418 -163.903405)
			(xy 62.294605 -163.841755) (xy 62.378612 -163.786854) (xy 62.466865 -163.739076) (xy 62.558762 -163.698748)
			(xy 62.653674 -163.666146) (xy 62.750955 -163.641492) (xy 62.849939 -163.624954) (xy 62.94995 -163.616645)
			(xy 63.000128 -163.616132) (xy 63.047789 -163.616612) (xy 63.142815 -163.624112) (xy 63.23696 -163.639041)
			(xy 63.329645 -163.661307) (xy 63.420299 -163.690773) (xy 63.508362 -163.727256) (xy 63.593294 -163.770532)
			(xy 63.67457 -163.820336) (xy 63.751691 -163.87636) (xy 63.824181 -163.938258) (xy 63.891593 -164.005651)
			(xy 63.92291 -164.041582) (xy 63.930481 -164.049606) (xy 63.950499 -164.058826) (xy 63.961518 -164.059362)
			(xy 64.038734 -164.059362) (xy 64.049751 -164.058817) (xy 64.069763 -164.049597) (xy 64.077342 -164.041582)
			(xy 64.108652 -164.005644) (xy 64.176057 -163.93824) (xy 64.248542 -163.876332) (xy 64.32566 -163.820302)
			(xy 64.406936 -163.770494) (xy 64.49187 -163.727216) (xy 64.579936 -163.690735) (xy 64.670594 -163.661275)
			(xy 64.763283 -163.639018) (xy 64.857432 -163.624102) (xy 64.952462 -163.616617) (xy 65.000124 -163.616132)
			(xy 65.05029 -163.616651) (xy 65.150279 -163.624937) (xy 65.249243 -163.641451) (xy 65.346505 -163.66608)
			(xy 65.441401 -163.698656) (xy 65.533284 -163.738956) (xy 65.621525 -163.786705) (xy 65.705522 -163.841577)
			(xy 65.784702 -163.903197) (xy 65.858523 -163.971145) (xy 65.926482 -164.044956) (xy 65.988115 -164.124126)
			(xy 66.043 -164.208115) (xy 66.090762 -164.296349) (xy 66.131076 -164.388226) (xy 66.163667 -164.483117)
			(xy 66.188311 -164.580375) (xy 66.20484 -164.679336) (xy 66.213141 -164.779324) (xy 66.213736 -164.82949)
			(xy 66.213736 -164.829998) (xy 66.213269 -164.877655) (xy 66.205795 -164.972675) (xy 66.190892 -165.066816)
			(xy 66.168653 -165.159499) (xy 66.139215 -165.250152) (xy 66.102758 -165.338217) (xy 66.059507 -165.423153)
			(xy 66.009729 -165.504435) (xy 65.95373 -165.581564) (xy 65.891855 -165.654063) (xy 65.824486 -165.721487)
			(xy 65.78854 -165.75278) (xy 65.780521 -165.760355) (xy 65.771304 -165.78037) (xy 65.77076 -165.791388)
			(xy 65.77076 -165.868604) (xy 65.7713 -165.879623) (xy 65.780515 -165.899642) (xy 65.78854 -165.907212)
			(xy 65.82697 -165.940715) (xy 65.898682 -166.013199) (xy 65.964058 -166.091444) (xy 66.022637 -166.1749)
			(xy 66.074006 -166.262977) (xy 66.096388 -166.308786) (xy 66.101452 -166.318178) (xy 66.11759 -166.332102)
			(xy 66.12763 -166.33571) (xy 66.199258 -166.3573) (xy 66.209525 -166.359844) (xy 66.230505 -166.35734)
			(xy 66.239898 -166.352474) (xy 66.28586 -166.325669) (xy 66.380963 -166.277934) (xy 66.479237 -166.237121)
			(xy 66.580177 -166.203441) (xy 66.683267 -166.177064) (xy 66.787979 -166.158126) (xy 66.893777 -166.146725)
			(xy 67.00012 -166.142918) (xy 67.106463 -166.146725) (xy 67.212261 -166.158126) (xy 67.316973 -166.177064)
			(xy 67.420063 -166.203441) (xy 67.521003 -166.237121) (xy 67.619277 -166.277934) (xy 67.71438 -166.325669)
			(xy 67.760342 -166.352474) (xy 67.769682 -166.357501) (xy 67.790727 -166.36001) (xy 67.800982 -166.3573)
			(xy 67.87261 -166.33571) (xy 67.882696 -166.33218) (xy 67.898864 -166.318237) (xy 67.903852 -166.308786)
			(xy 67.926229 -166.262975) (xy 67.977606 -166.174903) (xy 68.036189 -166.091451) (xy 68.101565 -166.013206)
			(xy 68.173274 -165.94072) (xy 68.2117 -165.907212) (xy 68.219726 -165.899641) (xy 68.228951 -165.879624)
			(xy 68.22948 -165.868604) (xy 68.22948 -165.791388) (xy 68.228937 -165.780371) (xy 68.219712 -165.760362)
			(xy 68.2117 -165.75278) (xy 68.175777 -165.721462) (xy 68.108403 -165.654044) (xy 68.046524 -165.58155)
			(xy 67.990523 -165.504425) (xy 67.940743 -165.423146) (xy 67.897492 -165.338212) (xy 67.861035 -165.250148)
			(xy 67.831599 -165.159496) (xy 67.809363 -165.066814) (xy 67.794465 -164.972673) (xy 67.786997 -164.877654)
			(xy 67.786504 -164.829998) (xy 67.787022 -164.77982) (xy 67.795308 -164.679806) (xy 67.811824 -164.580818)
			(xy 67.836457 -164.483532) (xy 67.869038 -164.388612) (xy 67.909345 -164.296706) (xy 67.957103 -164.208441)
			(xy 68.011985 -164.124422) (xy 68.073618 -164.045221) (xy 68.141579 -163.971379) (xy 68.215405 -163.9034)
			(xy 68.294592 -163.841749) (xy 68.378599 -163.786847) (xy 68.466852 -163.739069) (xy 68.558749 -163.69874)
			(xy 68.653662 -163.666137) (xy 68.750942 -163.641482) (xy 68.849926 -163.624943) (xy 68.949938 -163.616634)
			(xy 69.000116 -163.616132) (xy 69.047777 -163.616611) (xy 69.142804 -163.624111) (xy 69.23695 -163.639039)
			(xy 69.329635 -163.661304) (xy 69.420289 -163.690769) (xy 69.508353 -163.727252) (xy 69.593285 -163.770528)
			(xy 69.674562 -163.820331) (xy 69.751684 -163.876354) (xy 69.824175 -163.938253) (xy 69.891588 -164.005645)
			(xy 69.922898 -164.041582) (xy 69.930468 -164.049609) (xy 69.950486 -164.058833) (xy 69.961506 -164.059362)
			(xy 70.038722 -164.059362) (xy 70.04974 -164.058819) (xy 70.069756 -164.049602) (xy 70.07733 -164.041582)
			(xy 70.10864 -164.005644) (xy 70.176045 -163.938239) (xy 70.248529 -163.876331) (xy 70.325647 -163.820299)
			(xy 70.406924 -163.770491) (xy 70.491857 -163.727212) (xy 70.579924 -163.69073) (xy 70.670581 -163.661269)
			(xy 70.76327 -163.639012) (xy 70.85742 -163.624094) (xy 70.95245 -163.616609) (xy 71.000112 -163.616132)
			(xy 71.050278 -163.61665) (xy 71.150268 -163.624936) (xy 71.249232 -163.641449) (xy 71.346495 -163.666077)
			(xy 71.441392 -163.698653) (xy 71.533276 -163.738952) (xy 71.621518 -163.786701) (xy 71.705516 -163.841573)
			(xy 71.784697 -163.903193) (xy 71.858519 -163.971141) (xy 71.926479 -164.044952) (xy 71.988112 -164.124123)
			(xy 72.042998 -164.208112) (xy 72.090761 -164.296346) (xy 72.131075 -164.388223) (xy 72.163666 -164.483115)
			(xy 72.18831 -164.580374) (xy 72.20484 -164.679335) (xy 72.213141 -164.779324) (xy 72.213724 -164.82949)
			(xy 72.213724 -164.829998) (xy 72.213257 -164.877655) (xy 72.205783 -164.972675) (xy 72.19088 -165.066816)
			(xy 72.168641 -165.159498) (xy 72.139202 -165.250151) (xy 72.102745 -165.338217) (xy 72.059494 -165.423152)
			(xy 72.009715 -165.504434) (xy 71.953716 -165.581562) (xy 71.891841 -165.654061) (xy 71.824471 -165.721484)
			(xy 71.788528 -165.75278) (xy 71.780497 -165.760349) (xy 71.771264 -165.780366) (xy 71.770748 -165.791388)
			(xy 71.770748 -165.868604) (xy 71.771287 -165.879623) (xy 71.780501 -165.899644) (xy 71.788528 -165.907212)
			(xy 71.826153 -165.940035) (xy 71.896477 -166.010927) (xy 71.960739 -166.087356) (xy 72.018505 -166.168807)
			(xy 72.069383 -166.254728) (xy 72.11303 -166.344539) (xy 72.149152 -166.437632) (xy 72.177502 -166.533378)
			(xy 72.197891 -166.631129) (xy 72.21018 -166.730225) (xy 72.214285 -166.829996) (xy 72.21018 -166.929767)
			(xy 72.197892 -167.028863) (xy 72.177504 -167.126615) (xy 72.149154 -167.222361) (xy 72.113034 -167.315454)
			(xy 72.069387 -167.405265) (xy 72.018509 -167.491187) (xy 71.960744 -167.572638) (xy 71.896483 -167.649068)
			(xy 71.826159 -167.71996) (xy 71.788528 -167.752776) (xy 71.780497 -167.760345) (xy 71.771262 -167.780362)
			(xy 71.770748 -167.791384) (xy 71.770748 -167.8686) (xy 71.771287 -167.87962) (xy 71.780499 -167.899642)
			(xy 71.788528 -167.907208) (xy 71.824454 -167.938525) (xy 71.891832 -168.00594) (xy 71.953714 -168.078433)
			(xy 72.00972 -168.155557) (xy 72.059504 -168.236836) (xy 72.102759 -168.32177) (xy 72.139218 -168.409834)
			(xy 72.168658 -168.500488) (xy 72.190896 -168.593171) (xy 72.205795 -168.687313) (xy 72.213264 -168.782333)
			(xy 72.213724 -168.82999) (xy 72.213206 -168.880167) (xy 72.204921 -168.98018) (xy 72.188405 -169.079166)
			(xy 72.163773 -169.176451) (xy 72.131192 -169.271369) (xy 72.090885 -169.363274) (xy 72.043127 -169.451536)
			(xy 71.988244 -169.535553) (xy 71.926611 -169.614752) (xy 71.858649 -169.688592) (xy 71.784822 -169.756567)
			(xy 71.705634 -169.818215) (xy 71.621627 -169.873113) (xy 71.533373 -169.920887) (xy 71.441476 -169.961211)
			(xy 71.346564 -169.99381) (xy 71.249283 -170.01846) (xy 71.1503 -170.034993) (xy 71.050289 -170.043297)
			(xy 71.000112 -170.043856) (xy 70.952451 -170.043378) (xy 70.857423 -170.03588) (xy 70.763276 -170.020954)
			(xy 70.67059 -169.99869) (xy 70.579934 -169.969227) (xy 70.491869 -169.932745) (xy 70.406935 -169.88947)
			(xy 70.325657 -169.839667) (xy 70.248534 -169.783645) (xy 70.176042 -169.721747) (xy 70.108628 -169.654354)
			(xy 70.07733 -169.618406) (xy 70.06976 -169.610377) (xy 70.049744 -169.601144) (xy 70.038722 -169.600626)
			(xy 69.961506 -169.600626) (xy 69.950488 -169.601166) (xy 69.930474 -169.610387) (xy 69.922898 -169.618406)
			(xy 69.890343 -169.655732) (xy 69.820078 -169.725545) (xy 69.744358 -169.789402) (xy 69.663688 -169.846877)
			(xy 69.6214 -169.87266) (xy 69.612951 -169.878186) (xy 69.600899 -169.894363) (xy 69.595973 -169.913926)
			(xy 69.597016 -169.923968) (xy 69.599556 -169.941494) (xy 69.619114 -169.975022) (xy 69.643244 -169.993564)
			(xy 69.651361 -169.999244) (xy 69.670449 -170.004474) (xy 69.680328 -170.003724) (xy 69.680582 -170.003724)
			(xy 69.708715 -170.000303) (xy 69.765273 -169.996617) (xy 69.793612 -169.996358) (xy 69.836136 -169.99686)
			(xy 69.920794 -170.004989) (xy 70.004291 -170.021162) (xy 70.085862 -170.04523) (xy 70.164763 -170.076976)
			(xy 70.240273 -170.116108) (xy 70.311704 -170.162269) (xy 70.378402 -170.215037) (xy 70.439758 -170.273932)
			(xy 70.495213 -170.338414) (xy 70.544259 -170.407895) (xy 70.586449 -170.48174) (xy 70.621398 -170.559276)
			(xy 70.635622 -170.599354) (xy 70.635622 -170.599608) (xy 70.639551 -170.609388) (xy 70.653823 -170.624867)
			(xy 70.673102 -170.63333) (xy 70.683628 -170.633898) (xy 73.983596 -170.633898) (xy 73.994128 -170.633372)
			(xy 74.013415 -170.624903) (xy 74.027668 -170.609393) (xy 74.031602 -170.599608) (xy 74.031602 -170.599354)
			(xy 74.045706 -170.559465) (xy 74.080448 -170.482313) (xy 74.122357 -170.408807) (xy 74.171055 -170.339613)
			(xy 74.226102 -170.275354) (xy 74.287002 -170.216612) (xy 74.353203 -170.163917) (xy 74.424108 -170.117744)
			(xy 74.46137 -170.097704) (xy 74.474324 -170.090846) (xy 74.488548 -170.066716) (xy 74.487532 -169.96156)
			(xy 74.487013 -169.952266) (xy 74.480199 -169.93496) (xy 74.467689 -169.921195) (xy 74.459592 -169.916602)
			(xy 74.459338 -169.916602) (xy 74.41651 -169.894752) (xy 74.334095 -169.84522) (xy 74.255858 -169.789323)
			(xy 74.182287 -169.727412) (xy 74.113845 -169.659874) (xy 74.050961 -169.587133) (xy 73.994029 -169.509645)
			(xy 73.943406 -169.427896) (xy 73.899409 -169.342398) (xy 73.862314 -169.253688) (xy 73.832353 -169.16232)
			(xy 73.809715 -169.068869) (xy 73.794542 -168.973919) (xy 73.786927 -168.878067) (xy 73.786492 -168.82999)
			(xy 73.786959 -168.782334) (xy 73.794435 -168.687314) (xy 73.809338 -168.593174) (xy 73.831578 -168.500492)
			(xy 73.861018 -168.40984) (xy 73.897476 -168.321776) (xy 73.940728 -168.236841) (xy 73.990508 -168.155561)
			(xy 74.046508 -168.078434) (xy 74.108383 -168.005936) (xy 74.175754 -167.938514) (xy 74.211688 -167.907208)
			(xy 74.219715 -167.899637) (xy 74.22894 -167.87962) (xy 74.229468 -167.8686) (xy 74.229468 -167.791384)
			(xy 74.228924 -167.780368) (xy 74.219697 -167.760361) (xy 74.211688 -167.752776) (xy 74.174065 -167.719951)
			(xy 74.103747 -167.649058) (xy 74.03949 -167.572627) (xy 73.98173 -167.491176) (xy 73.930856 -167.405255)
			(xy 73.887213 -167.315445) (xy 73.851095 -167.222353) (xy 73.822747 -167.126608) (xy 73.802361 -167.028859)
			(xy 73.790074 -166.929765) (xy 73.785969 -166.829996) (xy 73.790074 -166.730228) (xy 73.802362 -166.631134)
			(xy 73.822749 -166.533384) (xy 73.851098 -166.43764) (xy 73.887216 -166.344548) (xy 73.93086 -166.254738)
			(xy 73.981734 -166.168818) (xy 74.039495 -166.087367) (xy 74.103752 -166.010936) (xy 74.174071 -165.940043)
			(xy 74.211688 -165.907212) (xy 74.219715 -165.899642) (xy 74.228942 -165.879625) (xy 74.229468 -165.868604)
			(xy 74.229468 -165.791388) (xy 74.228924 -165.780372) (xy 74.219698 -165.760364) (xy 74.211688 -165.75278)
			(xy 74.175765 -165.721462) (xy 74.108392 -165.654044) (xy 74.046514 -165.581549) (xy 73.990513 -165.504424)
			(xy 73.940733 -165.423145) (xy 73.897483 -165.338211) (xy 73.861027 -165.250147) (xy 73.83159 -165.159495)
			(xy 73.809355 -165.066813) (xy 73.794457 -164.972673) (xy 73.78699 -164.877654) (xy 73.786492 -164.829998)
			(xy 73.78701 -164.77982) (xy 73.795296 -164.679806) (xy 73.811812 -164.580817) (xy 73.836445 -164.483531)
			(xy 73.869026 -164.38861) (xy 73.909333 -164.296704) (xy 73.957091 -164.208439) (xy 74.011973 -164.124419)
			(xy 74.073605 -164.045217) (xy 74.141566 -163.971374) (xy 74.215393 -163.903395) (xy 74.294579 -163.841744)
			(xy 74.378586 -163.786841) (xy 74.466839 -163.739062) (xy 74.558736 -163.698733) (xy 74.653649 -163.666129)
			(xy 74.75093 -163.641473) (xy 74.849914 -163.624933) (xy 74.949926 -163.616622) (xy 75.000104 -163.616132)
			(xy 75.047765 -163.616611) (xy 75.142792 -163.62411) (xy 75.236939 -163.639037) (xy 75.329625 -163.661301)
			(xy 75.420279 -163.690765) (xy 75.508344 -163.727248) (xy 75.593277 -163.770523) (xy 75.674555 -163.820326)
			(xy 75.751677 -163.876349) (xy 75.824168 -163.938247) (xy 75.891583 -164.005639) (xy 75.922886 -164.041582)
			(xy 75.930456 -164.04961) (xy 75.950473 -164.058839) (xy 75.961494 -164.059362) (xy 76.03871 -164.059362)
			(xy 76.049729 -164.058822) (xy 76.069749 -164.049608) (xy 76.077318 -164.041582) (xy 76.108628 -164.005643)
			(xy 76.176032 -163.938238) (xy 76.248517 -163.876329) (xy 76.325635 -163.820297) (xy 76.406911 -163.770488)
			(xy 76.491844 -163.727208) (xy 76.579911 -163.690725) (xy 76.670568 -163.661263) (xy 76.763258 -163.639005)
			(xy 76.857408 -163.624086) (xy 76.952438 -163.6166) (xy 77.0001 -163.616132) (xy 77.050267 -163.61665)
			(xy 77.150257 -163.624934) (xy 77.249222 -163.641447) (xy 77.346486 -163.666075) (xy 77.441384 -163.698649)
			(xy 77.533268 -163.738948) (xy 77.621511 -163.786697) (xy 77.70551 -163.841569) (xy 77.784692 -163.903189)
			(xy 77.858515 -163.971137) (xy 77.926475 -164.044948) (xy 77.988109 -164.124119) (xy 78.042995 -164.208108)
			(xy 78.090759 -164.296343) (xy 78.131074 -164.38822) (xy 78.163665 -164.483113) (xy 78.18831 -164.580372)
			(xy 78.20484 -164.679334) (xy 78.213141 -164.779324) (xy 78.213712 -164.82949) (xy 78.213712 -164.829998)
			(xy 78.213245 -164.877655) (xy 78.205771 -164.972674) (xy 78.190868 -165.066815) (xy 78.168629 -165.159498)
			(xy 78.13919 -165.250151) (xy 78.102732 -165.338216) (xy 78.059481 -165.423151) (xy 78.009702 -165.504432)
			(xy 77.953702 -165.58156) (xy 77.891827 -165.654058) (xy 77.824457 -165.721481) (xy 77.788516 -165.75278)
			(xy 77.780487 -165.76035) (xy 77.771256 -165.780367) (xy 77.770736 -165.791388) (xy 77.770736 -165.868604)
			(xy 77.771279 -165.879621) (xy 77.780503 -165.899631) (xy 77.788516 -165.907212) (xy 77.826139 -165.940037)
			(xy 77.896458 -166.01093) (xy 77.960716 -166.087361) (xy 78.018477 -166.168813) (xy 78.069352 -166.254734)
			(xy 78.112996 -166.344545) (xy 78.149114 -166.437637) (xy 78.177462 -166.533382) (xy 78.19785 -166.631132)
			(xy 78.210137 -166.730227) (xy 78.214243 -166.829996) (xy 78.210138 -166.929765) (xy 78.197851 -167.02886)
			(xy 78.177464 -167.12661) (xy 78.149116 -167.222355) (xy 78.112999 -167.315448) (xy 78.069355 -167.405259)
			(xy 78.018481 -167.49118) (xy 77.96072 -167.572632) (xy 77.896463 -167.649064) (xy 77.826145 -167.719958)
			(xy 77.788516 -167.752776) (xy 77.780486 -167.760345) (xy 77.771254 -167.780362) (xy 77.770736 -167.791384)
			(xy 77.770736 -167.8686) (xy 77.771278 -167.879617) (xy 77.780501 -167.899628) (xy 77.788516 -167.907208)
			(xy 77.826739 -167.940564) (xy 77.898101 -168.012681) (xy 77.963195 -168.090502) (xy 78.021569 -168.173483)
			(xy 78.072814 -168.261046) (xy 78.116574 -168.35258) (xy 78.152543 -168.447446) (xy 78.18047 -168.544983)
			(xy 78.200161 -168.64451) (xy 78.206346 -168.694862) (xy 78.208011 -168.705286) (xy 78.218537 -168.723555)
			(xy 78.235531 -168.736036) (xy 78.245716 -168.738804) (xy 78.339696 -168.759632) (xy 78.350041 -168.76138)
			(xy 78.370603 -168.75733) (xy 78.387838 -168.745406) (xy 78.393798 -168.736772) (xy 78.441296 -168.658537)
			(xy 78.529916 -168.498373) (xy 78.611087 -168.334308) (xy 78.684636 -168.166689) (xy 78.75041 -167.995868)
			(xy 78.808269 -167.822206) (xy 78.858092 -167.646071) (xy 78.899772 -167.467833) (xy 78.933222 -167.287869)
			(xy 78.958372 -167.106559) (xy 78.975168 -166.924284) (xy 78.983576 -166.741431) (xy 78.984094 -166.649908)
			(xy 78.984094 -166.360094) (xy 78.965298 -166.333932) (xy 78.949804 -166.328598) (xy 78.909724 -166.314413)
			(xy 78.83223 -166.279428) (xy 78.758427 -166.237208) (xy 78.68899 -166.188139) (xy 78.624551 -166.132668)
			(xy 78.565699 -166.071302) (xy 78.512971 -166.004601) (xy 78.466848 -165.933172) (xy 78.427751 -165.857669)
			(xy 78.396036 -165.77878) (xy 78.371994 -165.697224) (xy 78.355842 -165.613747) (xy 78.34773 -165.529109)
			(xy 78.34773 -165.444083) (xy 78.355843 -165.359446) (xy 78.371995 -165.275968) (xy 78.396039 -165.194413)
			(xy 78.427754 -165.115524) (xy 78.466852 -165.040021) (xy 78.512976 -164.968593) (xy 78.565704 -164.901892)
			(xy 78.624557 -164.840526) (xy 78.688996 -164.785056) (xy 78.758434 -164.735988) (xy 78.832237 -164.693769)
			(xy 78.909732 -164.658784) (xy 78.949804 -164.644578) (xy 78.965298 -164.639244) (xy 78.984094 -164.613082)
			(xy 78.984094 -161.299906) (xy 78.9846 -161.209783) (xy 78.992686 -161.02972) (xy 79.008843 -160.8502)
			(xy 79.033037 -160.671586) (xy 79.065221 -160.494237) (xy 79.105329 -160.318511) (xy 79.153281 -160.144761)
			(xy 79.208979 -159.973337) (xy 79.272313 -159.804585) (xy 79.343153 -159.638844) (xy 79.421359 -159.476449)
			(xy 79.506771 -159.317726) (xy 79.599218 -159.162994) (xy 79.698514 -159.012566) (xy 79.80446 -158.866744)
			(xy 79.916841 -158.725822) (xy 80.035431 -158.590085) (xy 80.159991 -158.459804) (xy 80.290271 -158.335243)
			(xy 80.426009 -158.216652) (xy 80.56693 -158.104271) (xy 80.712751 -157.998325) (xy 80.863179 -157.899028)
			(xy 81.01791 -157.80658) (xy 81.176633 -157.721167) (xy 81.339028 -157.642961) (xy 81.504768 -157.572119)
			(xy 81.67352 -157.508785) (xy 81.844944 -157.453086) (xy 82.018693 -157.405134) (xy 82.194419 -157.365025)
			(xy 82.371768 -157.33284) (xy 82.550382 -157.308645) (xy 82.729902 -157.292487) (xy 82.909965 -157.2844)
			(xy 83.000088 -157.283912) (xy 83.256882 -157.283912) (xy 83.28406 -157.263084) (xy 83.288632 -157.246574)
			(xy 83.30005 -157.206781) (xy 83.329295 -157.129326) (xy 83.365612 -157.054924) (xy 83.408685 -156.984219)
			(xy 83.458141 -156.917822) (xy 83.513554 -156.856308) (xy 83.574443 -156.800209) (xy 83.640281 -156.750012)
			(xy 83.7105 -156.706149) (xy 83.78449 -156.669001) (xy 83.861612 -156.638889) (xy 83.941198 -156.616074)
			(xy 84.02256 -156.600753) (xy 84.104994 -156.593058) (xy 84.14639 -156.592524) (xy 84.190299 -156.593054)
			(xy 84.27769 -156.601708) (xy 84.363802 -156.618934) (xy 84.447797 -156.644562) (xy 84.528857 -156.678345)
			(xy 84.606193 -156.719952) (xy 84.679052 -156.768979) (xy 84.746724 -156.824948) (xy 84.80855 -156.887314)
			(xy 84.863928 -156.955471) (xy 84.888578 -156.991812) (xy 84.895425 -157.001196) (xy 84.915398 -157.013007)
			(xy 84.938531 -157.014831) (xy 84.949538 -157.011116) (xy 85.028187 -156.979904) (xy 85.183051 -156.91167)
			(xy 85.334879 -156.836923) (xy 85.483397 -156.755799) (xy 85.628337 -156.668442) (xy 85.769438 -156.575012)
			(xy 85.906446 -156.475676) (xy 86.039113 -156.370613) (xy 86.10346 -156.315664) (xy 86.111877 -156.307763)
			(xy 86.121106 -156.286628) (xy 86.12014 -156.263587) (xy 86.115144 -156.25318) (xy 86.094763 -156.214247)
			(xy 86.0609 -156.133149) (xy 86.035206 -156.049105) (xy 86.017931 -155.962935) (xy 86.009244 -155.875482)
			(xy 86.008718 -155.83154) (xy 86.009176 -155.790436) (xy 86.016758 -155.708579) (xy 86.031861 -155.62777)
			(xy 86.054356 -155.5487) (xy 86.08405 -155.472042) (xy 86.120692 -155.398452) (xy 86.163967 -155.328557)
			(xy 86.213508 -155.262953) (xy 86.26889 -155.2022) (xy 86.329642 -155.146817) (xy 86.395245 -155.097275)
			(xy 86.46514 -155.053999) (xy 86.53873 -155.017356) (xy 86.615386 -154.98766) (xy 86.694456 -154.965164)
			(xy 86.775265 -154.95006) (xy 86.857122 -154.942477) (xy 86.898226 -154.942032) (xy 86.89848 -154.942032)
			(xy 86.943632 -154.942586) (xy 87.03347 -154.951748) (xy 87.077804 -154.96032) (xy 87.088218 -154.961336)
			(xy 87.097967 -154.960907) (xy 87.116052 -154.953625) (xy 87.130086 -154.940093) (xy 87.134446 -154.931364)
			(xy 87.172195 -154.845944) (xy 87.240623 -154.672155) (xy 87.300833 -154.495351) (xy 87.352694 -154.315921)
			(xy 87.39609 -154.134257) (xy 87.430927 -153.950759) (xy 87.457128 -153.765831) (xy 87.474635 -153.579878)
			(xy 87.483411 -153.393309) (xy 87.48395 -153.299922) (xy 87.48395 -152.024842) (xy 87.483435 -152.014266)
			(xy 87.474913 -151.994911) (xy 87.459273 -151.980676) (xy 87.449406 -151.976836) (xy 87.409233 -151.962711)
			(xy 87.331545 -151.92782) (xy 87.257548 -151.885665) (xy 87.187919 -151.83663) (xy 87.123295 -151.781165)
			(xy 87.064268 -151.719777) (xy 87.011379 -151.653028) (xy 86.965111 -151.58153) (xy 86.925889 -151.505937)
			(xy 86.894071 -151.426941) (xy 86.869949 -151.345266) (xy 86.853744 -151.26166) (xy 86.845604 -151.176887)
			(xy 86.845603 -151.091724) (xy 86.853742 -151.006952) (xy 86.869946 -150.923345) (xy 86.894067 -150.84167)
			(xy 86.925884 -150.762674) (xy 86.965105 -150.68708) (xy 87.011372 -150.615582) (xy 87.06426 -150.548832)
			(xy 87.123286 -150.487443) (xy 87.18791 -150.431977) (xy 87.257538 -150.382941) (xy 87.331535 -150.340785)
			(xy 87.409222 -150.305894) (xy 87.449406 -150.2918) (xy 87.45924 -150.287907) (xy 87.474843 -150.273661)
			(xy 87.483425 -150.254355) (xy 87.48395 -150.243794) (xy 87.48395 -146.944842) (xy 87.483435 -146.934266)
			(xy 87.474913 -146.914911) (xy 87.459273 -146.900676) (xy 87.449406 -146.896836) (xy 87.409233 -146.882711)
			(xy 87.331545 -146.84782) (xy 87.257548 -146.805665) (xy 87.187919 -146.75663) (xy 87.123295 -146.701165)
			(xy 87.064268 -146.639777) (xy 87.011379 -146.573028) (xy 86.965111 -146.50153) (xy 86.925889 -146.425937)
			(xy 86.894071 -146.346941) (xy 86.869949 -146.265266) (xy 86.853744 -146.18166) (xy 86.845604 -146.096887)
			(xy 86.845603 -146.011724) (xy 86.853742 -145.926952) (xy 86.869946 -145.843345) (xy 86.894067 -145.76167)
			(xy 86.925884 -145.682674) (xy 86.965105 -145.60708) (xy 87.011372 -145.535582) (xy 87.06426 -145.468832)
			(xy 87.123286 -145.407443) (xy 87.18791 -145.351977) (xy 87.257538 -145.302941) (xy 87.331535 -145.260785)
			(xy 87.409222 -145.225894) (xy 87.449406 -145.2118) (xy 87.45924 -145.207907) (xy 87.474843 -145.193661)
			(xy 87.483425 -145.174355) (xy 87.48395 -145.163794) (xy 87.48395 -141.864842) (xy 87.483435 -141.854266)
			(xy 87.474913 -141.834911) (xy 87.459273 -141.820676) (xy 87.449406 -141.816836) (xy 87.409233 -141.802711)
			(xy 87.331545 -141.76782) (xy 87.257548 -141.725665) (xy 87.187919 -141.67663) (xy 87.123295 -141.621165)
			(xy 87.064268 -141.559777) (xy 87.011379 -141.493028) (xy 86.965111 -141.42153) (xy 86.925889 -141.345937)
			(xy 86.894071 -141.266941) (xy 86.869949 -141.185266) (xy 86.853744 -141.10166) (xy 86.845604 -141.016887)
			(xy 86.845603 -140.931724) (xy 86.853742 -140.846952) (xy 86.869946 -140.763345) (xy 86.894067 -140.68167)
			(xy 86.925884 -140.602674) (xy 86.965105 -140.52708) (xy 87.011372 -140.455582) (xy 87.06426 -140.388832)
			(xy 87.123286 -140.327443) (xy 87.18791 -140.271977) (xy 87.257538 -140.222941) (xy 87.331535 -140.180785)
			(xy 87.409222 -140.145894) (xy 87.449406 -140.1318) (xy 87.45924 -140.127907) (xy 87.474843 -140.113661)
			(xy 87.483425 -140.094355) (xy 87.48395 -140.083794) (xy 87.48395 -136.784842) (xy 87.483435 -136.774266)
			(xy 87.474913 -136.754911) (xy 87.459273 -136.740676) (xy 87.449406 -136.736836) (xy 87.409233 -136.722711)
			(xy 87.331545 -136.68782) (xy 87.257548 -136.645665) (xy 87.187919 -136.59663) (xy 87.123295 -136.541165)
			(xy 87.064268 -136.479777) (xy 87.011379 -136.413028) (xy 86.965111 -136.34153) (xy 86.925889 -136.265937)
			(xy 86.894071 -136.186941) (xy 86.869949 -136.105266) (xy 86.853744 -136.02166) (xy 86.845604 -135.936887)
			(xy 86.845603 -135.851724) (xy 86.853742 -135.766952) (xy 86.869946 -135.683345) (xy 86.894067 -135.60167)
			(xy 86.925884 -135.522674) (xy 86.965105 -135.44708) (xy 87.011372 -135.375582) (xy 87.06426 -135.308832)
			(xy 87.123286 -135.247443) (xy 87.18791 -135.191977) (xy 87.257538 -135.142941) (xy 87.331535 -135.100785)
			(xy 87.409222 -135.065894) (xy 87.449406 -135.0518) (xy 87.45924 -135.047907) (xy 87.474843 -135.033661)
			(xy 87.483425 -135.014355) (xy 87.48395 -135.003794) (xy 87.48395 -131.704842) (xy 87.483435 -131.694266)
			(xy 87.474913 -131.674911) (xy 87.459273 -131.660676) (xy 87.449406 -131.656836) (xy 87.409233 -131.642711)
			(xy 87.331545 -131.60782) (xy 87.257548 -131.565665) (xy 87.187919 -131.51663) (xy 87.123295 -131.461165)
			(xy 87.064268 -131.399777) (xy 87.011379 -131.333028) (xy 86.965111 -131.26153) (xy 86.925889 -131.185937)
			(xy 86.894071 -131.106941) (xy 86.869949 -131.025266) (xy 86.853744 -130.94166) (xy 86.845604 -130.856887)
			(xy 86.845603 -130.771724) (xy 86.853742 -130.686952) (xy 86.869946 -130.603345) (xy 86.894067 -130.52167)
			(xy 86.925884 -130.442674) (xy 86.965105 -130.36708) (xy 87.011372 -130.295582) (xy 87.06426 -130.228832)
			(xy 87.123286 -130.167443) (xy 87.18791 -130.111977) (xy 87.257538 -130.062941) (xy 87.331535 -130.020785)
			(xy 87.409222 -129.985894) (xy 87.449406 -129.9718) (xy 87.45924 -129.967907) (xy 87.474843 -129.953661)
			(xy 87.483425 -129.934355) (xy 87.48395 -129.923794) (xy 87.48395 -126.624842) (xy 87.483435 -126.614266)
			(xy 87.474913 -126.594911) (xy 87.459273 -126.580676) (xy 87.449406 -126.576836) (xy 87.409233 -126.562711)
			(xy 87.331545 -126.52782) (xy 87.257548 -126.485665) (xy 87.187919 -126.43663) (xy 87.123295 -126.381165)
			(xy 87.064268 -126.319777) (xy 87.011379 -126.253028) (xy 86.965111 -126.18153) (xy 86.925889 -126.105937)
			(xy 86.894071 -126.026941) (xy 86.869949 -125.945266) (xy 86.853744 -125.86166) (xy 86.845604 -125.776887)
			(xy 86.845603 -125.691724) (xy 86.853742 -125.606952) (xy 86.869946 -125.523345) (xy 86.894067 -125.44167)
			(xy 86.925884 -125.362674) (xy 86.965105 -125.28708) (xy 87.011372 -125.215582) (xy 87.06426 -125.148832)
			(xy 87.123286 -125.087443) (xy 87.18791 -125.031977) (xy 87.257538 -124.982941) (xy 87.331535 -124.940785)
			(xy 87.409222 -124.905894) (xy 87.449406 -124.8918) (xy 87.45924 -124.887907) (xy 87.474843 -124.873661)
			(xy 87.483425 -124.854355) (xy 87.48395 -124.843794) (xy 87.48395 -121.544842) (xy 87.483435 -121.534266)
			(xy 87.474913 -121.514911) (xy 87.459273 -121.500676) (xy 87.449406 -121.496836) (xy 87.409233 -121.482711)
			(xy 87.331545 -121.44782) (xy 87.257548 -121.405665) (xy 87.187919 -121.35663) (xy 87.123295 -121.301165)
			(xy 87.064268 -121.239777) (xy 87.011379 -121.173028) (xy 86.965111 -121.10153) (xy 86.925889 -121.025937)
			(xy 86.894071 -120.946941) (xy 86.869949 -120.865266) (xy 86.853744 -120.78166) (xy 86.845604 -120.696887)
			(xy 86.845603 -120.611724) (xy 86.853742 -120.526952) (xy 86.869946 -120.443345) (xy 86.894067 -120.36167)
			(xy 86.925884 -120.282674) (xy 86.965105 -120.20708) (xy 87.011372 -120.135582) (xy 87.06426 -120.068832)
			(xy 87.123286 -120.007443) (xy 87.18791 -119.951977) (xy 87.257538 -119.902941) (xy 87.331535 -119.860785)
			(xy 87.409222 -119.825894) (xy 87.449406 -119.8118) (xy 87.45924 -119.807907) (xy 87.474843 -119.793661)
			(xy 87.483425 -119.774355) (xy 87.48395 -119.763794) (xy 87.48395 -116.464842) (xy 87.483435 -116.454266)
			(xy 87.474913 -116.434911) (xy 87.459273 -116.420676) (xy 87.449406 -116.416836) (xy 87.409233 -116.402711)
			(xy 87.331545 -116.36782) (xy 87.257548 -116.325665) (xy 87.187919 -116.27663) (xy 87.123295 -116.221165)
			(xy 87.064268 -116.159777) (xy 87.011379 -116.093028) (xy 86.965111 -116.02153) (xy 86.925889 -115.945937)
			(xy 86.894071 -115.866941) (xy 86.869949 -115.785266) (xy 86.853744 -115.70166) (xy 86.845604 -115.616887)
			(xy 86.845603 -115.531724) (xy 86.853742 -115.446952) (xy 86.869946 -115.363345) (xy 86.894067 -115.28167)
			(xy 86.925884 -115.202674) (xy 86.965105 -115.12708) (xy 87.011372 -115.055582) (xy 87.06426 -114.988832)
			(xy 87.123286 -114.927443) (xy 87.18791 -114.871977) (xy 87.257538 -114.822941) (xy 87.331535 -114.780785)
			(xy 87.409222 -114.745894) (xy 87.449406 -114.7318) (xy 87.45924 -114.727907) (xy 87.474843 -114.713661)
			(xy 87.483425 -114.694355) (xy 87.48395 -114.683794) (xy 87.48395 -111.384842) (xy 87.483435 -111.374266)
			(xy 87.474913 -111.354911) (xy 87.459273 -111.340676) (xy 87.449406 -111.336836) (xy 87.409237 -111.322707)
			(xy 87.331557 -111.287812) (xy 87.257568 -111.245652) (xy 87.187947 -111.196615) (xy 87.123331 -111.141148)
			(xy 87.064311 -111.07976) (xy 87.011428 -111.013013) (xy 86.965167 -110.941517) (xy 86.925949 -110.865928)
			(xy 86.894135 -110.786936) (xy 86.870016 -110.705266) (xy 86.853812 -110.621664) (xy 86.845672 -110.536897)
			(xy 86.84514 -110.494318) (xy 86.845606 -110.453059) (xy 86.853247 -110.370897) (xy 86.868464 -110.289795)
			(xy 86.891126 -110.21045) (xy 86.921039 -110.133546) (xy 86.957946 -110.059742) (xy 87.001529 -109.989673)
			(xy 87.051414 -109.923942) (xy 87.107172 -109.863114) (xy 87.168324 -109.80771) (xy 87.234343 -109.758208)
			(xy 87.304664 -109.715033) (xy 87.378681 -109.678556) (xy 87.455758 -109.64909) (xy 87.49538 -109.637576)
			(xy 87.53221 -109.593888) (xy 87.540084 -109.523784) (xy 87.549189 -109.446216) (xy 87.569891 -109.291393)
			(xy 87.581486 -109.214158) (xy 87.607648 -109.053122) (xy 87.630302 -108.924668) (xy 87.682483 -108.669069)
			(xy 87.74247 -108.415189) (xy 87.810207 -108.163267) (xy 87.88563 -107.913537) (xy 87.926672 -107.789726)
			(xy 87.964065 -107.67963) (xy 88.044091 -107.461288) (xy 88.130051 -107.245214) (xy 88.221881 -107.031569)
			(xy 88.270334 -106.925872) (xy 88.274188 -106.916457) (xy 88.274876 -106.896143) (xy 88.267617 -106.877158)
			(xy 88.260936 -106.869484) (xy 88.232229 -106.838517) (xy 88.18016 -106.772033) (xy 88.134627 -106.700913)
			(xy 88.096041 -106.625797) (xy 88.064749 -106.547361) (xy 88.041033 -106.466313) (xy 88.025105 -106.383381)
			(xy 88.017111 -106.299314) (xy 88.016588 -106.25709) (xy 88.017063 -106.215988) (xy 88.024649 -106.134134)
			(xy 88.039755 -106.053329) (xy 88.062252 -105.974263) (xy 88.091948 -105.89761) (xy 88.12859 -105.824024)
			(xy 88.171866 -105.754132) (xy 88.221405 -105.688532) (xy 88.276786 -105.627782) (xy 88.337536 -105.572401)
			(xy 88.403137 -105.522862) (xy 88.473029 -105.479587) (xy 88.546615 -105.442945) (xy 88.623269 -105.41325)
			(xy 88.702335 -105.390753) (xy 88.78314 -105.375648) (xy 88.864994 -105.368063) (xy 88.906096 -105.367582)
			(xy 88.945644 -105.368024) (xy 89.024428 -105.375065) (xy 89.102276 -105.389064) (xy 89.140538 -105.399078)
			(xy 89.150464 -105.401342) (xy 89.170632 -105.398692) (xy 89.188181 -105.388406) (xy 89.19464 -105.380536)
			(xy 89.258187 -105.296581) (xy 89.388884 -105.131461) (xy 89.456006 -105.050336) (xy 89.521792 -104.972104)
			(xy 89.528904 -104.963976) (xy 89.534746 -104.957118) (xy 89.536524 -104.955086) (xy 89.536778 -104.954832)
			(xy 89.628933 -104.84827) (xy 89.819346 -104.640582) (xy 89.917524 -104.539542) (xy 89.995751 -104.460251)
			(xy 90.155792 -104.305292) (xy 90.237564 -104.229662) (xy 90.339389 -104.136831) (xy 90.548213 -103.957012)
			(xy 90.762744 -103.784041) (xy 90.982757 -103.6181) (xy 91.095068 -103.538274) (xy 91.116658 -103.496872)
			(xy 91.115134 -103.484934) (xy 91.103743 -103.434069) (xy 91.091517 -103.330551) (xy 91.09075 -103.278432)
			(xy 91.091223 -103.237328) (xy 91.098805 -103.15547) (xy 91.113908 -103.074661) (xy 91.136402 -102.99559)
			(xy 91.166097 -102.918932) (xy 91.202737 -102.845341) (xy 91.246011 -102.775444) (xy 91.29555 -102.709838)
			(xy 91.350931 -102.649083) (xy 91.411681 -102.593698) (xy 91.477283 -102.544153) (xy 91.547176 -102.500873)
			(xy 91.620764 -102.464226) (xy 91.69742 -102.434526) (xy 91.776489 -102.412025) (xy 91.857297 -102.396916)
			(xy 91.939154 -102.389327) (xy 91.980258 -102.388924) (xy 92.024167 -102.389457) (xy 92.111557 -102.398114)
			(xy 92.19767 -102.415338) (xy 92.281667 -102.440962) (xy 92.36273 -102.474737) (xy 92.440072 -102.516333)
			(xy 92.51294 -102.565346) (xy 92.580625 -102.621299) (xy 92.611956 -102.652068) (xy 92.619388 -102.65896)
			(xy 92.638078 -102.666758) (xy 92.658329 -102.666756) (xy 92.667836 -102.663244) (xy 92.812362 -102.603046)
			(xy 92.81287 -102.603046) (xy 92.81541 -102.601776) (xy 92.815918 -102.601776) (xy 92.978224 -102.538022)
			(xy 93.112336 -102.488492) (xy 93.23578 -102.445058) (xy 93.239336 -102.443788) (xy 93.250004 -102.440232)
			(xy 93.252036 -102.43947) (xy 93.316572 -102.417607) (xy 93.446246 -102.375694) (xy 93.51137 -102.35565)
			(xy 93.566864 -102.338793) (xy 93.678247 -102.306406) (xy 93.734128 -102.29088) (xy 93.851535 -102.258927)
			(xy 94.087874 -102.200919) (xy 94.325774 -102.149685) (xy 94.445328 -102.12705) (xy 94.571788 -102.104076)
			(xy 94.825831 -102.064825) (xy 94.953328 -102.048564) (xy 95.10148 -102.030862) (xy 95.398729 -102.004567)
			(xy 95.547688 -101.995986) (xy 95.557881 -101.995026) (xy 95.576306 -101.986138) (xy 95.589806 -101.970769)
			(xy 95.593408 -101.961188) (xy 95.60723 -101.920536) (xy 95.641637 -101.84186) (xy 95.683468 -101.766868)
			(xy 95.732333 -101.696257) (xy 95.787777 -101.630686) (xy 95.849283 -101.570765) (xy 95.91628 -101.517051)
			(xy 95.988142 -101.470046) (xy 96.0642 -101.430187) (xy 96.143747 -101.397845) (xy 96.22604 -101.373322)
			(xy 96.310315 -101.356846) (xy 96.395785 -101.348571) (xy 96.43872 -101.348032) (xy 96.481198 -101.348532)
			(xy 96.565766 -101.356641) (xy 96.649177 -101.372774) (xy 96.73067 -101.396784) (xy 96.809503 -101.428452)
			(xy 96.884959 -101.46749) (xy 96.95635 -101.513543) (xy 97.023026 -101.566191) (xy 97.084381 -101.624955)
			(xy 97.139855 -101.689299) (xy 97.188944 -101.758637) (xy 97.2312 -101.83234) (xy 97.266238 -101.909734)
			(xy 97.280476 -101.949758) (xy 97.28581 -101.965252) (xy 97.311972 -101.984048) (xy 100.645468 -101.984048)
			(xy 100.67163 -101.965252) (xy 100.676964 -101.949758) (xy 100.691175 -101.90972) (xy 100.726201 -101.832311)
			(xy 100.768448 -101.758595) (xy 100.817531 -101.689242) (xy 100.873003 -101.624885) (xy 100.934358 -101.56611)
			(xy 101.001038 -101.513453) (xy 101.072434 -101.467393) (xy 101.147897 -101.428351) (xy 101.226739 -101.396681)
			(xy 101.308241 -101.372673) (xy 101.39166 -101.356545) (xy 101.476238 -101.348444) (xy 101.561202 -101.348444)
			(xy 101.64578 -101.356545) (xy 101.729199 -101.372673) (xy 101.810701 -101.396681) (xy 101.889543 -101.428351)
			(xy 101.965006 -101.467393) (xy 102.036402 -101.513453) (xy 102.103082 -101.56611) (xy 102.164437 -101.624885)
			(xy 102.219909 -101.689242) (xy 102.268992 -101.758595) (xy 102.311239 -101.832311) (xy 102.346265 -101.90972)
			(xy 102.360476 -101.949758) (xy 102.36581 -101.965252) (xy 102.391972 -101.984048) (xy 105.725468 -101.984048)
			(xy 105.75163 -101.965252) (xy 105.756964 -101.949758) (xy 105.771175 -101.90972) (xy 105.806201 -101.832311)
			(xy 105.848448 -101.758595) (xy 105.897531 -101.689242) (xy 105.953003 -101.624885) (xy 106.014358 -101.56611)
			(xy 106.081038 -101.513453) (xy 106.152434 -101.467393) (xy 106.227897 -101.428351) (xy 106.306739 -101.396681)
			(xy 106.388241 -101.372673) (xy 106.47166 -101.356545) (xy 106.556238 -101.348444) (xy 106.641202 -101.348444)
			(xy 106.72578 -101.356545) (xy 106.809199 -101.372673) (xy 106.890701 -101.396681) (xy 106.969543 -101.428351)
			(xy 107.045006 -101.467393) (xy 107.116402 -101.513453) (xy 107.183082 -101.56611) (xy 107.244437 -101.624885)
			(xy 107.299909 -101.689242) (xy 107.348992 -101.758595) (xy 107.391239 -101.832311) (xy 107.426265 -101.90972)
			(xy 107.440476 -101.949758) (xy 107.44581 -101.965252) (xy 107.471972 -101.984048) (xy 110.805468 -101.984048)
			(xy 110.83163 -101.965252) (xy 110.836964 -101.949758) (xy 110.851175 -101.90972) (xy 110.886201 -101.832311)
			(xy 110.928448 -101.758595) (xy 110.977531 -101.689242) (xy 111.033003 -101.624885) (xy 111.094358 -101.56611)
			(xy 111.161038 -101.513453) (xy 111.232434 -101.467393) (xy 111.307897 -101.428351) (xy 111.386739 -101.396681)
			(xy 111.468241 -101.372673) (xy 111.55166 -101.356545) (xy 111.636238 -101.348444) (xy 111.721202 -101.348444)
			(xy 111.80578 -101.356545) (xy 111.889199 -101.372673) (xy 111.970701 -101.396681) (xy 112.049543 -101.428351)
			(xy 112.125006 -101.467393) (xy 112.196402 -101.513453) (xy 112.263082 -101.56611) (xy 112.324437 -101.624885)
			(xy 112.379909 -101.689242) (xy 112.428992 -101.758595) (xy 112.471239 -101.832311) (xy 112.506265 -101.90972)
			(xy 112.520476 -101.949758) (xy 112.52581 -101.965252) (xy 112.551972 -101.984048) (xy 114.146584 -101.984048)
			(xy 114.156597 -101.983563) (xy 114.175103 -101.975908) (xy 114.189272 -101.961757) (xy 114.196951 -101.943261)
			(xy 114.197384 -101.933248) (xy 114.197384 -85.1281) (xy 114.197847 -85.097399) (xy 114.205248 -85.036446)
			(xy 114.219942 -84.976828) (xy 114.241715 -84.919417) (xy 114.270249 -84.865049) (xy 114.305128 -84.814516)
			(xy 114.345844 -84.768556) (xy 114.391803 -84.727838) (xy 114.442335 -84.692957) (xy 114.496702 -84.664422)
			(xy 114.554113 -84.642647) (xy 114.61373 -84.627951) (xy 114.674683 -84.620548) (xy 114.705384 -84.6201)
			(xy 123.9012 -84.6201) (xy 123.93446 -84.620621) (xy 124.00041 -84.629309) (xy 124.064661 -84.646534)
			(xy 124.126112 -84.672003) (xy 124.183711 -84.705279) (xy 124.236471 -84.745792) (xy 124.260356 -84.768944)
			(xy 126.954026 -87.462614) (xy 126.961422 -87.469466) (xy 126.980021 -87.477204) (xy 126.990094 -87.4776)
			(xy 132.966206 -87.4776) (xy 132.976276 -87.477176) (xy 132.994879 -87.46946) (xy 133.002274 -87.462614)
			(xy 135.695944 -84.768944) (xy 135.719824 -84.745788) (xy 135.772588 -84.705282) (xy 135.830189 -84.672011)
			(xy 135.89164 -84.646547) (xy 135.955891 -84.629325) (xy 136.021841 -84.620639) (xy 136.0551 -84.6201)
			(xy 156.16936 -84.6201) (xy 156.178382 -84.619696) (xy 156.195282 -84.613364) (xy 156.208947 -84.601576)
			(xy 156.217688 -84.585787) (xy 156.219398 -84.57692) (xy 156.226148 -84.5353) (xy 156.246505 -84.453471)
			(xy 156.274515 -84.373937) (xy 156.309927 -84.29741) (xy 156.352422 -84.224579) (xy 156.40162 -84.156096)
			(xy 156.457078 -84.092576) (xy 156.518298 -84.034591) (xy 156.584732 -83.982659) (xy 156.655782 -83.937248)
			(xy 156.730812 -83.898766) (xy 156.809146 -83.867556) (xy 156.890083 -83.843901) (xy 156.972895 -83.828012)
			(xy 157.056839 -83.820032) (xy 157.141161 -83.820032) (xy 157.225105 -83.828012) (xy 157.307917 -83.843901)
			(xy 157.388854 -83.867556) (xy 157.467188 -83.898766) (xy 157.542218 -83.937248) (xy 157.613268 -83.982659)
			(xy 157.679702 -84.034591) (xy 157.740922 -84.092576) (xy 157.79638 -84.156096) (xy 157.845578 -84.224579)
			(xy 157.888073 -84.29741) (xy 157.923485 -84.373937) (xy 157.951495 -84.453471) (xy 157.971852 -84.5353)
			(xy 157.978602 -84.57692) (xy 157.981396 -84.595716) (xy 158.009844 -84.6201) (xy 166.283386 -84.6201)
			(xy 166.293247 -84.619591) (xy 166.311485 -84.612072) (xy 166.325558 -84.598248) (xy 166.329868 -84.589366)
			(xy 166.366952 -84.503768) (xy 166.368839 -84.498968) (xy 166.370881 -84.488859) (xy 166.371016 -84.483702)
			(xy 166.3573 -84.448904) (xy 166.32888 -84.417995) (xy 166.27735 -84.351694) (xy 166.232296 -84.280833)
			(xy 166.194118 -84.206042) (xy 166.163156 -84.127987) (xy 166.139685 -84.047363) (xy 166.123914 -83.964886)
			(xy 166.115984 -83.88129) (xy 166.115492 -83.839304) (xy 166.115492 -83.83905) (xy 166.11593 -83.799951)
			(xy 166.122817 -83.722056) (xy 166.136508 -83.645066) (xy 166.156898 -83.569572) (xy 166.183829 -83.496157)
			(xy 166.200074 -83.46059) (xy 166.20431 -83.450203) (xy 166.20431 -83.427797) (xy 166.200074 -83.41741)
			(xy 166.183811 -83.381849) (xy 166.156859 -83.308439) (xy 166.136461 -83.232944) (xy 166.122772 -83.15595)
			(xy 166.115898 -83.078051) (xy 166.115492 -83.03895) (xy 166.115988 -82.996488) (xy 166.124084 -82.91195)
			(xy 166.140197 -82.828569) (xy 166.164182 -82.747102) (xy 166.19582 -82.668291) (xy 166.234822 -82.592853)
			(xy 166.280835 -82.521473) (xy 166.333439 -82.454803) (xy 166.392155 -82.393448) (xy 166.456451 -82.337966)
			(xy 166.52574 -82.288863) (xy 166.599392 -82.246584) (xy 166.676738 -82.211515) (xy 166.757073 -82.183975)
			(xy 166.798244 -82.173572) (xy 166.798498 -82.173572) (xy 166.807749 -82.170931) (xy 166.823473 -82.15987)
			(xy 166.834004 -82.143788) (xy 166.836344 -82.134456) (xy 166.85768 -82.030062) (xy 166.847266 -82.002376)
			(xy 166.835328 -81.993486) (xy 166.802411 -81.968371) (xy 166.740893 -81.912944) (xy 166.684792 -81.852041)
			(xy 166.634592 -81.786189) (xy 166.590728 -81.715958) (xy 166.553579 -81.641955) (xy 166.523467 -81.564821)
			(xy 166.500652 -81.485222) (xy 166.485331 -81.403848) (xy 166.477637 -81.321402) (xy 166.477188 -81.28)
			(xy 166.477662 -81.238905) (xy 166.485244 -81.157065) (xy 166.500344 -81.076274) (xy 166.522832 -80.99722)
			(xy 166.552518 -80.920578) (xy 166.589147 -80.847001) (xy 166.632407 -80.777117) (xy 166.68193 -80.711522)
			(xy 166.737293 -80.650775) (xy 166.798024 -80.595395) (xy 166.863604 -80.545853) (xy 166.933476 -80.502572)
			(xy 167.007042 -80.465922) (xy 167.083675 -80.436215) (xy 167.162723 -80.413703) (xy 167.24351 -80.39858)
			(xy 167.325347 -80.390974) (xy 167.366442 -80.390492) (xy 167.36695 -80.390492) (xy 167.406049 -80.39093)
			(xy 167.483944 -80.397817) (xy 167.560934 -80.411508) (xy 167.636428 -80.431898) (xy 167.709843 -80.458829)
			(xy 167.74541 -80.475074) (xy 167.755797 -80.479309) (xy 167.778203 -80.479309) (xy 167.78859 -80.475074)
			(xy 167.824151 -80.458811) (xy 167.897561 -80.431859) (xy 167.973056 -80.411461) (xy 168.05005 -80.397772)
			(xy 168.127949 -80.390898) (xy 168.16705 -80.390492) (xy 168.209401 -80.390978) (xy 168.293719 -80.399025)
			(xy 168.376891 -80.41505) (xy 168.458162 -80.43891) (xy 168.536798 -80.470387) (xy 168.612085 -80.509196)
			(xy 168.683342 -80.554987) (xy 168.749924 -80.607344) (xy 168.811227 -80.665793) (xy 168.866696 -80.729805)
			(xy 168.915829 -80.798799) (xy 168.958181 -80.872152) (xy 168.993369 -80.949199) (xy 169.021073 -81.029241)
			(xy 169.041043 -81.111555) (xy 169.053098 -81.195394) (xy 169.057128 -81.28) (xy 169.053098 -81.364606)
			(xy 169.041043 -81.448445) (xy 169.021073 -81.530759) (xy 168.993369 -81.610801) (xy 168.958181 -81.687848)
			(xy 168.915829 -81.761201) (xy 168.866696 -81.830195) (xy 168.811227 -81.894207) (xy 168.749924 -81.952656)
			(xy 168.683342 -82.005013) (xy 168.612085 -82.050804) (xy 168.536798 -82.089613) (xy 168.458162 -82.12109)
			(xy 168.376891 -82.14495) (xy 168.293719 -82.160975) (xy 168.209401 -82.169022) (xy 168.16705 -82.169508)
			(xy 168.127951 -82.16907) (xy 168.050056 -82.162183) (xy 167.973066 -82.148492) (xy 167.897572 -82.128102)
			(xy 167.824157 -82.101171) (xy 167.78859 -82.084926) (xy 167.767254 -82.080354) (xy 167.74541 -82.08518)
			(xy 167.703922 -82.104058) (xy 167.6179 -82.134219) (xy 167.573706 -82.145378) (xy 167.53586 -82.184748)
			(xy 167.517318 -82.274664) (xy 167.515862 -82.284163) (xy 167.519316 -82.303053) (xy 167.529445 -82.319367)
			(xy 167.531923 -82.3214) (xy 179.679092 -82.3214) (xy 179.679567 -82.280298) (xy 179.687152 -82.198443)
			(xy 179.702257 -82.117638) (xy 179.724753 -82.038571) (xy 179.754449 -81.961917) (xy 179.791091 -81.88833)
			(xy 179.834366 -81.818438) (xy 179.883906 -81.752837) (xy 179.939287 -81.692087) (xy 180.000037 -81.636706)
			(xy 180.065638 -81.587166) (xy 180.13553 -81.543891) (xy 180.209117 -81.507249) (xy 180.285771 -81.477553)
			(xy 180.364838 -81.455057) (xy 180.445643 -81.439952) (xy 180.527498 -81.432367) (xy 180.5686 -81.431892)
			(xy 180.568854 -81.431892) (xy 180.613178 -81.432481) (xy 180.701382 -81.441336) (xy 180.788269 -81.458914)
			(xy 180.87298 -81.48504) (xy 180.91404 -81.501742) (xy 180.922999 -81.505002) (xy 180.942044 -81.505407)
			(xy 180.951124 -81.502504) (xy 180.987636 -81.489691) (xy 181.062399 -81.469713) (xy 181.138615 -81.45631)
			(xy 181.215707 -81.449583) (xy 181.2544 -81.449164) (xy 181.295478 -81.449674) (xy 181.377283 -81.457254)
			(xy 181.458041 -81.47235) (xy 181.53706 -81.494832) (xy 181.613669 -81.52451) (xy 181.687212 -81.561129)
			(xy 181.757063 -81.604378) (xy 181.822626 -81.653887) (xy 181.883341 -81.709233) (xy 181.93869 -81.769946)
			(xy 181.988202 -81.835507) (xy 182.031453 -81.905356) (xy 182.068076 -81.978898) (xy 182.097756 -82.055505)
			(xy 182.120242 -82.134524) (xy 182.135341 -82.215281) (xy 182.142924 -82.297086) (xy 182.1434 -82.338164)
			(xy 182.1434 -82.338418) (xy 182.142834 -82.383711) (xy 182.133591 -82.473826) (xy 182.115232 -82.562533)
			(xy 182.087948 -82.648913) (xy 182.070502 -82.690716) (xy 182.066871 -82.700428) (xy 182.066864 -82.72114)
			(xy 182.070502 -82.730848) (xy 182.087944 -82.772652) (xy 182.115227 -82.859032) (xy 182.133584 -82.947739)
			(xy 182.142823 -83.037853) (xy 182.1434 -83.083146) (xy 182.1434 -83.0834) (xy 182.142926 -83.124479)
			(xy 182.135345 -83.206287) (xy 182.120249 -83.287046) (xy 182.097765 -83.366068) (xy 182.068086 -83.442678)
			(xy 182.031465 -83.516223) (xy 181.988215 -83.586075) (xy 181.938703 -83.651638) (xy 181.883354 -83.712354)
			(xy 181.822638 -83.767703) (xy 181.757075 -83.817215) (xy 181.687223 -83.860465) (xy 181.613678 -83.897086)
			(xy 181.537068 -83.926765) (xy 181.458046 -83.949249) (xy 181.377287 -83.964345) (xy 181.295479 -83.971926)
			(xy 181.2544 -83.9724) (xy 181.212482 -83.971876) (xy 181.129018 -83.963986) (xy 181.046668 -83.948275)
			(xy 180.966161 -83.924883) (xy 180.888214 -83.894018) (xy 180.813518 -83.855954) (xy 180.742735 -83.811028)
			(xy 180.676496 -83.75964) (xy 180.615386 -83.702246) (xy 180.55995 -83.639355) (xy 180.510679 -83.571526)
			(xy 180.468011 -83.49936) (xy 180.432324 -83.423499) (xy 180.403936 -83.344616) (xy 180.383097 -83.263411)
			(xy 180.376068 -83.222084) (xy 180.374013 -83.212504) (xy 180.363916 -83.19574) (xy 180.348309 -83.183933)
			(xy 180.338984 -83.180936) (xy 180.298908 -83.169698) (xy 180.220855 -83.140782) (xy 180.145845 -83.104701)
			(xy 180.074532 -83.061772) (xy 180.00754 -83.01237) (xy 179.945456 -82.956926) (xy 179.888822 -82.895927)
			(xy 179.838132 -82.829904) (xy 179.793831 -82.759435) (xy 179.756306 -82.685137) (xy 179.725884 -82.607658)
			(xy 179.702831 -82.527677) (xy 179.68735 -82.445892) (xy 179.679576 -82.363019) (xy 179.679092 -82.3214)
			(xy 167.531923 -82.3214) (xy 167.536876 -82.325464) (xy 167.569741 -82.350584) (xy 167.631156 -82.406007)
			(xy 167.687165 -82.466889) (xy 167.737283 -82.532704) (xy 167.781079 -82.602886) (xy 167.818174 -82.676829)
			(xy 167.848248 -82.753895) (xy 167.871042 -82.833418) (xy 167.88636 -82.914713) (xy 167.894068 -82.997079)
			(xy 167.894508 -83.038442) (xy 167.894508 -83.03895) (xy 167.89407 -83.078049) (xy 167.887183 -83.155944)
			(xy 167.873492 -83.232934) (xy 167.853102 -83.308428) (xy 167.826171 -83.381843) (xy 167.809926 -83.41741)
			(xy 167.80569 -83.427797) (xy 167.80569 -83.450203) (xy 167.809926 -83.46059) (xy 167.826189 -83.496151)
			(xy 167.853141 -83.569561) (xy 167.873539 -83.645056) (xy 167.887228 -83.72205) (xy 167.894102 -83.799949)
			(xy 167.894508 -83.83905) (xy 167.894508 -83.839304) (xy 167.894025 -83.881292) (xy 167.886116 -83.964893)
			(xy 167.87036 -84.047377) (xy 167.846896 -84.128007) (xy 167.815934 -84.206066) (xy 167.77775 -84.280858)
			(xy 167.732684 -84.351716) (xy 167.681137 -84.418009) (xy 167.6527 -84.448904) (xy 167.638984 -84.483702)
			(xy 167.639082 -84.488862) (xy 167.641138 -84.498973) (xy 167.643048 -84.503768) (xy 167.680132 -84.589366)
			(xy 167.684445 -84.598249) (xy 167.698502 -84.612092) (xy 167.716751 -84.619588) (xy 167.726614 -84.6201)
			(xy 184.896506 -84.6201) (xy 184.906576 -84.619676) (xy 184.925179 -84.61196) (xy 184.932574 -84.605114)
			(xy 186.294014 -83.243674) (xy 186.300866 -83.236278) (xy 186.308604 -83.217679) (xy 186.309 -83.207606)
			(xy 186.309 -79.775558) (xy 186.308478 -79.765061) (xy 186.300078 -79.745819) (xy 186.284692 -79.731533)
			(xy 186.274964 -79.727552) (xy 186.27471 -79.727552) (xy 186.234706 -79.713325) (xy 186.157366 -79.678273)
			(xy 186.083718 -79.636011) (xy 186.014434 -79.586923) (xy 185.950142 -79.531455) (xy 185.89143 -79.470113)
			(xy 185.83883 -79.403454) (xy 185.792822 -79.332087) (xy 185.753825 -79.256659) (xy 185.722194 -79.177859)
			(xy 185.698216 -79.096403) (xy 185.682111 -79.013032) (xy 185.674023 -78.928506) (xy 185.673492 -78.88605)
			(xy 185.67393 -78.846951) (xy 185.680817 -78.769056) (xy 185.694508 -78.692066) (xy 185.714898 -78.616572)
			(xy 185.741829 -78.543157) (xy 185.758074 -78.50759) (xy 185.76231 -78.497203) (xy 185.76231 -78.474797)
			(xy 185.758074 -78.46441) (xy 185.741811 -78.428849) (xy 185.714859 -78.355439) (xy 185.694461 -78.279944)
			(xy 185.680772 -78.20295) (xy 185.673898 -78.125051) (xy 185.673492 -78.08595) (xy 185.673988 -78.043495)
			(xy 185.682084 -77.958971) (xy 185.698198 -77.875603) (xy 185.722183 -77.794151) (xy 185.753821 -77.715354)
			(xy 185.792823 -77.639931) (xy 185.838836 -77.568568) (xy 185.891439 -77.501915) (xy 185.950155 -77.440577)
			(xy 186.014448 -77.385114) (xy 186.083735 -77.33603) (xy 186.157383 -77.293772) (xy 186.234723 -77.258725)
			(xy 186.27471 -77.244448) (xy 186.274964 -77.244448) (xy 186.284711 -77.240501) (xy 186.300108 -77.226212)
			(xy 186.308477 -77.206946) (xy 186.309 -77.196442) (xy 186.309 -68.684394) (xy 186.308576 -68.674324)
			(xy 186.30086 -68.655721) (xy 186.294014 -68.648326) (xy 185.605674 -67.959986) (xy 185.598278 -67.953134)
			(xy 185.579679 -67.945396) (xy 185.569606 -67.945) (xy 184.127394 -67.945) (xy 184.117324 -67.945424)
			(xy 184.098721 -67.95314) (xy 184.091326 -67.959986) (xy 183.783986 -68.267326) (xy 183.777134 -68.274722)
			(xy 183.769396 -68.293321) (xy 183.769 -68.303394) (xy 183.769 -73.344024) (xy 183.769624 -73.355867)
			(xy 183.780226 -73.37705) (xy 183.78932 -73.384664) (xy 183.854598 -73.433432) (xy 183.861337 -73.438105)
			(xy 183.876883 -73.443294) (xy 183.885078 -73.443592) (xy 183.899302 -73.44156) (xy 183.940087 -73.430085)
			(xy 184.023286 -73.414038) (xy 184.107634 -73.405978) (xy 184.15 -73.405492) (xy 184.191102 -73.405967)
			(xy 184.272957 -73.413552) (xy 184.353762 -73.428657) (xy 184.432829 -73.451153) (xy 184.509483 -73.480849)
			(xy 184.58307 -73.517491) (xy 184.652962 -73.560766) (xy 184.718563 -73.610306) (xy 184.779313 -73.665687)
			(xy 184.834694 -73.726437) (xy 184.884234 -73.792038) (xy 184.927509 -73.86193) (xy 184.964151 -73.935517)
			(xy 184.993847 -74.012171) (xy 185.016343 -74.091238) (xy 185.031448 -74.172043) (xy 185.039033 -74.253898)
			(xy 185.039508 -74.295) (xy 185.039508 -74.295254) (xy 185.039049 -74.336065) (xy 185.031574 -74.417343)
			(xy 185.016684 -74.497595) (xy 184.994504 -74.576144) (xy 184.96522 -74.652332) (xy 184.929078 -74.725515)
			(xy 184.886383 -74.795079) (xy 184.837494 -74.860439) (xy 184.782821 -74.921044) (xy 184.722826 -74.976385)
			(xy 184.658013 -75.025996) (xy 184.62371 -75.04811) (xy 184.600088 -75.091036) (xy 184.600596 -75.098656)
			(xy 184.614312 -75.190858) (xy 184.616223 -75.200525) (xy 184.626281 -75.217448) (xy 184.641996 -75.229305)
			(xy 184.651396 -75.23226) (xy 184.65165 -75.23226) (xy 184.691796 -75.243423) (xy 184.769983 -75.272247)
			(xy 184.845131 -75.308259) (xy 184.916582 -75.351142) (xy 184.983708 -75.400521) (xy 185.045921 -75.455961)
			(xy 185.102675 -75.516978) (xy 185.153474 -75.583036) (xy 185.197871 -75.653556) (xy 185.235476 -75.727919)
			(xy 185.265962 -75.805474) (xy 185.289059 -75.885541) (xy 185.304566 -75.967417) (xy 185.312347 -76.050384)
			(xy 185.312812 -76.09205) (xy 185.312354 -76.133166) (xy 185.304771 -76.215046) (xy 185.289664 -76.295878)
			(xy 185.267163 -76.37497) (xy 185.23746 -76.45165) (xy 185.200809 -76.525261) (xy 185.157521 -76.595176)
			(xy 185.107966 -76.660798) (xy 185.052568 -76.721568) (xy 184.991798 -76.776966) (xy 184.926176 -76.826521)
			(xy 184.856261 -76.869809) (xy 184.78265 -76.90646) (xy 184.70597 -76.936163) (xy 184.626878 -76.958664)
			(xy 184.546046 -76.973771) (xy 184.464166 -76.981354) (xy 184.42305 -76.981812) (xy 184.381829 -76.981321)
			(xy 184.299743 -76.973644) (xy 184.21872 -76.958407) (xy 184.139454 -76.93574) (xy 184.062624 -76.905839)
			(xy 184.02554 -76.887832) (xy 184.015249 -76.883378) (xy 183.992857 -76.882866) (xy 183.98236 -76.886816)
			(xy 183.939863 -76.904928) (xy 183.851932 -76.933264) (xy 183.761536 -76.952325) (xy 183.66965 -76.961905)
			(xy 183.623458 -76.962508) (xy 183.622696 -76.962508) (xy 183.580252 -76.962033) (xy 183.495748 -76.953977)
			(xy 183.412396 -76.937901) (xy 183.330957 -76.913952) (xy 183.252173 -76.882347) (xy 183.176761 -76.843374)
			(xy 183.105408 -76.797389) (xy 183.07177 -76.7715) (xy 183.040274 -76.760578) (xy 183.031892 -76.76134)
			(xy 183.010906 -76.764678) (xy 182.968559 -76.768242) (xy 182.94731 -76.768452) (xy 172.34662 -76.768452)
			(xy 172.337829 -76.768818) (xy 172.321283 -76.774767) (xy 172.30773 -76.785968) (xy 172.302932 -76.793344)
			(xy 172.258228 -76.868528) (xy 172.254939 -76.874495) (xy 172.251327 -76.887627) (xy 172.251116 -76.894436)
			(xy 172.257212 -76.918566) (xy 172.277822 -76.957701) (xy 172.312079 -77.039251) (xy 172.338078 -77.123797)
			(xy 172.355564 -77.210505) (xy 172.364362 -77.298519) (xy 172.364908 -77.342746) (xy 172.364908 -77.343)
			(xy 172.364404 -77.385348) (xy 172.356353 -77.469662) (xy 172.340324 -77.552828) (xy 172.316463 -77.634095)
			(xy 172.284984 -77.712725) (xy 172.246173 -77.788006) (xy 172.200383 -77.859258) (xy 172.148027 -77.925834)
			(xy 172.089579 -77.987132) (xy 172.025569 -78.042597) (xy 171.956577 -78.091726) (xy 171.883227 -78.134075)
			(xy 171.806184 -78.169259) (xy 171.726145 -78.196961) (xy 171.643836 -78.216929) (xy 171.560001 -78.228982)
			(xy 171.4754 -78.233013) (xy 171.390799 -78.228982) (xy 171.306964 -78.216929) (xy 171.224655 -78.196961)
			(xy 171.144616 -78.169259) (xy 171.067573 -78.134075) (xy 170.994223 -78.091726) (xy 170.925231 -78.042597)
			(xy 170.861221 -77.987132) (xy 170.802773 -77.925834) (xy 170.750417 -77.859258) (xy 170.704627 -77.788006)
			(xy 170.665816 -77.712725) (xy 170.634337 -77.634095) (xy 170.610476 -77.552828) (xy 170.594447 -77.469662)
			(xy 170.586396 -77.385348) (xy 170.585892 -77.343) (xy 170.585892 -77.342746) (xy 170.586437 -77.298519)
			(xy 170.595218 -77.210501) (xy 170.612698 -77.123791) (xy 170.638704 -77.039246) (xy 170.672979 -76.957702)
			(xy 170.693588 -76.918566) (xy 170.699684 -76.894436) (xy 170.69947 -76.887626) (xy 170.695869 -76.87449)
			(xy 170.692572 -76.868528) (xy 170.647868 -76.793344) (xy 170.643063 -76.785979) (xy 170.629505 -76.7748)
			(xy 170.612966 -76.768864) (xy 170.60418 -76.768452) (xy 169.04462 -76.768452) (xy 169.035829 -76.768818)
			(xy 169.019283 -76.774767) (xy 169.00573 -76.785968) (xy 169.000932 -76.793344) (xy 168.956228 -76.868528)
			(xy 168.952939 -76.874495) (xy 168.949327 -76.887627) (xy 168.949116 -76.894436) (xy 168.955212 -76.918566)
			(xy 168.975822 -76.957701) (xy 169.010079 -77.039251) (xy 169.036078 -77.123797) (xy 169.053564 -77.210505)
			(xy 169.062362 -77.298519) (xy 169.062908 -77.342746) (xy 169.062908 -77.343254) (xy 169.062431 -77.385093)
			(xy 169.054575 -77.468402) (xy 169.03893 -77.550605) (xy 169.015633 -77.630975) (xy 168.984889 -77.708802)
			(xy 168.946972 -77.783396) (xy 168.924986 -77.818996) (xy 168.920216 -77.827438) (xy 168.91676 -77.846502)
			(xy 168.920587 -77.865495) (xy 168.925494 -77.87386) (xy 168.94836 -77.909952) (xy 168.987856 -77.985722)
			(xy 169.019903 -78.064931) (xy 169.044206 -78.146848) (xy 169.06054 -78.230719) (xy 169.068755 -78.315769)
			(xy 169.069258 -78.358492) (xy 169.069258 -78.359508) (xy 169.069747 -78.369518) (xy 169.077406 -78.388014)
			(xy 169.091557 -78.402175) (xy 169.110049 -78.409846) (xy 169.120058 -78.410308) (xy 169.120312 -78.410308)
			(xy 169.128186 -78.410017) (xy 169.143192 -78.405238) (xy 169.149776 -78.40091) (xy 169.15003 -78.400656)
			(xy 169.182542 -78.37764) (xy 169.25097 -78.336848) (xy 169.322773 -78.302343) (xy 169.397376 -78.274401)
			(xy 169.47418 -78.253247) (xy 169.552569 -78.239051) (xy 169.631914 -78.231927) (xy 169.671746 -78.231492)
			(xy 169.672 -78.231492) (xy 169.713102 -78.231967) (xy 169.794957 -78.239552) (xy 169.875762 -78.254657)
			(xy 169.954829 -78.277153) (xy 170.031483 -78.306849) (xy 170.10507 -78.343491) (xy 170.174962 -78.386766)
			(xy 170.240563 -78.436306) (xy 170.301313 -78.491687) (xy 170.334746 -78.528361) (xy 174.817528 -78.528361)
			(xy 174.817528 -78.443639) (xy 174.825581 -78.359302) (xy 174.841615 -78.276112) (xy 174.865483 -78.194822)
			(xy 174.896971 -78.11617) (xy 174.935793 -78.040867) (xy 174.981596 -77.969595) (xy 175.033967 -77.902999)
			(xy 175.092432 -77.841684) (xy 175.15646 -77.786203) (xy 175.225472 -77.73706) (xy 175.298842 -77.6947)
			(xy 175.375907 -77.659505) (xy 175.455969 -77.631796) (xy 175.538302 -77.611822) (xy 175.622161 -77.599765)
			(xy 175.706786 -77.595734) (xy 175.791411 -77.599765) (xy 175.87527 -77.611822) (xy 175.957603 -77.631796)
			(xy 176.037665 -77.659505) (xy 176.11473 -77.6947) (xy 176.1881 -77.73706) (xy 176.257112 -77.786203)
			(xy 176.32114 -77.841684) (xy 176.379605 -77.902999) (xy 176.431976 -77.969595) (xy 176.477779 -78.040867)
			(xy 176.516601 -78.11617) (xy 176.548089 -78.194822) (xy 176.571957 -78.276112) (xy 176.587991 -78.359302)
			(xy 176.596044 -78.443639) (xy 176.596548 -78.486) (xy 176.596044 -78.528361) (xy 176.587991 -78.612698)
			(xy 176.571957 -78.695888) (xy 176.548089 -78.777178) (xy 176.516601 -78.85583) (xy 176.477779 -78.931133)
			(xy 176.431976 -79.002405) (xy 176.379605 -79.069001) (xy 176.32114 -79.130316) (xy 176.257112 -79.185797)
			(xy 176.1881 -79.23494) (xy 176.11473 -79.2773) (xy 176.037665 -79.312495) (xy 175.957603 -79.340204)
			(xy 175.87527 -79.360178) (xy 175.791411 -79.372235) (xy 175.706786 -79.376267) (xy 175.622161 -79.372235)
			(xy 175.538302 -79.360178) (xy 175.455969 -79.340204) (xy 175.375907 -79.312495) (xy 175.298842 -79.2773)
			(xy 175.225472 -79.23494) (xy 175.15646 -79.185797) (xy 175.092432 -79.130316) (xy 175.033967 -79.069001)
			(xy 174.981596 -79.002405) (xy 174.935793 -78.931133) (xy 174.896971 -78.85583) (xy 174.865483 -78.777178)
			(xy 174.841615 -78.695888) (xy 174.825581 -78.612698) (xy 174.817528 -78.528361) (xy 170.334746 -78.528361)
			(xy 170.356694 -78.552437) (xy 170.406234 -78.618038) (xy 170.449509 -78.68793) (xy 170.486151 -78.761517)
			(xy 170.515847 -78.838171) (xy 170.538343 -78.917238) (xy 170.553448 -78.998043) (xy 170.561033 -79.079898)
			(xy 170.561508 -79.121) (xy 170.561508 -79.121762) (xy 170.561224 -79.153688) (xy 170.556645 -79.217377)
			(xy 170.552364 -79.249016) (xy 170.552364 -79.24927) (xy 170.551418 -79.258763) (xy 170.555859 -79.277301)
			(xy 170.561 -79.285338) (xy 170.578526 -79.310484) (xy 170.584426 -79.318158) (xy 170.600627 -79.328719)
			(xy 170.610022 -79.331058) (xy 170.652641 -79.3402) (xy 170.735993 -79.365719) (xy 170.816448 -79.39927)
			(xy 170.893234 -79.440531) (xy 170.965616 -79.489106) (xy 171.032899 -79.544529) (xy 171.094436 -79.606269)
			(xy 171.149638 -79.673734) (xy 171.197975 -79.746275) (xy 171.238983 -79.823197) (xy 171.272269 -79.903762)
			(xy 171.297514 -79.987197) (xy 171.314475 -80.072701) (xy 171.322989 -80.159455) (xy 171.323226 -80.179361)
			(xy 181.863742 -80.179361) (xy 181.863742 -80.094639) (xy 181.871795 -80.010302) (xy 181.887829 -79.927112)
			(xy 181.911697 -79.845822) (xy 181.943185 -79.76717) (xy 181.982007 -79.691867) (xy 182.02781 -79.620595)
			(xy 182.080181 -79.553999) (xy 182.138646 -79.492684) (xy 182.202674 -79.437203) (xy 182.271686 -79.38806)
			(xy 182.345056 -79.3457) (xy 182.422121 -79.310505) (xy 182.502183 -79.282796) (xy 182.584516 -79.262822)
			(xy 182.668375 -79.250765) (xy 182.753 -79.246734) (xy 182.837625 -79.250765) (xy 182.921484 -79.262822)
			(xy 183.003817 -79.282796) (xy 183.083879 -79.310505) (xy 183.160944 -79.3457) (xy 183.234314 -79.38806)
			(xy 183.303326 -79.437203) (xy 183.367354 -79.492684) (xy 183.425819 -79.553999) (xy 183.47819 -79.620595)
			(xy 183.523993 -79.691867) (xy 183.562815 -79.76717) (xy 183.594303 -79.845822) (xy 183.618171 -79.927112)
			(xy 183.634205 -80.010302) (xy 183.642258 -80.094639) (xy 183.642762 -80.137) (xy 183.642258 -80.179361)
			(xy 183.634205 -80.263698) (xy 183.618171 -80.346888) (xy 183.594303 -80.428178) (xy 183.562815 -80.50683)
			(xy 183.523993 -80.582133) (xy 183.47819 -80.653405) (xy 183.425819 -80.720001) (xy 183.367354 -80.781316)
			(xy 183.303326 -80.836797) (xy 183.234314 -80.88594) (xy 183.160944 -80.9283) (xy 183.083879 -80.963495)
			(xy 183.003817 -80.991204) (xy 182.921484 -81.011178) (xy 182.837625 -81.023235) (xy 182.753 -81.027267)
			(xy 182.668375 -81.023235) (xy 182.584516 -81.011178) (xy 182.502183 -80.991204) (xy 182.422121 -80.963495)
			(xy 182.345056 -80.9283) (xy 182.271686 -80.88594) (xy 182.202674 -80.836797) (xy 182.138646 -80.781316)
			(xy 182.080181 -80.720001) (xy 182.02781 -80.653405) (xy 181.982007 -80.582133) (xy 181.943185 -80.50683)
			(xy 181.911697 -80.428178) (xy 181.887829 -80.346888) (xy 181.871795 -80.263698) (xy 181.863742 -80.179361)
			(xy 171.323226 -80.179361) (xy 171.323508 -80.20304) (xy 171.323004 -80.245388) (xy 171.314953 -80.329702)
			(xy 171.298924 -80.412868) (xy 171.275063 -80.494135) (xy 171.243584 -80.572765) (xy 171.204773 -80.648046)
			(xy 171.158983 -80.719298) (xy 171.106627 -80.785874) (xy 171.048179 -80.847172) (xy 170.984169 -80.902637)
			(xy 170.915177 -80.951766) (xy 170.841827 -80.994115) (xy 170.764784 -81.029299) (xy 170.684745 -81.057001)
			(xy 170.602436 -81.076969) (xy 170.518601 -81.089022) (xy 170.434 -81.093053) (xy 170.349399 -81.089022)
			(xy 170.265564 -81.076969) (xy 170.183255 -81.057001) (xy 170.103216 -81.029299) (xy 170.026173 -80.994115)
			(xy 169.952823 -80.951766) (xy 169.883831 -80.902637) (xy 169.819821 -80.847172) (xy 169.761373 -80.785874)
			(xy 169.709017 -80.719298) (xy 169.663227 -80.648046) (xy 169.624416 -80.572765) (xy 169.592937 -80.494135)
			(xy 169.569076 -80.412868) (xy 169.553047 -80.329702) (xy 169.544996 -80.245388) (xy 169.544492 -80.20304)
			(xy 169.544492 -80.202278) (xy 169.544775 -80.170352) (xy 169.54935 -80.106663) (xy 169.553636 -80.075024)
			(xy 169.553636 -80.07477) (xy 169.554589 -80.065275) (xy 169.55016 -80.046728) (xy 169.545 -80.038702)
			(xy 169.527474 -80.013556) (xy 169.521577 -80.005878) (xy 169.505377 -79.995308) (xy 169.495978 -79.992982)
			(xy 169.45648 -79.984537) (xy 169.37908 -79.961424) (xy 169.304095 -79.931387) (xy 169.232143 -79.894674)
			(xy 169.163817 -79.851586) (xy 169.131488 -79.827374) (xy 169.122289 -79.821031) (xy 169.1005 -79.8162)
			(xy 169.078711 -79.821031) (xy 169.069512 -79.827374) (xy 169.036273 -79.852204) (xy 168.965967 -79.896269)
			(xy 168.891866 -79.933599) (xy 168.814612 -79.963871) (xy 168.734875 -79.986821) (xy 168.653349 -80.00225)
			(xy 168.57074 -80.010024) (xy 168.529254 -80.010508) (xy 168.529 -80.010508) (xy 168.487898 -80.010033)
			(xy 168.406043 -80.002448) (xy 168.325238 -79.987343) (xy 168.246171 -79.964847) (xy 168.169517 -79.935151)
			(xy 168.09593 -79.898509) (xy 168.026038 -79.855234) (xy 167.960437 -79.805694) (xy 167.899687 -79.750313)
			(xy 167.844306 -79.689563) (xy 167.794766 -79.623962) (xy 167.751491 -79.55407) (xy 167.714849 -79.480483)
			(xy 167.685153 -79.403829) (xy 167.662657 -79.324762) (xy 167.647552 -79.243957) (xy 167.639967 -79.162102)
			(xy 167.639492 -79.121) (xy 167.64 -79.092298) (xy 167.639752 -79.080457) (xy 167.629828 -79.058986)
			(xy 167.62095 -79.05115) (xy 167.586988 -79.02305) (xy 167.5242 -78.961174) (xy 167.467839 -78.893392)
			(xy 167.418458 -78.820368) (xy 167.376541 -78.742818) (xy 167.342499 -78.661503) (xy 167.316666 -78.57722)
			(xy 167.299295 -78.490795) (xy 167.290557 -78.403076) (xy 167.289988 -78.359) (xy 167.289988 -78.358746)
			(xy 167.290466 -78.316907) (xy 167.298323 -78.233599) (xy 167.313971 -78.151398) (xy 167.337273 -78.071031)
			(xy 167.368022 -77.993207) (xy 167.405946 -77.918617) (xy 167.42791 -77.883004) (xy 167.435784 -77.855826)
			(xy 167.427656 -77.82814) (xy 167.404789 -77.792048) (xy 167.36529 -77.716279) (xy 167.333242 -77.63707)
			(xy 167.308938 -77.555153) (xy 167.292603 -77.471282) (xy 167.284387 -77.386231) (xy 167.283892 -77.343508)
			(xy 167.283892 -77.343) (xy 167.284411 -77.300004) (xy 167.292708 -77.214413) (xy 167.309224 -77.130021)
			(xy 167.333805 -77.047617) (xy 167.366223 -76.967969) (xy 167.406174 -76.891821) (xy 167.453285 -76.819882)
			(xy 167.507118 -76.752824) (xy 167.567169 -76.691273) (xy 167.632879 -76.635803) (xy 167.703634 -76.586932)
			(xy 167.778775 -76.545116) (xy 167.857599 -76.510744) (xy 167.898318 -76.496926) (xy 167.911018 -76.492862)
			(xy 167.929052 -76.473558) (xy 167.95242 -76.376276) (xy 167.954132 -76.367769) (xy 167.952348 -76.35052)
			(xy 167.944872 -76.334874) (xy 167.938958 -76.328524) (xy 167.661844 -76.051156) (xy 167.638688 -76.027276)
			(xy 167.598182 -75.974512) (xy 167.564911 -75.916911) (xy 167.539447 -75.85546) (xy 167.522225 -75.791209)
			(xy 167.513539 -75.725259) (xy 167.513 -75.692) (xy 167.513 -73.868534) (xy 167.512705 -73.859863)
			(xy 167.507004 -73.843489) (xy 167.501824 -73.83653) (xy 167.475208 -73.802682) (xy 167.427928 -73.73071)
			(xy 167.387831 -73.654502) (xy 167.355295 -73.574772) (xy 167.330625 -73.492269) (xy 167.314052 -73.407766)
			(xy 167.305731 -73.322056) (xy 167.305228 -73.279) (xy 167.305656 -73.241605) (xy 167.312014 -73.167083)
			(xy 167.317928 -73.130156) (xy 167.31915 -73.12016) (xy 167.314715 -73.10054) (xy 167.309292 -73.092056)
			(xy 167.26789 -73.033636) (xy 167.23487 -73.012808) (xy 167.194029 -73.005273) (xy 167.113858 -72.983581)
			(xy 167.036056 -72.954513) (xy 166.961303 -72.918321) (xy 166.890247 -72.87532) (xy 166.823507 -72.825885)
			(xy 166.761665 -72.770445) (xy 166.705259 -72.709484) (xy 166.654779 -72.643531) (xy 166.610665 -72.573161)
			(xy 166.5733 -72.498986) (xy 166.543011 -72.421652) (xy 166.52006 -72.341832) (xy 166.504648 -72.26022)
			(xy 166.496908 -72.177527) (xy 166.496492 -72.136) (xy 166.496985 -72.093547) (xy 166.505077 -72.009026)
			(xy 166.521186 -71.925661) (xy 166.545168 -71.844211) (xy 166.576802 -71.765417) (xy 166.615801 -71.689997)
			(xy 166.66181 -71.618636) (xy 166.714411 -71.551985) (xy 166.773124 -71.49065) (xy 166.837415 -71.435189)
			(xy 166.906698 -71.386108) (xy 166.980344 -71.343853) (xy 167.057682 -71.308809) (xy 167.138007 -71.281295)
			(xy 167.220589 -71.261561) (xy 167.262556 -71.255128) (xy 167.274198 -71.252856) (xy 167.293707 -71.239413)
			(xy 167.305169 -71.218679) (xy 167.306244 -71.206868) (xy 167.308503 -71.166746) (xy 167.319358 -71.087116)
			(xy 167.337354 -71.00879) (xy 167.362344 -70.932407) (xy 167.394123 -70.858591) (xy 167.432432 -70.787943)
			(xy 167.47696 -70.721039) (xy 167.501824 -70.68947) (xy 167.506971 -70.682491) (xy 167.512687 -70.666132)
			(xy 167.513 -70.657466) (xy 167.513 -70.072758) (xy 167.513524 -70.039499) (xy 167.522216 -69.973552)
			(xy 167.539446 -69.909304) (xy 167.564919 -69.847856) (xy 167.598197 -69.790262) (xy 167.638713 -69.737506)
			(xy 167.661844 -69.713602) (xy 169.75836 -67.617086) (xy 169.765209 -67.609689) (xy 169.772944 -67.59109)
			(xy 169.773346 -67.581018) (xy 169.773346 -60.345574) (xy 169.772917 -60.335507) (xy 169.76519 -60.316915)
			(xy 169.75836 -60.309506) (xy 169.382186 -59.933332) (xy 169.374788 -59.926484) (xy 169.35619 -59.91875)
			(xy 169.346118 -59.918346) (xy 166.373048 -59.918346) (xy 166.362983 -59.91878) (xy 166.344397 -59.926513)
			(xy 166.33698 -59.933332) (xy 166.130986 -60.139326) (xy 166.124134 -60.146722) (xy 166.116396 -60.165321)
			(xy 166.116 -60.175394) (xy 166.116 -65.841372) (xy 166.116497 -65.851184) (xy 166.123938 -65.869348)
			(xy 166.130478 -65.876678) (xy 166.151306 -65.898268) (xy 166.158246 -65.904798) (xy 166.1756 -65.912637)
			(xy 166.185088 -65.913508) (xy 166.185342 -65.913508) (xy 166.228812 -65.916163) (xy 166.314972 -65.928898)
			(xy 166.399474 -65.949993) (xy 166.48151 -65.979246) (xy 166.52113 -65.997328) (xy 166.54272 -66.002154)
			(xy 166.56431 -65.997328) (xy 166.599958 -65.980999) (xy 166.673558 -65.953943) (xy 166.749256 -65.933479)
			(xy 166.826463 -65.919764) (xy 166.904578 -65.912905) (xy 166.943786 -65.912492) (xy 166.94404 -65.912492)
			(xy 166.98199 -65.912887) (xy 167.057614 -65.919353) (xy 167.132411 -65.932243) (xy 167.205837 -65.951464)
			(xy 167.241728 -65.9638) (xy 167.253665 -65.967369) (xy 167.278289 -65.963761) (xy 167.288718 -65.956942)
			(xy 167.321366 -65.933619) (xy 167.390142 -65.892283) (xy 167.462361 -65.857311) (xy 167.537437 -65.828986)
			(xy 167.61476 -65.80754) (xy 167.6937 -65.793146) (xy 167.773615 -65.785921) (xy 167.813736 -65.785492)
			(xy 167.856083 -65.785997) (xy 167.940394 -65.794051) (xy 168.023558 -65.810083) (xy 168.104821 -65.833947)
			(xy 168.183448 -65.865427) (xy 168.258727 -65.904239) (xy 168.329976 -65.95003) (xy 168.396549 -66.002386)
			(xy 168.457844 -66.060834) (xy 168.513307 -66.124843) (xy 168.562433 -66.193834) (xy 168.60478 -66.267182)
			(xy 168.639962 -66.344224) (xy 168.667663 -66.424261) (xy 168.68763 -66.506568) (xy 168.699683 -66.590401)
			(xy 168.703713 -66.675) (xy 168.699683 -66.759599) (xy 168.68763 -66.843432) (xy 168.667663 -66.925739)
			(xy 168.639962 -67.005776) (xy 168.60478 -67.082818) (xy 168.562433 -67.156166) (xy 168.513307 -67.225157)
			(xy 168.457844 -67.289166) (xy 168.396549 -67.347614) (xy 168.329976 -67.39997) (xy 168.258727 -67.445761)
			(xy 168.183448 -67.484573) (xy 168.104821 -67.516053) (xy 168.023558 -67.539917) (xy 167.940394 -67.555949)
			(xy 167.856083 -67.564003) (xy 167.813736 -67.564508) (xy 167.812974 -67.564508) (xy 167.775088 -67.564095)
			(xy 167.699592 -67.557609) (xy 167.624923 -67.544721) (xy 167.551622 -67.525524) (xy 167.515794 -67.5132)
			(xy 167.503856 -67.509626) (xy 167.479226 -67.513225) (xy 167.468804 -67.520058) (xy 167.436155 -67.543379)
			(xy 167.367378 -67.584708) (xy 167.295158 -67.619674) (xy 167.220081 -67.647992) (xy 167.142759 -67.669432)
			(xy 167.06382 -67.683819) (xy 166.983906 -67.691037) (xy 166.943786 -67.691508) (xy 166.943532 -67.691508)
			(xy 166.90435 -67.691079) (xy 166.826291 -67.684187) (xy 166.749139 -67.670463) (xy 166.673491 -67.650012)
			(xy 166.599933 -67.622994) (xy 166.56431 -67.606672) (xy 166.54272 -67.601846) (xy 166.52113 -67.606672)
			(xy 166.48528 -67.623097) (xy 166.411247 -67.65027) (xy 166.335099 -67.670783) (xy 166.29634 -67.678046)
			(xy 166.28621 -67.680336) (xy 166.268874 -67.691736) (xy 166.257456 -67.70906) (xy 166.255192 -67.719194)
			(xy 166.246842 -67.763208) (xy 166.222449 -67.849416) (xy 166.189516 -67.932735) (xy 166.148376 -68.012323)
			(xy 166.124382 -68.050156) (xy 166.116 -68.077842) (xy 166.116 -75.565) (xy 166.115479 -75.59826)
			(xy 166.106791 -75.66421) (xy 166.089566 -75.728461) (xy 166.064097 -75.789912) (xy 166.030821 -75.847511)
			(xy 165.990308 -75.900271) (xy 165.967156 -75.924156) (xy 165.332156 -76.559156) (xy 165.308276 -76.582312)
			(xy 165.255512 -76.622818) (xy 165.197911 -76.656089) (xy 165.13646 -76.681553) (xy 165.072209 -76.698775)
			(xy 165.006259 -76.707461) (xy 164.973 -76.708) (xy 155.236926 -76.708) (xy 155.227174 -76.708422)
			(xy 155.20908 -76.715697) (xy 155.195041 -76.729232) (xy 155.190698 -76.737972) (xy 155.146756 -76.836524)
			(xy 155.151328 -76.865988) (xy 155.161234 -76.877164) (xy 155.187932 -76.907703) (xy 155.236266 -76.972855)
			(xy 155.278466 -77.042138) (xy 155.314181 -77.114976) (xy 155.343113 -77.190765) (xy 155.365024 -77.268873)
			(xy 155.379729 -77.348652) (xy 155.387108 -77.429438) (xy 155.387548 -77.47) (xy 155.387073 -77.511103)
			(xy 155.379489 -77.592959) (xy 155.364384 -77.673766) (xy 155.341887 -77.752834) (xy 155.312192 -77.829489)
			(xy 155.27555 -77.903078) (xy 155.232275 -77.972972) (xy 155.182736 -78.038575) (xy 155.127355 -78.099327)
			(xy 155.066606 -78.154711) (xy 155.001005 -78.204253) (xy 154.966531 -78.2256) (xy 155.747468 -78.2256)
			(xy 155.751499 -78.140976) (xy 155.763556 -78.057118) (xy 155.78353 -77.974786) (xy 155.81124 -77.894726)
			(xy 155.846435 -77.817662) (xy 155.888796 -77.744293) (xy 155.93794 -77.675283) (xy 155.993421 -77.611257)
			(xy 156.054737 -77.552795) (xy 156.121333 -77.500426) (xy 156.192605 -77.454624) (xy 156.267908 -77.415806)
			(xy 156.34656 -77.384321) (xy 156.42785 -77.360455) (xy 156.511039 -77.344425) (xy 156.595376 -77.336375)
			(xy 156.637736 -77.335888) (xy 156.681473 -77.336417) (xy 156.768524 -77.345024) (xy 156.854309 -77.362134)
			(xy 156.938001 -77.387579) (xy 157.018793 -77.421115) (xy 157.095902 -77.462417) (xy 157.168587 -77.511088)
			(xy 157.236144 -77.566657) (xy 157.267402 -77.597254) (xy 157.267656 -77.597508) (xy 157.275013 -77.604153)
			(xy 157.293315 -77.611724) (xy 157.303216 -77.61224) (xy 157.374844 -77.612748) (xy 157.384809 -77.612257)
			(xy 157.403246 -77.604692) (xy 157.410658 -77.598016) (xy 157.441843 -77.568087) (xy 157.509054 -77.513734)
			(xy 157.581217 -77.46615) (xy 157.657653 -77.425785) (xy 157.73764 -77.393019) (xy 157.820428 -77.368161)
			(xy 157.905235 -77.351443) (xy 157.991263 -77.343024) (xy 158.034482 -77.342492) (xy 158.034736 -77.342492)
			(xy 158.077083 -77.342997) (xy 158.161394 -77.351051) (xy 158.244558 -77.367083) (xy 158.325821 -77.390947)
			(xy 158.404448 -77.422427) (xy 158.479727 -77.461239) (xy 158.550976 -77.50703) (xy 158.617549 -77.559386)
			(xy 158.678844 -77.617834) (xy 158.734307 -77.681843) (xy 158.783433 -77.750834) (xy 158.82578 -77.824182)
			(xy 158.860962 -77.901224) (xy 158.888663 -77.981261) (xy 158.90863 -78.063568) (xy 158.920683 -78.147401)
			(xy 158.924713 -78.232) (xy 158.920683 -78.316599) (xy 158.90863 -78.400432) (xy 158.888663 -78.482739)
			(xy 158.860962 -78.562776) (xy 158.82578 -78.639818) (xy 158.783433 -78.713166) (xy 158.734307 -78.782157)
			(xy 158.678844 -78.846166) (xy 158.617549 -78.904614) (xy 158.550976 -78.95697) (xy 158.479727 -79.002761)
			(xy 158.404448 -79.041573) (xy 158.325821 -79.073053) (xy 158.244558 -79.096917) (xy 158.161394 -79.112949)
			(xy 158.077083 -79.121003) (xy 158.034736 -79.121508) (xy 157.991005 -79.120981) (xy 157.903966 -79.112402)
			(xy 157.818188 -79.095325) (xy 157.7345 -79.069912) (xy 157.65371 -79.036411) (xy 157.576596 -78.995143)
			(xy 157.503904 -78.946508) (xy 157.436336 -78.890975) (xy 157.40507 -78.860396) (xy 157.404816 -78.860142)
			(xy 157.397463 -78.853492) (xy 157.379158 -78.845922) (xy 157.369256 -78.84541) (xy 157.297628 -78.844902)
			(xy 157.287646 -78.845298) (xy 157.269184 -78.85289) (xy 157.261814 -78.859634) (xy 157.230612 -78.889577)
			(xy 157.163392 -78.943992) (xy 157.091211 -78.99163) (xy 157.014749 -79.03204) (xy 156.934727 -79.064842)
			(xy 156.8519 -79.089727) (xy 156.767051 -79.106459) (xy 156.680978 -79.114882) (xy 156.637736 -79.115412)
			(xy 156.595376 -79.114825) (xy 156.511039 -79.106775) (xy 156.42785 -79.090745) (xy 156.34656 -79.066879)
			(xy 156.267908 -79.035394) (xy 156.192605 -78.996576) (xy 156.121333 -78.950774) (xy 156.054737 -78.898405)
			(xy 155.993421 -78.839943) (xy 155.93794 -78.775917) (xy 155.888796 -78.706907) (xy 155.846435 -78.633538)
			(xy 155.81124 -78.556474) (xy 155.78353 -78.476414) (xy 155.763556 -78.394082) (xy 155.751499 -78.310224)
			(xy 155.747468 -78.2256) (xy 154.966531 -78.2256) (xy 154.931113 -78.247531) (xy 154.857526 -78.284176)
			(xy 154.780872 -78.313875) (xy 154.701804 -78.336374) (xy 154.620998 -78.351483) (xy 154.539143 -78.359072)
			(xy 154.49804 -78.359508) (xy 154.497532 -78.359508) (xy 154.456485 -78.359037) (xy 154.374741 -78.351476)
			(xy 154.294041 -78.336415) (xy 154.215073 -78.313981) (xy 154.138507 -78.284367) (xy 154.064996 -78.247824)
			(xy 153.995165 -78.204663) (xy 153.929608 -78.15525) (xy 153.868882 -78.100008) (xy 153.813506 -78.039405)
			(xy 153.788364 -78.006956) (xy 153.747978 -77.98689) (xy 153.743406 -77.987144) (xy 153.644854 -77.99578)
			(xy 153.62301 -78.010512) (xy 153.617168 -78.021942) (xy 153.598204 -78.057931) (xy 153.554632 -78.126632)
			(xy 153.50497 -78.191069) (xy 153.449635 -78.250705) (xy 153.389087 -78.305041) (xy 153.323833 -78.353624)
			(xy 153.254417 -78.396048) (xy 153.181418 -78.431959) (xy 153.105446 -78.461057) (xy 153.027135 -78.483099)
			(xy 152.94714 -78.497902) (xy 152.866127 -78.505341) (xy 152.82545 -78.505812) (xy 152.783089 -78.505306)
			(xy 152.69875 -78.497248) (xy 152.615559 -78.48121) (xy 152.534269 -78.457337) (xy 152.455616 -78.425845)
			(xy 152.380313 -78.38702) (xy 152.309041 -78.341213) (xy 152.242446 -78.288838) (xy 152.181131 -78.230371)
			(xy 152.125651 -78.16634) (xy 152.076508 -78.097326) (xy 152.034148 -78.023953) (xy 151.998954 -77.946886)
			(xy 151.971245 -77.866822) (xy 151.951272 -77.784488) (xy 151.939215 -77.700627) (xy 151.935183 -77.616)
			(xy 151.939215 -77.531373) (xy 151.951272 -77.447512) (xy 151.971245 -77.365178) (xy 151.998954 -77.285114)
			(xy 152.034148 -77.208047) (xy 152.076508 -77.134674) (xy 152.125651 -77.06566) (xy 152.181131 -77.001629)
			(xy 152.242446 -76.943162) (xy 152.309041 -76.890787) (xy 152.380313 -76.84498) (xy 152.455616 -76.806155)
			(xy 152.534269 -76.774663) (xy 152.615559 -76.75079) (xy 152.69875 -76.734752) (xy 152.783089 -76.726694)
			(xy 152.82545 -76.726288) (xy 152.866515 -76.726759) (xy 152.948297 -76.734324) (xy 153.029033 -76.749396)
			(xy 153.108036 -76.771845) (xy 153.184634 -76.801481) (xy 153.258174 -76.838051) (xy 153.328029 -76.881244)
			(xy 153.393607 -76.930692) (xy 153.454347 -76.985974) (xy 153.509733 -77.04662) (xy 153.534872 -77.079094)
			(xy 153.540324 -77.085724) (xy 153.55463 -77.095189) (xy 153.571262 -77.099392) (xy 153.57983 -77.098906)
			(xy 153.678382 -77.09027) (xy 153.700226 -77.075538) (xy 153.706068 -77.064108) (xy 153.72371 -77.030567)
			(xy 153.763895 -76.966308) (xy 153.809392 -76.905692) (xy 153.834338 -76.877164) (xy 153.844244 -76.865988)
			(xy 153.848816 -76.836524) (xy 153.804874 -76.737972) (xy 153.800469 -76.729278) (xy 153.786428 -76.715784)
			(xy 153.768381 -76.708467) (xy 153.758646 -76.708) (xy 153.385774 -76.708) (xy 153.352515 -76.707477)
			(xy 153.286566 -76.698787) (xy 153.222317 -76.681558) (xy 153.160868 -76.656087) (xy 153.103272 -76.62281)
			(xy 153.050515 -76.582295) (xy 153.026618 -76.559156) (xy 152.531318 -76.063856) (xy 152.525251 -76.05814)
			(xy 152.510332 -76.050728) (xy 152.502108 -76.049378) (xy 152.459996 -76.043137) (xy 152.377123 -76.023635)
			(xy 152.296492 -75.996305) (xy 152.218841 -75.961395) (xy 152.14488 -75.919226) (xy 152.075287 -75.870183)
			(xy 152.010699 -75.814716) (xy 151.951705 -75.75333) (xy 151.898847 -75.68659) (xy 151.852607 -75.615104)
			(xy 151.813409 -75.539527) (xy 151.781612 -75.46055) (xy 151.757505 -75.378897) (xy 151.741311 -75.295314)
			(xy 151.733177 -75.210567) (xy 151.732742 -75.167998) (xy 151.733199 -75.127269) (xy 151.740647 -75.046152)
			(xy 151.75548 -74.966056) (xy 151.777573 -74.887652) (xy 151.806742 -74.811596) (xy 151.842743 -74.738525)
			(xy 151.885273 -74.669051) (xy 151.933977 -74.603757) (xy 151.988446 -74.543189) (xy 152.048225 -74.487855)
			(xy 152.080214 -74.46264) (xy 152.100026 -74.422508) (xy 152.100026 -60.006484) (xy 152.099601 -59.996415)
			(xy 152.091885 -59.977812) (xy 152.08504 -59.970416) (xy 151.84501 -59.730386) (xy 151.837616 -59.723529)
			(xy 151.819017 -59.715777) (xy 151.808942 -59.7154) (xy 149.811994 -59.7154) (xy 149.801924 -59.715824)
			(xy 149.783321 -59.72354) (xy 149.775926 -59.730386) (xy 149.7076 -59.798712) (xy 149.700756 -59.806111)
			(xy 149.693026 -59.824709) (xy 149.692614 -59.83478) (xy 149.692614 -66.798444) (xy 149.69209 -66.831703)
			(xy 149.683398 -66.897651) (xy 149.666168 -66.961898) (xy 149.640696 -67.023346) (xy 149.607418 -67.080941)
			(xy 149.566903 -67.133697) (xy 149.54377 -67.1576) (xy 149.027388 -67.673982) (xy 149.00351 -67.697143)
			(xy 148.950749 -67.737658) (xy 148.89315 -67.770937) (xy 148.831697 -67.796409) (xy 148.767445 -67.813638)
			(xy 148.701493 -67.822329) (xy 148.668232 -67.822826) (xy 147.268438 -67.822826) (xy 147.222718 -67.851528)
			(xy 147.20415 -67.888594) (xy 147.161092 -67.959444) (xy 147.111631 -68.025982) (xy 147.056195 -68.08763)
			(xy 146.995265 -68.143854) (xy 146.929368 -68.194166) (xy 146.859078 -68.238131) (xy 146.785002 -68.275367)
			(xy 146.707784 -68.30555) (xy 146.628093 -68.32842) (xy 146.54662 -68.343777) (xy 146.464072 -68.351489)
			(xy 146.381164 -68.351489) (xy 146.298616 -68.343777) (xy 146.217143 -68.32842) (xy 146.137452 -68.30555)
			(xy 146.060234 -68.275367) (xy 145.986158 -68.238131) (xy 145.915868 -68.194166) (xy 145.849971 -68.143854)
			(xy 145.789041 -68.08763) (xy 145.733605 -68.025982) (xy 145.684144 -67.959444) (xy 145.641086 -67.888594)
			(xy 145.622518 -67.851528) (xy 145.576798 -67.822826) (xy 143.862806 -67.822826) (xy 143.834866 -67.845686)
			(xy 143.83131 -67.86372) (xy 143.822258 -67.906695) (xy 143.796789 -67.990751) (xy 143.763164 -68.071889)
			(xy 143.742918 -68.110862) (xy 143.736822 -68.134992) (xy 143.742918 -68.159122) (xy 143.763202 -68.198003)
			(xy 143.796896 -68.278976) (xy 143.822459 -68.36287) (xy 143.839644 -68.448873) (xy 143.848283 -68.536149)
			(xy 143.848836 -68.58) (xy 143.848314 -68.623763) (xy 143.839721 -68.710865) (xy 143.822617 -68.796703)
			(xy 143.797168 -68.880447) (xy 143.76362 -68.961288) (xy 143.743426 -69.000116) (xy 143.737584 -69.023738)
			(xy 143.74368 -69.047868) (xy 143.763927 -69.086734) (xy 143.797555 -69.167666) (xy 143.823068 -69.251511)
			(xy 143.840218 -69.337457) (xy 143.848841 -69.424672) (xy 143.849344 -69.468492) (xy 143.849344 -69.469)
			(xy 143.848823 -69.51282) (xy 143.840214 -69.600036) (xy 143.82307 -69.685983) (xy 143.797557 -69.769827)
			(xy 143.763922 -69.850756) (xy 143.74368 -69.889624) (xy 143.738368 -69.90098) (xy 143.738368 -69.92602)
			(xy 143.74368 -69.937376) (xy 143.763915 -69.976247) (xy 143.797525 -70.057183) (xy 143.82303 -70.141028)
			(xy 143.840185 -70.22697) (xy 143.848824 -70.314181) (xy 143.849344 -70.358) (xy 143.84884 -70.400397)
			(xy 143.84078 -70.484807) (xy 143.824732 -70.568068) (xy 143.800843 -70.649427) (xy 143.769328 -70.728147)
			(xy 143.730474 -70.803515) (xy 143.684631 -70.874848) (xy 143.632215 -70.9415) (xy 143.5737 -71.002868)
			(xy 143.509618 -71.058396) (xy 143.440547 -71.107581) (xy 143.367113 -71.149978) (xy 143.289982 -71.185203)
			(xy 143.209852 -71.212936) (xy 143.127448 -71.232927) (xy 143.043518 -71.244994) (xy 142.95882 -71.249029)
			(xy 142.874122 -71.244994) (xy 142.790192 -71.232927) (xy 142.707788 -71.212936) (xy 142.627658 -71.185203)
			(xy 142.550527 -71.149978) (xy 142.477093 -71.107581) (xy 142.408022 -71.058396) (xy 142.34394 -71.002868)
			(xy 142.285425 -70.9415) (xy 142.233009 -70.874848) (xy 142.187166 -70.803515) (xy 142.148312 -70.728147)
			(xy 142.116797 -70.649427) (xy 142.092908 -70.568068) (xy 142.07686 -70.484807) (xy 142.0688 -70.400397)
			(xy 142.068296 -70.358) (xy 142.068817 -70.31418) (xy 142.077425 -70.226963) (xy 142.094568 -70.141016)
			(xy 142.12008 -70.057171) (xy 142.153713 -69.976242) (xy 142.17396 -69.937376) (xy 142.179269 -69.92602)
			(xy 142.179269 -69.90098) (xy 142.17396 -69.889624) (xy 142.153725 -69.850753) (xy 142.120113 -69.769817)
			(xy 142.094607 -69.685973) (xy 142.077451 -69.60003) (xy 142.068812 -69.512819) (xy 142.068296 -69.469)
			(xy 142.068296 -69.468492) (xy 142.068834 -69.424674) (xy 142.077465 -69.337462) (xy 142.094614 -69.251519)
			(xy 142.120115 -69.167674) (xy 142.153722 -69.086737) (xy 142.17396 -69.047868) (xy 142.180056 -69.023738)
			(xy 142.174214 -69.000116) (xy 142.154016 -68.96129) (xy 142.120472 -68.880447) (xy 142.095024 -68.796702)
			(xy 142.077918 -68.710865) (xy 142.069318 -68.623763) (xy 142.068804 -68.58) (xy 142.069345 -68.536149)
			(xy 142.077998 -68.448875) (xy 142.09519 -68.362874) (xy 142.120756 -68.278981) (xy 142.154447 -68.198008)
			(xy 142.174722 -68.159122) (xy 142.180818 -68.134992) (xy 142.174722 -68.110862) (xy 142.154457 -68.071898)
			(xy 142.120829 -67.990759) (xy 142.095367 -67.906699) (xy 142.08633 -67.86372) (xy 142.082774 -67.845686)
			(xy 142.054834 -67.822826) (xy 140.90904 -67.822826) (xy 140.86332 -67.851528) (xy 140.844752 -67.888594)
			(xy 140.801694 -67.959444) (xy 140.752233 -68.025982) (xy 140.696797 -68.08763) (xy 140.635867 -68.143854)
			(xy 140.56997 -68.194166) (xy 140.49968 -68.238131) (xy 140.425604 -68.275367) (xy 140.348386 -68.30555)
			(xy 140.268695 -68.32842) (xy 140.187222 -68.343777) (xy 140.104674 -68.351489) (xy 140.021766 -68.351489)
			(xy 139.939218 -68.343777) (xy 139.857745 -68.32842) (xy 139.778054 -68.30555) (xy 139.700836 -68.275367)
			(xy 139.62676 -68.238131) (xy 139.55647 -68.194166) (xy 139.490573 -68.143854) (xy 139.429643 -68.08763)
			(xy 139.374207 -68.025982) (xy 139.324746 -67.959444) (xy 139.281688 -67.888594) (xy 139.26312 -67.851528)
			(xy 139.2174 -67.822826) (xy 138.0871 -67.822826) (xy 138.07703 -67.82325) (xy 138.058428 -67.830967)
			(xy 138.051032 -67.837812) (xy 137.389616 -68.499228) (xy 137.382772 -68.506627) (xy 137.375045 -68.525225)
			(xy 137.37463 -68.535296) (xy 137.37463 -71.85406) (xy 149.046184 -71.85406) (xy 149.046695 -71.811643)
			(xy 149.054765 -71.727194) (xy 149.070836 -71.643896) (xy 149.094764 -71.562507) (xy 149.12633 -71.483764)
			(xy 149.165248 -71.408384) (xy 149.211164 -71.33705) (xy 149.263662 -71.270412) (xy 149.322265 -71.209073)
			(xy 149.354032 -71.18096) (xy 149.361938 -71.173399) (xy 149.371032 -71.153531) (xy 149.371558 -71.142606)
			(xy 149.371558 -71.06539) (xy 149.371056 -71.054461) (xy 149.361953 -71.034585) (xy 149.354032 -71.027036)
			(xy 149.322275 -70.998912) (xy 149.263673 -70.937573) (xy 149.211174 -70.870935) (xy 149.165256 -70.799603)
			(xy 149.126335 -70.724225) (xy 149.094765 -70.645485) (xy 149.070832 -70.564097) (xy 149.054754 -70.480801)
			(xy 149.046677 -70.396353) (xy 149.046184 -70.353936) (xy 149.046688 -70.311588) (xy 149.054739 -70.227274)
			(xy 149.070768 -70.144108) (xy 149.094629 -70.062841) (xy 149.126108 -69.984211) (xy 149.164919 -69.90893)
			(xy 149.210709 -69.837678) (xy 149.263065 -69.771102) (xy 149.321513 -69.709804) (xy 149.385523 -69.654339)
			(xy 149.454515 -69.60521) (xy 149.527865 -69.562861) (xy 149.604908 -69.527677) (xy 149.684947 -69.499975)
			(xy 149.767256 -69.480007) (xy 149.851091 -69.467954) (xy 149.935692 -69.463924) (xy 150.020293 -69.467954)
			(xy 150.104128 -69.480007) (xy 150.186437 -69.499975) (xy 150.266476 -69.527677) (xy 150.343519 -69.562861)
			(xy 150.416869 -69.60521) (xy 150.485861 -69.654339) (xy 150.549871 -69.709804) (xy 150.608319 -69.771102)
			(xy 150.660675 -69.837678) (xy 150.706465 -69.90893) (xy 150.745276 -69.984211) (xy 150.776755 -70.062841)
			(xy 150.800616 -70.144108) (xy 150.816645 -70.227274) (xy 150.824696 -70.311588) (xy 150.8252 -70.353936)
			(xy 150.824691 -70.396353) (xy 150.816622 -70.480803) (xy 150.800551 -70.5641) (xy 150.776623 -70.64549)
			(xy 150.745057 -70.724233) (xy 150.706139 -70.799613) (xy 150.660221 -70.870946) (xy 150.607723 -70.937585)
			(xy 150.549119 -70.998924) (xy 150.517352 -71.027036) (xy 150.509446 -71.034596) (xy 150.500353 -71.054465)
			(xy 150.499826 -71.06539) (xy 150.499826 -71.142606) (xy 150.500336 -71.153534) (xy 150.509433 -71.173409)
			(xy 150.517352 -71.18096) (xy 150.549103 -71.20909) (xy 150.607707 -71.270428) (xy 150.660206 -71.337064)
			(xy 150.706125 -71.408396) (xy 150.745047 -71.483773) (xy 150.776617 -71.562513) (xy 150.800551 -71.6439)
			(xy 150.816629 -71.727196) (xy 150.824707 -71.811643) (xy 150.8252 -71.85406) (xy 150.824696 -71.896408)
			(xy 150.816645 -71.980722) (xy 150.800616 -72.063888) (xy 150.776755 -72.145155) (xy 150.745276 -72.223785)
			(xy 150.706465 -72.299066) (xy 150.660675 -72.370318) (xy 150.608319 -72.436894) (xy 150.549871 -72.498192)
			(xy 150.485861 -72.553657) (xy 150.416869 -72.602786) (xy 150.343519 -72.645135) (xy 150.266476 -72.680319)
			(xy 150.186437 -72.708021) (xy 150.104128 -72.727989) (xy 150.020293 -72.740042) (xy 149.935692 -72.744073)
			(xy 149.851091 -72.740042) (xy 149.767256 -72.727989) (xy 149.684947 -72.708021) (xy 149.604908 -72.680319)
			(xy 149.527865 -72.645135) (xy 149.454515 -72.602786) (xy 149.385523 -72.553657) (xy 149.321513 -72.498192)
			(xy 149.263065 -72.436894) (xy 149.210709 -72.370318) (xy 149.164919 -72.299066) (xy 149.126108 -72.223785)
			(xy 149.094629 -72.145155) (xy 149.070768 -72.063888) (xy 149.054739 -71.980722) (xy 149.046688 -71.896408)
			(xy 149.046184 -71.85406) (xy 137.37463 -71.85406) (xy 137.37463 -74.360278) (xy 144.226788 -74.360278)
			(xy 144.227274 -74.317132) (xy 144.23562 -74.231244) (xy 144.252241 -74.146568) (xy 144.276981 -74.063898)
			(xy 144.309607 -73.984012) (xy 144.349813 -73.907659) (xy 144.373092 -73.871328) (xy 144.377639 -73.863717)
			(xy 144.381747 -73.846485) (xy 144.37974 -73.828884) (xy 144.37614 -73.820782) (xy 144.358096 -73.78366)
			(xy 144.328174 -73.706728) (xy 144.305503 -73.627357) (xy 144.290279 -73.546227) (xy 144.28263 -73.464037)
			(xy 144.28216 -73.422764) (xy 144.28216 -73.42251) (xy 144.282664 -73.380162) (xy 144.290715 -73.295848)
			(xy 144.306744 -73.212682) (xy 144.330605 -73.131415) (xy 144.362084 -73.052785) (xy 144.400895 -72.977504)
			(xy 144.446685 -72.906252) (xy 144.499041 -72.839676) (xy 144.557489 -72.778378) (xy 144.621499 -72.722913)
			(xy 144.690491 -72.673784) (xy 144.763841 -72.631435) (xy 144.840884 -72.596251) (xy 144.920923 -72.568549)
			(xy 145.003232 -72.548581) (xy 145.087067 -72.536528) (xy 145.171668 -72.532498) (xy 145.256269 -72.536528)
			(xy 145.340104 -72.548581) (xy 145.422413 -72.568549) (xy 145.502452 -72.596251) (xy 145.579495 -72.631435)
			(xy 145.652845 -72.673784) (xy 145.721837 -72.722913) (xy 145.785847 -72.778378) (xy 145.844295 -72.839676)
			(xy 145.896651 -72.906252) (xy 145.942441 -72.977504) (xy 145.981252 -73.052785) (xy 146.012731 -73.131415)
			(xy 146.036592 -73.212682) (xy 146.052621 -73.295848) (xy 146.060672 -73.380162) (xy 146.061176 -73.42251)
			(xy 146.061176 -73.423272) (xy 146.060668 -73.466348) (xy 146.052315 -73.552094) (xy 146.035714 -73.636632)
			(xy 146.011019 -73.719169) (xy 145.978463 -73.798933) (xy 145.93835 -73.875177) (xy 145.915126 -73.91146)
			(xy 145.910587 -73.919075) (xy 145.906476 -73.936305) (xy 145.908479 -73.953905) (xy 145.912078 -73.962006)
			(xy 145.930176 -73.999137) (xy 145.960164 -74.076112) (xy 145.982889 -74.155534) (xy 145.998156 -74.236721)
			(xy 146.005833 -74.318973) (xy 146.006312 -74.360278) (xy 146.005808 -74.402639) (xy 145.997755 -74.486976)
			(xy 145.981721 -74.570166) (xy 145.957853 -74.651456) (xy 145.926365 -74.730108) (xy 145.887543 -74.805411)
			(xy 145.84174 -74.876683) (xy 145.789369 -74.943279) (xy 145.730904 -75.004594) (xy 145.666876 -75.060075)
			(xy 145.597864 -75.109218) (xy 145.524494 -75.151578) (xy 145.447429 -75.186773) (xy 145.367367 -75.214482)
			(xy 145.285034 -75.234456) (xy 145.201175 -75.246513) (xy 145.11655 -75.250545) (xy 145.031925 -75.246513)
			(xy 144.948066 -75.234456) (xy 144.865733 -75.214482) (xy 144.785671 -75.186773) (xy 144.708606 -75.151578)
			(xy 144.635236 -75.109218) (xy 144.566224 -75.060075) (xy 144.502196 -75.004594) (xy 144.443731 -74.943279)
			(xy 144.39136 -74.876683) (xy 144.345557 -74.805411) (xy 144.306735 -74.730108) (xy 144.275247 -74.651456)
			(xy 144.251379 -74.570166) (xy 144.235345 -74.486976) (xy 144.227292 -74.402639) (xy 144.226788 -74.360278)
			(xy 137.37463 -74.360278) (xy 137.37463 -76.8584) (xy 142.64304 -76.8584) (xy 142.64707 -76.773794)
			(xy 142.659125 -76.689953) (xy 142.679094 -76.607639) (xy 142.706798 -76.527595) (xy 142.741985 -76.450547)
			(xy 142.784337 -76.377193) (xy 142.833469 -76.308197) (xy 142.888938 -76.244183) (xy 142.95024 -76.185733)
			(xy 143.016821 -76.133374) (xy 143.088078 -76.087581) (xy 143.163365 -76.048769) (xy 143.242 -76.017289)
			(xy 143.323272 -75.993427) (xy 143.406444 -75.977398) (xy 143.490763 -75.969347) (xy 143.533114 -75.96886)
			(xy 143.533368 -75.96886) (xy 143.576522 -75.969355) (xy 143.662423 -75.977737) (xy 143.747109 -75.994397)
			(xy 143.829784 -76.019177) (xy 143.909671 -76.051846) (xy 143.98602 -76.092095) (xy 144.058114 -76.139548)
			(xy 144.125275 -76.193757) (xy 144.15643 -76.223622) (xy 144.163594 -76.230101) (xy 144.181339 -76.237687)
			(xy 144.190974 -76.238354) (xy 144.270476 -76.239878) (xy 144.28851 -76.23302) (xy 144.295876 -76.226416)
			(xy 144.32649 -76.199346) (xy 144.391887 -76.150331) (xy 144.461506 -76.107524) (xy 144.534759 -76.071287)
			(xy 144.611029 -76.041924) (xy 144.689671 -76.019684) (xy 144.770022 -76.004754) (xy 144.851405 -75.997261)
			(xy 144.892268 -75.9968) (xy 144.892522 -75.9968) (xy 144.93487 -75.997289) (xy 145.019183 -76.005341)
			(xy 145.102348 -76.021372) (xy 145.183614 -76.045236) (xy 145.262242 -76.076716) (xy 145.337523 -76.115527)
			(xy 145.408773 -76.161318) (xy 145.475349 -76.213675) (xy 145.536645 -76.272123) (xy 145.592109 -76.336133)
			(xy 145.641237 -76.405125) (xy 145.683585 -76.478475) (xy 145.718768 -76.555518) (xy 145.74647 -76.635556)
			(xy 145.766437 -76.717865) (xy 145.778491 -76.8017) (xy 145.782521 -76.8863) (xy 145.778491 -76.9709)
			(xy 145.766437 -77.054735) (xy 145.74647 -77.137044) (xy 145.718768 -77.217082) (xy 145.683585 -77.294125)
			(xy 145.641237 -77.367475) (xy 145.592109 -77.436467) (xy 145.536645 -77.500477) (xy 145.475349 -77.558925)
			(xy 145.408773 -77.611282) (xy 145.337523 -77.657073) (xy 145.262242 -77.695884) (xy 145.183614 -77.727364)
			(xy 145.102348 -77.751228) (xy 145.019183 -77.767259) (xy 144.93487 -77.775311) (xy 144.892522 -77.775816)
			(xy 144.892268 -77.775816) (xy 144.849115 -77.775276) (xy 144.763216 -77.766898) (xy 144.678532 -77.750243)
			(xy 144.595858 -77.725468) (xy 144.515971 -77.692806) (xy 144.439621 -77.652563) (xy 144.367526 -77.605117)
			(xy 144.300363 -77.550915) (xy 144.269206 -77.521054) (xy 144.262065 -77.514545) (xy 144.244303 -77.506978)
			(xy 144.234662 -77.506322) (xy 144.15516 -77.504798) (xy 144.137126 -77.511656) (xy 144.12976 -77.51826)
			(xy 144.099127 -77.545309) (xy 144.033734 -77.594326) (xy 143.964118 -77.637135) (xy 143.890867 -77.673375)
			(xy 143.8146 -77.702741) (xy 143.73596 -77.724984) (xy 143.655611 -77.739917) (xy 143.574231 -77.747414)
			(xy 143.533368 -77.747876) (xy 143.533114 -77.747876) (xy 143.490763 -77.747453) (xy 143.406444 -77.739402)
			(xy 143.323272 -77.723373) (xy 143.242 -77.699511) (xy 143.163365 -77.668031) (xy 143.088078 -77.629219)
			(xy 143.016821 -77.583426) (xy 142.95024 -77.531067) (xy 142.888938 -77.472617) (xy 142.833469 -77.408603)
			(xy 142.784337 -77.339607) (xy 142.741985 -77.266253) (xy 142.706798 -77.189205) (xy 142.679094 -77.109161)
			(xy 142.659125 -77.026847) (xy 142.64707 -76.943006) (xy 142.64304 -76.8584) (xy 137.37463 -76.8584)
			(xy 137.37463 -79.7052) (xy 149.144228 -79.7052) (xy 149.144228 -79.704692) (xy 149.144831 -79.65836)
			(xy 149.154503 -79.566202) (xy 149.173699 -79.475548) (xy 149.202212 -79.387379) (xy 149.220428 -79.344774)
			(xy 149.224232 -79.334831) (xy 149.224232 -79.313569) (xy 149.220428 -79.303626) (xy 149.202202 -79.261025)
			(xy 149.173686 -79.172856) (xy 149.154495 -79.082201) (xy 149.144836 -78.99004) (xy 149.144228 -78.943708)
			(xy 149.144228 -78.9432) (xy 149.144732 -78.900852) (xy 149.152783 -78.816538) (xy 149.168812 -78.733372)
			(xy 149.192673 -78.652105) (xy 149.224152 -78.573475) (xy 149.262963 -78.498194) (xy 149.308753 -78.426942)
			(xy 149.361109 -78.360366) (xy 149.419557 -78.299068) (xy 149.483567 -78.243603) (xy 149.552559 -78.194474)
			(xy 149.625909 -78.152125) (xy 149.702952 -78.116941) (xy 149.782991 -78.089239) (xy 149.8653 -78.069271)
			(xy 149.949135 -78.057218) (xy 150.033736 -78.053188) (xy 150.118337 -78.057218) (xy 150.202172 -78.069271)
			(xy 150.284481 -78.089239) (xy 150.36452 -78.116941) (xy 150.441563 -78.152125) (xy 150.514913 -78.194474)
			(xy 150.583905 -78.243603) (xy 150.647915 -78.299068) (xy 150.706363 -78.360366) (xy 150.758719 -78.426942)
			(xy 150.804509 -78.498194) (xy 150.84332 -78.573475) (xy 150.874799 -78.652105) (xy 150.89866 -78.733372)
			(xy 150.914689 -78.816538) (xy 150.92274 -78.900852) (xy 150.923244 -78.9432) (xy 150.923244 -78.943708)
			(xy 150.922635 -78.99004) (xy 150.912964 -79.082198) (xy 150.893769 -79.172852) (xy 150.865258 -79.26102)
			(xy 150.847044 -79.303626) (xy 150.843237 -79.313568) (xy 150.843237 -79.334832) (xy 150.847044 -79.344774)
			(xy 150.865268 -79.387376) (xy 150.893785 -79.475544) (xy 150.912977 -79.5662) (xy 150.922636 -79.65836)
			(xy 150.923244 -79.704692) (xy 150.923244 -79.7052) (xy 150.92274 -79.747548) (xy 150.917888 -79.798361)
			(xy 163.971728 -79.798361) (xy 163.971728 -79.713639) (xy 163.979781 -79.629302) (xy 163.995815 -79.546112)
			(xy 164.019683 -79.464822) (xy 164.051171 -79.38617) (xy 164.089993 -79.310867) (xy 164.135796 -79.239595)
			(xy 164.188167 -79.172999) (xy 164.246632 -79.111684) (xy 164.31066 -79.056203) (xy 164.379672 -79.00706)
			(xy 164.453042 -78.9647) (xy 164.530107 -78.929505) (xy 164.610169 -78.901796) (xy 164.692502 -78.881822)
			(xy 164.776361 -78.869765) (xy 164.860986 -78.865734) (xy 164.945611 -78.869765) (xy 165.02947 -78.881822)
			(xy 165.111803 -78.901796) (xy 165.191865 -78.929505) (xy 165.26893 -78.9647) (xy 165.3423 -79.00706)
			(xy 165.411312 -79.056203) (xy 165.47534 -79.111684) (xy 165.533805 -79.172999) (xy 165.586176 -79.239595)
			(xy 165.631979 -79.310867) (xy 165.670801 -79.38617) (xy 165.702289 -79.464822) (xy 165.726157 -79.546112)
			(xy 165.742191 -79.629302) (xy 165.750244 -79.713639) (xy 165.750748 -79.756) (xy 165.750244 -79.798361)
			(xy 165.742191 -79.882698) (xy 165.726157 -79.965888) (xy 165.702289 -80.047178) (xy 165.670801 -80.12583)
			(xy 165.631979 -80.201133) (xy 165.586176 -80.272405) (xy 165.533805 -80.339001) (xy 165.47534 -80.400316)
			(xy 165.411312 -80.455797) (xy 165.3423 -80.50494) (xy 165.26893 -80.5473) (xy 165.191865 -80.582495)
			(xy 165.111803 -80.610204) (xy 165.02947 -80.630178) (xy 164.945611 -80.642235) (xy 164.860986 -80.646267)
			(xy 164.776361 -80.642235) (xy 164.692502 -80.630178) (xy 164.610169 -80.610204) (xy 164.530107 -80.582495)
			(xy 164.453042 -80.5473) (xy 164.379672 -80.50494) (xy 164.31066 -80.455797) (xy 164.246632 -80.400316)
			(xy 164.188167 -80.339001) (xy 164.135796 -80.272405) (xy 164.089993 -80.201133) (xy 164.051171 -80.12583)
			(xy 164.019683 -80.047178) (xy 163.995815 -79.965888) (xy 163.979781 -79.882698) (xy 163.971728 -79.798361)
			(xy 150.917888 -79.798361) (xy 150.914689 -79.831862) (xy 150.89866 -79.915028) (xy 150.874799 -79.996295)
			(xy 150.84332 -80.074925) (xy 150.804509 -80.150206) (xy 150.758719 -80.221458) (xy 150.706363 -80.288034)
			(xy 150.647915 -80.349332) (xy 150.583905 -80.404797) (xy 150.514913 -80.453926) (xy 150.441563 -80.496275)
			(xy 150.36452 -80.531459) (xy 150.284481 -80.559161) (xy 150.202172 -80.579129) (xy 150.118337 -80.591182)
			(xy 150.033736 -80.595213) (xy 149.949135 -80.591182) (xy 149.8653 -80.579129) (xy 149.782991 -80.559161)
			(xy 149.702952 -80.531459) (xy 149.625909 -80.496275) (xy 149.552559 -80.453926) (xy 149.483567 -80.404797)
			(xy 149.419557 -80.349332) (xy 149.361109 -80.288034) (xy 149.308753 -80.221458) (xy 149.262963 -80.150206)
			(xy 149.224152 -80.074925) (xy 149.192673 -79.996295) (xy 149.168812 -79.915028) (xy 149.152783 -79.831862)
			(xy 149.144732 -79.747548) (xy 149.144228 -79.7052) (xy 137.37463 -79.7052) (xy 137.37463 -79.89062)
			(xy 137.374107 -79.92388) (xy 137.365418 -79.989829) (xy 137.348191 -80.054079) (xy 137.322722 -80.115529)
			(xy 137.289446 -80.173127) (xy 137.248933 -80.225887) (xy 137.225786 -80.249776) (xy 136.598406 -80.877156)
			(xy 136.574527 -80.900315) (xy 136.521765 -80.940827) (xy 136.464165 -80.974102) (xy 136.402713 -80.999573)
			(xy 136.338461 -81.016801) (xy 136.272511 -81.025493) (xy 136.23925 -81.026) (xy 132.161026 -81.026)
			(xy 132.151274 -81.026422) (xy 132.13318 -81.033697) (xy 132.119141 -81.047232) (xy 132.114798 -81.055972)
			(xy 132.070856 -81.154524) (xy 132.075428 -81.183988) (xy 132.085334 -81.195164) (xy 132.112032 -81.225703)
			(xy 132.160366 -81.290855) (xy 132.202566 -81.360138) (xy 132.238281 -81.432976) (xy 132.267213 -81.508765)
			(xy 132.289124 -81.586873) (xy 132.303829 -81.666652) (xy 132.311208 -81.747438) (xy 132.311648 -81.788)
			(xy 132.311181 -81.829247) (xy 132.303544 -81.911386) (xy 132.288336 -81.992466) (xy 132.265687 -82.071789)
			(xy 132.235793 -82.148675) (xy 132.198908 -82.222463) (xy 132.155351 -82.29252) (xy 132.105496 -82.358244)
			(xy 132.04977 -82.41907) (xy 131.988653 -82.474476) (xy 131.922668 -82.523986) (xy 131.852384 -82.567175)
			(xy 131.815586 -82.585814) (xy 131.807248 -82.5903) (xy 131.794411 -82.6042) (xy 131.787515 -82.62182)
			(xy 131.787138 -82.63128) (xy 131.787138 -82.722466) (xy 131.787635 -82.731897) (xy 131.794556 -82.74945)
			(xy 131.807335 -82.763333) (xy 131.815586 -82.767932) (xy 131.852356 -82.786599) (xy 131.922614 -82.829783)
			(xy 131.988576 -82.879282) (xy 132.049675 -82.93467) (xy 132.105389 -82.995474) (xy 132.155238 -83.061171)
			(xy 132.198796 -83.131199) (xy 132.235688 -83.204955) (xy 132.265599 -83.281808) (xy 132.288271 -83.361099)
			(xy 132.303511 -83.442147) (xy 132.311187 -83.524258) (xy 132.311648 -83.565492) (xy 132.311648 -83.566)
			(xy 132.311144 -83.608348) (xy 132.303093 -83.692662) (xy 132.287064 -83.775828) (xy 132.263203 -83.857095)
			(xy 132.231724 -83.935725) (xy 132.192913 -84.011006) (xy 132.147123 -84.082258) (xy 132.094767 -84.148834)
			(xy 132.036319 -84.210132) (xy 131.972309 -84.265597) (xy 131.903317 -84.314726) (xy 131.829967 -84.357075)
			(xy 131.752924 -84.392259) (xy 131.672885 -84.419961) (xy 131.590576 -84.439929) (xy 131.506741 -84.451982)
			(xy 131.42214 -84.456013) (xy 131.337539 -84.451982) (xy 131.253704 -84.439929) (xy 131.171395 -84.419961)
			(xy 131.091356 -84.392259) (xy 131.014313 -84.357075) (xy 130.940963 -84.314726) (xy 130.871971 -84.265597)
			(xy 130.807961 -84.210132) (xy 130.749513 -84.148834) (xy 130.697157 -84.082258) (xy 130.651367 -84.011006)
			(xy 130.612556 -83.935725) (xy 130.581077 -83.857095) (xy 130.557216 -83.775828) (xy 130.541187 -83.692662)
			(xy 130.533136 -83.608348) (xy 130.532632 -83.566) (xy 130.533098 -83.524761) (xy 130.54073 -83.442636)
			(xy 130.555929 -83.36157) (xy 130.578564 -83.282258) (xy 130.608442 -83.205382) (xy 130.645305 -83.131599)
			(xy 130.688837 -83.061545) (xy 130.738665 -82.995819) (xy 130.794361 -82.934986) (xy 130.855448 -82.879568)
			(xy 130.9214 -82.830041) (xy 130.991653 -82.786829) (xy 131.02844 -82.768186) (xy 131.036775 -82.763698)
			(xy 131.049605 -82.749796) (xy 131.056497 -82.732179) (xy 131.056888 -82.72272) (xy 131.056888 -82.631534)
			(xy 131.056392 -82.622102) (xy 131.049472 -82.604546) (xy 131.036697 -82.590658) (xy 131.02844 -82.586068)
			(xy 130.991637 -82.567405) (xy 130.921314 -82.524218) (xy 130.855293 -82.474705) (xy 130.794141 -82.41929)
			(xy 130.738384 -82.358449) (xy 130.688501 -82.292707) (xy 130.64492 -82.222628) (xy 130.608017 -82.148813)
			(xy 130.578109 -82.071899) (xy 130.555452 -81.992545) (xy 130.540242 -81.911434) (xy 130.532608 -81.829263)
			(xy 130.532124 -81.788) (xy 130.532574 -81.747439) (xy 130.539958 -81.666653) (xy 130.554666 -81.586874)
			(xy 130.576574 -81.508766) (xy 130.605502 -81.432977) (xy 130.641209 -81.360135) (xy 130.683398 -81.290846)
			(xy 130.73172 -81.225685) (xy 130.758438 -81.195164) (xy 130.768344 -81.183988) (xy 130.772916 -81.154524)
			(xy 130.728974 -81.055972) (xy 130.724569 -81.047278) (xy 130.710528 -81.033784) (xy 130.692481 -81.026467)
			(xy 130.682746 -81.026) (xy 129.341626 -81.026) (xy 129.331874 -81.026422) (xy 129.31378 -81.033697)
			(xy 129.299741 -81.047232) (xy 129.295398 -81.055972) (xy 129.251456 -81.154524) (xy 129.256028 -81.183988)
			(xy 129.265934 -81.195164) (xy 129.292632 -81.225703) (xy 129.340966 -81.290855) (xy 129.383166 -81.360138)
			(xy 129.418881 -81.432976) (xy 129.447813 -81.508765) (xy 129.469724 -81.586873) (xy 129.484429 -81.666652)
			(xy 129.491808 -81.747438) (xy 129.492248 -81.788) (xy 129.491781 -81.829247) (xy 129.484144 -81.911386)
			(xy 129.468936 -81.992466) (xy 129.446287 -82.071789) (xy 129.416393 -82.148675) (xy 129.379508 -82.222463)
			(xy 129.335951 -82.29252) (xy 129.286096 -82.358244) (xy 129.23037 -82.41907) (xy 129.169253 -82.474476)
			(xy 129.103268 -82.523986) (xy 129.032984 -82.567175) (xy 128.996186 -82.585814) (xy 128.987848 -82.5903)
			(xy 128.975011 -82.6042) (xy 128.968115 -82.62182) (xy 128.967738 -82.63128) (xy 128.967738 -82.72272)
			(xy 128.968227 -82.732156) (xy 128.975138 -82.749722) (xy 128.987915 -82.763618) (xy 128.996186 -82.768186)
			(xy 129.032973 -82.786848) (xy 129.103263 -82.830028) (xy 129.169252 -82.879531) (xy 129.230375 -82.934932)
			(xy 129.286105 -82.995754) (xy 129.335963 -83.061476) (xy 129.379521 -83.131532) (xy 129.416405 -83.205321)
			(xy 129.446299 -83.282208) (xy 129.468944 -83.361532) (xy 129.484146 -83.442613) (xy 129.491776 -83.524753)
			(xy 129.492248 -83.566) (xy 129.491744 -83.608361) (xy 129.483691 -83.692698) (xy 129.467657 -83.775888)
			(xy 129.443789 -83.857178) (xy 129.412301 -83.93583) (xy 129.373479 -84.011133) (xy 129.327676 -84.082405)
			(xy 129.275305 -84.149001) (xy 129.21684 -84.210316) (xy 129.152812 -84.265797) (xy 129.0838 -84.31494)
			(xy 129.01043 -84.3573) (xy 128.933365 -84.392495) (xy 128.853303 -84.420204) (xy 128.77097 -84.440178)
			(xy 128.687111 -84.452235) (xy 128.602486 -84.456267) (xy 128.517861 -84.452235) (xy 128.434002 -84.440178)
			(xy 128.351669 -84.420204) (xy 128.271607 -84.392495) (xy 128.194542 -84.3573) (xy 128.121172 -84.31494)
			(xy 128.05216 -84.265797) (xy 127.988132 -84.210316) (xy 127.929667 -84.149001) (xy 127.877296 -84.082405)
			(xy 127.831493 -84.011133) (xy 127.792671 -83.93583) (xy 127.761183 -83.857178) (xy 127.737315 -83.775888)
			(xy 127.721281 -83.692698) (xy 127.713228 -83.608361) (xy 127.712724 -83.566) (xy 127.713191 -83.524753)
			(xy 127.720827 -83.442613) (xy 127.736035 -83.361533) (xy 127.758684 -83.282209) (xy 127.788578 -83.205322)
			(xy 127.825462 -83.131533) (xy 127.869018 -83.061475) (xy 127.918873 -82.99575) (xy 127.974598 -82.934922)
			(xy 128.035714 -82.879515) (xy 128.101698 -82.830003) (xy 128.171981 -82.786812) (xy 128.208786 -82.768186)
			(xy 128.217115 -82.763693) (xy 128.229933 -82.749789) (xy 128.236818 -82.732175) (xy 128.237234 -82.72272)
			(xy 128.237234 -82.63128) (xy 128.236746 -82.621842) (xy 128.22984 -82.604267) (xy 128.217072 -82.590356)
			(xy 128.208786 -82.585814) (xy 128.171997 -82.567154) (xy 128.101702 -82.523978) (xy 128.035707 -82.474477)
			(xy 127.97458 -82.419078) (xy 127.918846 -82.358256) (xy 127.868983 -82.292535) (xy 127.825421 -82.222478)
			(xy 127.788533 -82.148688) (xy 127.758638 -82.0718) (xy 127.73599 -81.992473) (xy 127.720786 -81.911391)
			(xy 127.713156 -81.829248) (xy 127.712724 -81.788) (xy 127.713174 -81.747439) (xy 127.720558 -81.666653)
			(xy 127.735266 -81.586874) (xy 127.757174 -81.508766) (xy 127.786102 -81.432977) (xy 127.821809 -81.360135)
			(xy 127.863998 -81.290846) (xy 127.91232 -81.225685) (xy 127.939038 -81.195164) (xy 127.948944 -81.183988)
			(xy 127.953516 -81.154524) (xy 127.909574 -81.055972) (xy 127.905169 -81.047278) (xy 127.891128 -81.033784)
			(xy 127.873081 -81.026467) (xy 127.863346 -81.026) (xy 123.4694 -81.026) (xy 123.43614 -81.025479)
			(xy 123.37019 -81.016791) (xy 123.305939 -80.999566) (xy 123.244488 -80.974097) (xy 123.186889 -80.940821)
			(xy 123.134129 -80.900308) (xy 123.110244 -80.877156) (xy 122.475244 -80.242156) (xy 122.452088 -80.218276)
			(xy 122.411582 -80.165512) (xy 122.378311 -80.107911) (xy 122.352847 -80.04646) (xy 122.335625 -79.982209)
			(xy 122.326939 -79.916259) (xy 122.3264 -79.883) (xy 122.3264 -9.304782) (xy 122.325909 -9.294777)
			(xy 122.318246 -9.276291) (xy 122.304094 -9.262144) (xy 122.285605 -9.254488) (xy 122.2756 -9.253982)
			(xy 98.521012 -9.253982) (xy 98.51094 -9.254402) (xy 98.492331 -9.262112) (xy 98.484944 -9.268968)
			(xy 95.805301 -11.948611) (xy 99.749606 -11.948611) (xy 99.749606 -11.863889) (xy 99.757659 -11.779552)
			(xy 99.773693 -11.696362) (xy 99.797561 -11.615072) (xy 99.829049 -11.53642) (xy 99.867871 -11.461117)
			(xy 99.913674 -11.389845) (xy 99.966045 -11.323249) (xy 100.02451 -11.261934) (xy 100.088538 -11.206453)
			(xy 100.15755 -11.15731) (xy 100.23092 -11.11495) (xy 100.307985 -11.079755) (xy 100.388047 -11.052046)
			(xy 100.47038 -11.032072) (xy 100.554239 -11.020015) (xy 100.638864 -11.015984) (xy 100.723489 -11.020015)
			(xy 100.807348 -11.032072) (xy 100.889681 -11.052046) (xy 100.969743 -11.079755) (xy 101.046808 -11.11495)
			(xy 101.120178 -11.15731) (xy 101.18919 -11.206453) (xy 101.253218 -11.261934) (xy 101.311683 -11.323249)
			(xy 101.364054 -11.389845) (xy 101.409857 -11.461117) (xy 101.448679 -11.53642) (xy 101.480167 -11.615072)
			(xy 101.504035 -11.696362) (xy 101.520069 -11.779552) (xy 101.528122 -11.863889) (xy 101.528626 -11.90625)
			(xy 101.528122 -11.948611) (xy 101.520069 -12.032948) (xy 101.504035 -12.116138) (xy 101.480167 -12.197428)
			(xy 101.448679 -12.27608) (xy 101.409857 -12.351383) (xy 101.364054 -12.422655) (xy 101.311683 -12.489251)
			(xy 101.253218 -12.550566) (xy 101.18919 -12.606047) (xy 101.120178 -12.65519) (xy 101.046808 -12.69755)
			(xy 100.969743 -12.732745) (xy 100.889681 -12.760454) (xy 100.807348 -12.780428) (xy 100.723489 -12.792485)
			(xy 100.638864 -12.796517) (xy 100.554239 -12.792485) (xy 100.47038 -12.780428) (xy 100.388047 -12.760454)
			(xy 100.307985 -12.732745) (xy 100.23092 -12.69755) (xy 100.15755 -12.65519) (xy 100.088538 -12.606047)
			(xy 100.02451 -12.550566) (xy 99.966045 -12.489251) (xy 99.913674 -12.422655) (xy 99.867871 -12.351383)
			(xy 99.829049 -12.27608) (xy 99.797561 -12.197428) (xy 99.773693 -12.116138) (xy 99.757659 -12.032948)
			(xy 99.749606 -11.948611) (xy 95.805301 -11.948611) (xy 85.435751 -22.318161) (xy 111.362994 -22.318161)
			(xy 111.362994 -22.233439) (xy 111.371047 -22.149102) (xy 111.387081 -22.065912) (xy 111.410949 -21.984622)
			(xy 111.442437 -21.90597) (xy 111.481259 -21.830667) (xy 111.527062 -21.759395) (xy 111.579433 -21.692799)
			(xy 111.637898 -21.631484) (xy 111.701926 -21.576003) (xy 111.770938 -21.52686) (xy 111.844308 -21.4845)
			(xy 111.921373 -21.449305) (xy 112.001435 -21.421596) (xy 112.083768 -21.401622) (xy 112.167627 -21.389565)
			(xy 112.252252 -21.385534) (xy 112.336877 -21.389565) (xy 112.420736 -21.401622) (xy 112.503069 -21.421596)
			(xy 112.583131 -21.449305) (xy 112.660196 -21.4845) (xy 112.733566 -21.52686) (xy 112.802578 -21.576003)
			(xy 112.866606 -21.631484) (xy 112.925071 -21.692799) (xy 112.977442 -21.759395) (xy 113.023245 -21.830667)
			(xy 113.062067 -21.90597) (xy 113.093555 -21.984622) (xy 113.117423 -22.065912) (xy 113.133457 -22.149102)
			(xy 113.14151 -22.233439) (xy 113.142014 -22.2758) (xy 113.14151 -22.318161) (xy 113.133457 -22.402498)
			(xy 113.117423 -22.485688) (xy 113.093555 -22.566978) (xy 113.062067 -22.64563) (xy 113.023245 -22.720933)
			(xy 112.977442 -22.792205) (xy 112.925071 -22.858801) (xy 112.866606 -22.920116) (xy 112.802578 -22.975597)
			(xy 112.733566 -23.02474) (xy 112.660196 -23.0671) (xy 112.583131 -23.102295) (xy 112.503069 -23.130004)
			(xy 112.420736 -23.149978) (xy 112.336877 -23.162035) (xy 112.252252 -23.166067) (xy 112.167627 -23.162035)
			(xy 112.083768 -23.149978) (xy 112.001435 -23.130004) (xy 111.921373 -23.102295) (xy 111.844308 -23.0671)
			(xy 111.770938 -23.02474) (xy 111.701926 -22.975597) (xy 111.637898 -22.920116) (xy 111.579433 -22.858801)
			(xy 111.527062 -22.792205) (xy 111.481259 -22.720933) (xy 111.442437 -22.64563) (xy 111.410949 -22.566978)
			(xy 111.387081 -22.485688) (xy 111.371047 -22.402498) (xy 111.362994 -22.318161) (xy 85.435751 -22.318161)
			(xy 74.158151 -33.595761) (xy 111.362994 -33.595761) (xy 111.362994 -33.511039) (xy 111.371047 -33.426702)
			(xy 111.387081 -33.343512) (xy 111.410949 -33.262222) (xy 111.442437 -33.18357) (xy 111.481259 -33.108267)
			(xy 111.527062 -33.036995) (xy 111.579433 -32.970399) (xy 111.637898 -32.909084) (xy 111.701926 -32.853603)
			(xy 111.770938 -32.80446) (xy 111.844308 -32.7621) (xy 111.921373 -32.726905) (xy 112.001435 -32.699196)
			(xy 112.083768 -32.679222) (xy 112.167627 -32.667165) (xy 112.252252 -32.663134) (xy 112.336877 -32.667165)
			(xy 112.420736 -32.679222) (xy 112.503069 -32.699196) (xy 112.583131 -32.726905) (xy 112.660196 -32.7621)
			(xy 112.733566 -32.80446) (xy 112.802578 -32.853603) (xy 112.866606 -32.909084) (xy 112.925071 -32.970399)
			(xy 112.977442 -33.036995) (xy 113.023245 -33.108267) (xy 113.062067 -33.18357) (xy 113.093555 -33.262222)
			(xy 113.117423 -33.343512) (xy 113.133457 -33.426702) (xy 113.14151 -33.511039) (xy 113.142014 -33.5534)
			(xy 113.14151 -33.595761) (xy 113.133457 -33.680098) (xy 113.117423 -33.763288) (xy 113.093555 -33.844578)
			(xy 113.062067 -33.92323) (xy 113.023245 -33.998533) (xy 112.977442 -34.069805) (xy 112.925071 -34.136401)
			(xy 112.866606 -34.197716) (xy 112.802578 -34.253197) (xy 112.733566 -34.30234) (xy 112.660196 -34.3447)
			(xy 112.583131 -34.379895) (xy 112.503069 -34.407604) (xy 112.420736 -34.427578) (xy 112.336877 -34.439635)
			(xy 112.252252 -34.443667) (xy 112.167627 -34.439635) (xy 112.083768 -34.427578) (xy 112.001435 -34.407604)
			(xy 111.921373 -34.379895) (xy 111.844308 -34.3447) (xy 111.770938 -34.30234) (xy 111.701926 -34.253197)
			(xy 111.637898 -34.197716) (xy 111.579433 -34.136401) (xy 111.527062 -34.069805) (xy 111.481259 -33.998533)
			(xy 111.442437 -33.92323) (xy 111.410949 -33.844578) (xy 111.387081 -33.763288) (xy 111.371047 -33.680098)
			(xy 111.362994 -33.595761) (xy 74.158151 -33.595761) (xy 73.866756 -33.887156) (xy 73.842876 -33.910312)
			(xy 73.790112 -33.950818) (xy 73.732511 -33.984089) (xy 73.67106 -34.009553) (xy 73.606809 -34.026775)
			(xy 73.540859 -34.035461) (xy 73.5076 -34.036) (xy 35.127184 -34.036) (xy 35.117582 -34.036464) (xy 35.099752 -34.043614)
			(xy 35.085783 -34.056801) (xy 35.077618 -34.07419) (xy 35.076638 -34.083752) (xy 35.076638 -34.084006)
			(xy 35.073868 -34.12609) (xy 35.061364 -34.209502) (xy 35.041021 -34.291356) (xy 35.013021 -34.370917)
			(xy 34.977615 -34.447471) (xy 34.935123 -34.520329) (xy 34.885924 -34.588838) (xy 34.830461 -34.652382)
			(xy 34.769233 -34.71039) (xy 34.702788 -34.762343) (xy 34.631724 -34.807772) (xy 34.556679 -34.846271)
			(xy 34.478327 -34.877494) (xy 34.39737 -34.901159) (xy 34.314538 -34.917055) (xy 34.230572 -34.925039)
			(xy 34.1884 -34.925508) (xy 34.188146 -34.925508) (xy 34.144679 -34.924958) (xy 34.058164 -34.916436)
			(xy 34.015426 -34.90849) (xy 34.014918 -34.90849) (xy 34.002554 -34.906748) (xy 33.978722 -34.914092)
			(xy 33.969452 -34.92246) (xy 30.749551 -38.142361) (xy 33.299142 -38.142361) (xy 33.299142 -38.057639)
			(xy 33.307195 -37.973302) (xy 33.323229 -37.890112) (xy 33.347097 -37.808822) (xy 33.378585 -37.73017)
			(xy 33.417407 -37.654867) (xy 33.46321 -37.583595) (xy 33.515581 -37.516999) (xy 33.574046 -37.455684)
			(xy 33.638074 -37.400203) (xy 33.707086 -37.35106) (xy 33.780456 -37.3087) (xy 33.857521 -37.273505)
			(xy 33.937583 -37.245796) (xy 34.019916 -37.225822) (xy 34.103775 -37.213765) (xy 34.1884 -37.209734)
			(xy 34.273025 -37.213765) (xy 34.356884 -37.225822) (xy 34.439217 -37.245796) (xy 34.519279 -37.273505)
			(xy 34.596344 -37.3087) (xy 34.669714 -37.35106) (xy 34.738726 -37.400203) (xy 34.802754 -37.455684)
			(xy 34.861219 -37.516999) (xy 34.91359 -37.583595) (xy 34.959393 -37.654867) (xy 34.998215 -37.73017)
			(xy 35.029703 -37.808822) (xy 35.053571 -37.890112) (xy 35.069605 -37.973302) (xy 35.077658 -38.057639)
			(xy 35.078162 -38.1) (xy 35.077658 -38.142361) (xy 35.069605 -38.226698) (xy 35.053571 -38.309888)
			(xy 35.029703 -38.391178) (xy 34.998215 -38.46983) (xy 34.959393 -38.545133) (xy 34.91359 -38.616405)
			(xy 34.861219 -38.683001) (xy 34.802754 -38.744316) (xy 34.738726 -38.799797) (xy 34.669714 -38.84894)
			(xy 34.596344 -38.8913) (xy 34.519279 -38.926495) (xy 34.439217 -38.954204) (xy 34.356884 -38.974178)
			(xy 34.273025 -38.986235) (xy 34.1884 -38.990267) (xy 34.103775 -38.986235) (xy 34.019916 -38.974178)
			(xy 33.937583 -38.954204) (xy 33.857521 -38.926495) (xy 33.780456 -38.8913) (xy 33.707086 -38.84894)
			(xy 33.638074 -38.799797) (xy 33.574046 -38.744316) (xy 33.515581 -38.683001) (xy 33.46321 -38.616405)
			(xy 33.417407 -38.545133) (xy 33.378585 -38.46983) (xy 33.347097 -38.391178) (xy 33.323229 -38.309888)
			(xy 33.307195 -38.226698) (xy 33.299142 -38.142361) (xy 30.749551 -38.142361) (xy 26.417327 -42.474585)
			(xy 107.8931 -42.474585) (xy 107.8931 -42.389863) (xy 107.901153 -42.305526) (xy 107.917187 -42.222336)
			(xy 107.941055 -42.141046) (xy 107.972543 -42.062394) (xy 108.011365 -41.987091) (xy 108.057168 -41.915819)
			(xy 108.109539 -41.849223) (xy 108.168004 -41.787908) (xy 108.232032 -41.732427) (xy 108.301044 -41.683284)
			(xy 108.374414 -41.640924) (xy 108.451479 -41.605729) (xy 108.531541 -41.57802) (xy 108.613874 -41.558046)
			(xy 108.697733 -41.545989) (xy 108.782358 -41.541958) (xy 108.866983 -41.545989) (xy 108.950842 -41.558046)
			(xy 109.033175 -41.57802) (xy 109.113237 -41.605729) (xy 109.190302 -41.640924) (xy 109.263672 -41.683284)
			(xy 109.332684 -41.732427) (xy 109.396712 -41.787908) (xy 109.455177 -41.849223) (xy 109.507548 -41.915819)
			(xy 109.553351 -41.987091) (xy 109.592173 -42.062394) (xy 109.623661 -42.141046) (xy 109.647529 -42.222336)
			(xy 109.663563 -42.305526) (xy 109.671616 -42.389863) (xy 109.67212 -42.432224) (xy 109.671616 -42.474585)
			(xy 109.663563 -42.558922) (xy 109.647529 -42.642112) (xy 109.623661 -42.723402) (xy 109.592173 -42.802054)
			(xy 109.553351 -42.877357) (xy 109.507548 -42.948629) (xy 109.455177 -43.015225) (xy 109.396712 -43.07654)
			(xy 109.332684 -43.132021) (xy 109.263672 -43.181164) (xy 109.192316 -43.222361) (xy 110.388142 -43.222361)
			(xy 110.388142 -43.137639) (xy 110.396195 -43.053302) (xy 110.412229 -42.970112) (xy 110.436097 -42.888822)
			(xy 110.467585 -42.81017) (xy 110.506407 -42.734867) (xy 110.55221 -42.663595) (xy 110.604581 -42.596999)
			(xy 110.663046 -42.535684) (xy 110.727074 -42.480203) (xy 110.796086 -42.43106) (xy 110.869456 -42.3887)
			(xy 110.946521 -42.353505) (xy 111.026583 -42.325796) (xy 111.108916 -42.305822) (xy 111.192775 -42.293765)
			(xy 111.2774 -42.289734) (xy 111.362025 -42.293765) (xy 111.445884 -42.305822) (xy 111.528217 -42.325796)
			(xy 111.608279 -42.353505) (xy 111.685344 -42.3887) (xy 111.758714 -42.43106) (xy 111.827726 -42.480203)
			(xy 111.891754 -42.535684) (xy 111.950219 -42.596999) (xy 112.00259 -42.663595) (xy 112.048393 -42.734867)
			(xy 112.087215 -42.81017) (xy 112.118703 -42.888822) (xy 112.142571 -42.970112) (xy 112.158605 -43.053302)
			(xy 112.166658 -43.137639) (xy 112.167162 -43.18) (xy 112.166658 -43.222361) (xy 112.158605 -43.306698)
			(xy 112.142571 -43.389888) (xy 112.118703 -43.471178) (xy 112.087215 -43.54983) (xy 112.048393 -43.625133)
			(xy 112.00259 -43.696405) (xy 111.950219 -43.763001) (xy 111.891754 -43.824316) (xy 111.827726 -43.879797)
			(xy 111.758714 -43.92894) (xy 111.685344 -43.9713) (xy 111.608279 -44.006495) (xy 111.528217 -44.034204)
			(xy 111.445884 -44.054178) (xy 111.362025 -44.066235) (xy 111.2774 -44.070267) (xy 111.192775 -44.066235)
			(xy 111.108916 -44.054178) (xy 111.026583 -44.034204) (xy 110.946521 -44.006495) (xy 110.869456 -43.9713)
			(xy 110.796086 -43.92894) (xy 110.727074 -43.879797) (xy 110.663046 -43.824316) (xy 110.604581 -43.763001)
			(xy 110.55221 -43.696405) (xy 110.506407 -43.625133) (xy 110.467585 -43.54983) (xy 110.436097 -43.471178)
			(xy 110.412229 -43.389888) (xy 110.396195 -43.306698) (xy 110.388142 -43.222361) (xy 109.192316 -43.222361)
			(xy 109.190302 -43.223524) (xy 109.113237 -43.258719) (xy 109.033175 -43.286428) (xy 108.950842 -43.306402)
			(xy 108.866983 -43.318459) (xy 108.782358 -43.322491) (xy 108.697733 -43.318459) (xy 108.613874 -43.306402)
			(xy 108.531541 -43.286428) (xy 108.451479 -43.258719) (xy 108.374414 -43.223524) (xy 108.301044 -43.181164)
			(xy 108.232032 -43.132021) (xy 108.168004 -43.07654) (xy 108.109539 -43.015225) (xy 108.057168 -42.948629)
			(xy 108.011365 -42.877357) (xy 107.972543 -42.802054) (xy 107.941055 -42.723402) (xy 107.917187 -42.642112)
			(xy 107.901153 -42.558922) (xy 107.8931 -42.474585) (xy 26.417327 -42.474585) (xy 23.735538 -45.156374)
			(xy 23.728699 -45.163775) (xy 23.720986 -45.182373) (xy 23.720552 -45.192442) (xy 23.720552 -45.787761)
			(xy 102.768142 -45.787761) (xy 102.768142 -45.703039) (xy 102.776195 -45.618702) (xy 102.792229 -45.535512)
			(xy 102.816097 -45.454222) (xy 102.847585 -45.37557) (xy 102.886407 -45.300267) (xy 102.93221 -45.228995)
			(xy 102.984581 -45.162399) (xy 103.043046 -45.101084) (xy 103.107074 -45.045603) (xy 103.176086 -44.99646)
			(xy 103.249456 -44.9541) (xy 103.326521 -44.918905) (xy 103.406583 -44.891196) (xy 103.488916 -44.871222)
			(xy 103.572775 -44.859165) (xy 103.6574 -44.855134) (xy 103.742025 -44.859165) (xy 103.825884 -44.871222)
			(xy 103.834701 -44.873361) (xy 111.362994 -44.873361) (xy 111.362994 -44.788639) (xy 111.371047 -44.704302)
			(xy 111.387081 -44.621112) (xy 111.410949 -44.539822) (xy 111.442437 -44.46117) (xy 111.481259 -44.385867)
			(xy 111.527062 -44.314595) (xy 111.579433 -44.247999) (xy 111.637898 -44.186684) (xy 111.701926 -44.131203)
			(xy 111.770938 -44.08206) (xy 111.844308 -44.0397) (xy 111.921373 -44.004505) (xy 112.001435 -43.976796)
			(xy 112.083768 -43.956822) (xy 112.167627 -43.944765) (xy 112.252252 -43.940734) (xy 112.336877 -43.944765)
			(xy 112.420736 -43.956822) (xy 112.503069 -43.976796) (xy 112.583131 -44.004505) (xy 112.660196 -44.0397)
			(xy 112.733566 -44.08206) (xy 112.802578 -44.131203) (xy 112.866606 -44.186684) (xy 112.925071 -44.247999)
			(xy 112.977442 -44.314595) (xy 113.023245 -44.385867) (xy 113.062067 -44.46117) (xy 113.093555 -44.539822)
			(xy 113.117423 -44.621112) (xy 113.133457 -44.704302) (xy 113.14151 -44.788639) (xy 113.142014 -44.831)
			(xy 113.14151 -44.873361) (xy 113.133457 -44.957698) (xy 113.117423 -45.040888) (xy 113.093555 -45.122178)
			(xy 113.062067 -45.20083) (xy 113.023245 -45.276133) (xy 112.977442 -45.347405) (xy 112.925071 -45.414001)
			(xy 112.866606 -45.475316) (xy 112.802578 -45.530797) (xy 112.733566 -45.57994) (xy 112.660196 -45.6223)
			(xy 112.583131 -45.657495) (xy 112.503069 -45.685204) (xy 112.420736 -45.705178) (xy 112.336877 -45.717235)
			(xy 112.252252 -45.721267) (xy 112.167627 -45.717235) (xy 112.083768 -45.705178) (xy 112.001435 -45.685204)
			(xy 111.921373 -45.657495) (xy 111.844308 -45.6223) (xy 111.770938 -45.57994) (xy 111.701926 -45.530797)
			(xy 111.637898 -45.475316) (xy 111.579433 -45.414001) (xy 111.527062 -45.347405) (xy 111.481259 -45.276133)
			(xy 111.442437 -45.20083) (xy 111.410949 -45.122178) (xy 111.387081 -45.040888) (xy 111.371047 -44.957698)
			(xy 111.362994 -44.873361) (xy 103.834701 -44.873361) (xy 103.908217 -44.891196) (xy 103.988279 -44.918905)
			(xy 104.065344 -44.9541) (xy 104.138714 -44.99646) (xy 104.207726 -45.045603) (xy 104.271754 -45.101084)
			(xy 104.330219 -45.162399) (xy 104.38259 -45.228995) (xy 104.428393 -45.300267) (xy 104.467215 -45.37557)
			(xy 104.498703 -45.454222) (xy 104.522571 -45.535512) (xy 104.538605 -45.618702) (xy 104.546658 -45.703039)
			(xy 104.547162 -45.7454) (xy 104.546658 -45.787761) (xy 104.538605 -45.872098) (xy 104.522571 -45.955288)
			(xy 104.498703 -46.036578) (xy 104.467215 -46.11523) (xy 104.428393 -46.190533) (xy 104.38259 -46.261805)
			(xy 104.330219 -46.328401) (xy 104.271754 -46.389716) (xy 104.207726 -46.445197) (xy 104.138714 -46.49434)
			(xy 104.065344 -46.5367) (xy 103.988279 -46.571895) (xy 103.908217 -46.599604) (xy 103.825884 -46.619578)
			(xy 103.742025 -46.631635) (xy 103.6574 -46.635667) (xy 103.572775 -46.631635) (xy 103.488916 -46.619578)
			(xy 103.406583 -46.599604) (xy 103.326521 -46.571895) (xy 103.249456 -46.5367) (xy 103.176086 -46.49434)
			(xy 103.107074 -46.445197) (xy 103.043046 -46.389716) (xy 102.984581 -46.328401) (xy 102.93221 -46.261805)
			(xy 102.886407 -46.190533) (xy 102.847585 -46.11523) (xy 102.816097 -46.036578) (xy 102.792229 -45.955288)
			(xy 102.776195 -45.872098) (xy 102.768142 -45.787761) (xy 23.720552 -45.787761) (xy 23.720552 -50.919888)
			(xy 40.838131 -50.919888) (xy 40.842106 -50.809829) (xy 40.854014 -50.700343) (xy 40.87379 -50.592002)
			(xy 40.901333 -50.485371) (xy 40.936498 -50.381005) (xy 40.979102 -50.279448) (xy 41.028923 -50.181231)
			(xy 41.085702 -50.086864) (xy 41.149141 -49.99684) (xy 41.218912 -49.911629) (xy 41.294649 -49.831674)
			(xy 41.375958 -49.757393) (xy 41.462415 -49.689173) (xy 41.553569 -49.627368) (xy 41.648946 -49.572303)
			(xy 41.748047 -49.524263) (xy 41.850356 -49.483499) (xy 41.95534 -49.450224) (xy 42.062451 -49.424611)
			(xy 42.171131 -49.406794) (xy 42.280814 -49.396865) (xy 42.390927 -49.394877) (xy 42.500897 -49.400839)
			(xy 42.61015 -49.414721) (xy 42.718116 -49.436451) (xy 42.824233 -49.465914) (xy 42.927947 -49.502957)
			(xy 43.028718 -49.547388) (xy 43.12602 -49.598975) (xy 43.219346 -49.657447) (xy 43.308209 -49.722502)
			(xy 43.392147 -49.7938) (xy 43.470722 -49.870968) (xy 43.543523 -49.953605) (xy 43.610171 -50.041279)
			(xy 43.67032 -50.133535) (xy 43.723654 -50.22989) (xy 43.769897 -50.329842) (xy 43.808807 -50.43287)
			(xy 43.840181 -50.538438) (xy 43.863856 -50.645994) (xy 43.879708 -50.754978) (xy 43.887655 -50.864822)
			(xy 43.888152 -50.919888) (xy 60.396131 -50.919888) (xy 60.400106 -50.809829) (xy 60.412014 -50.700343)
			(xy 60.43179 -50.592002) (xy 60.459333 -50.485371) (xy 60.494498 -50.381005) (xy 60.537102 -50.279448)
			(xy 60.586923 -50.181231) (xy 60.643702 -50.086864) (xy 60.707141 -49.99684) (xy 60.776912 -49.911629)
			(xy 60.852649 -49.831674) (xy 60.933958 -49.757393) (xy 61.020415 -49.689173) (xy 61.111569 -49.627368)
			(xy 61.206946 -49.572303) (xy 61.306047 -49.524263) (xy 61.408356 -49.483499) (xy 61.51334 -49.450224)
			(xy 61.620451 -49.424611) (xy 61.729131 -49.406794) (xy 61.838814 -49.396865) (xy 61.948927 -49.394877)
			(xy 62.058897 -49.400839) (xy 62.16815 -49.414721) (xy 62.276116 -49.436451) (xy 62.382233 -49.465914)
			(xy 62.485947 -49.502957) (xy 62.586718 -49.547388) (xy 62.68402 -49.598975) (xy 62.777346 -49.657447)
			(xy 62.866209 -49.722502) (xy 62.950147 -49.7938) (xy 63.028722 -49.870968) (xy 63.101523 -49.953605)
			(xy 63.168171 -50.041279) (xy 63.22832 -50.133535) (xy 63.281654 -50.22989) (xy 63.327897 -50.329842)
			(xy 63.366807 -50.43287) (xy 63.398181 -50.538438) (xy 63.421856 -50.645994) (xy 63.437708 -50.754978)
			(xy 63.445655 -50.864822) (xy 63.446152 -50.919888) (xy 63.445655 -50.974954) (xy 63.437708 -51.084798)
			(xy 63.421856 -51.193782) (xy 63.398181 -51.301338) (xy 63.366807 -51.406906) (xy 63.327897 -51.509934)
			(xy 63.281654 -51.609886) (xy 63.22832 -51.706241) (xy 63.168171 -51.798497) (xy 63.101523 -51.886171)
			(xy 63.028722 -51.968808) (xy 62.950147 -52.045976) (xy 62.866209 -52.117274) (xy 62.777346 -52.182329)
			(xy 62.68402 -52.240801) (xy 62.586718 -52.292388) (xy 62.485947 -52.336819) (xy 62.382233 -52.373862)
			(xy 62.276116 -52.403325) (xy 62.16815 -52.425055) (xy 62.058897 -52.438937) (xy 61.948927 -52.444899)
			(xy 61.838814 -52.442911) (xy 61.729131 -52.432982) (xy 61.620451 -52.415165) (xy 61.51334 -52.389552)
			(xy 61.408356 -52.356277) (xy 61.306047 -52.315513) (xy 61.206946 -52.267473) (xy 61.111569 -52.212408)
			(xy 61.020415 -52.150603) (xy 60.933958 -52.082383) (xy 60.852649 -52.008102) (xy 60.776912 -51.928147)
			(xy 60.707141 -51.842936) (xy 60.643702 -51.752912) (xy 60.586923 -51.658545) (xy 60.537102 -51.560328)
			(xy 60.494498 -51.458771) (xy 60.459333 -51.354405) (xy 60.43179 -51.247774) (xy 60.412014 -51.139433)
			(xy 60.400106 -51.029947) (xy 60.396131 -50.919888) (xy 43.888152 -50.919888) (xy 43.887655 -50.974954)
			(xy 43.879708 -51.084798) (xy 43.863856 -51.193782) (xy 43.840181 -51.301338) (xy 43.808807 -51.406906)
			(xy 43.769897 -51.509934) (xy 43.723654 -51.609886) (xy 43.67032 -51.706241) (xy 43.610171 -51.798497)
			(xy 43.543523 -51.886171) (xy 43.470722 -51.968808) (xy 43.392147 -52.045976) (xy 43.308209 -52.117274)
			(xy 43.219346 -52.182329) (xy 43.12602 -52.240801) (xy 43.028718 -52.292388) (xy 42.927947 -52.336819)
			(xy 42.824233 -52.373862) (xy 42.718116 -52.403325) (xy 42.61015 -52.425055) (xy 42.500897 -52.438937)
			(xy 42.390927 -52.444899) (xy 42.280814 -52.442911) (xy 42.171131 -52.432982) (xy 42.062451 -52.415165)
			(xy 41.95534 -52.389552) (xy 41.850356 -52.356277) (xy 41.748047 -52.315513) (xy 41.648946 -52.267473)
			(xy 41.553569 -52.212408) (xy 41.462415 -52.150603) (xy 41.375958 -52.082383) (xy 41.294649 -52.008102)
			(xy 41.218912 -51.928147) (xy 41.149141 -51.842936) (xy 41.085702 -51.752912) (xy 41.028923 -51.658545)
			(xy 40.979102 -51.560328) (xy 40.936498 -51.458771) (xy 40.901333 -51.354405) (xy 40.87379 -51.247774)
			(xy 40.854014 -51.139433) (xy 40.842106 -51.029947) (xy 40.838131 -50.919888) (xy 23.720552 -50.919888)
			(xy 23.720552 -53.735167) (xy 108.485174 -53.735167) (xy 108.485174 -53.650445) (xy 108.493227 -53.566108)
			(xy 108.509261 -53.482918) (xy 108.533129 -53.401628) (xy 108.564617 -53.322976) (xy 108.603439 -53.247673)
			(xy 108.649242 -53.176401) (xy 108.701613 -53.109805) (xy 108.760078 -53.04849) (xy 108.824106 -52.993009)
			(xy 108.893118 -52.943866) (xy 108.966488 -52.901506) (xy 109.043553 -52.866311) (xy 109.123615 -52.838602)
			(xy 109.205948 -52.818628) (xy 109.289807 -52.806571) (xy 109.374432 -52.80254) (xy 109.459057 -52.806571)
			(xy 109.542916 -52.818628) (xy 109.625249 -52.838602) (xy 109.705311 -52.866311) (xy 109.782376 -52.901506)
			(xy 109.855746 -52.943866) (xy 109.924758 -52.993009) (xy 109.988786 -53.04849) (xy 110.047251 -53.109805)
			(xy 110.099622 -53.176401) (xy 110.145425 -53.247673) (xy 110.184247 -53.322976) (xy 110.215735 -53.401628)
			(xy 110.239603 -53.482918) (xy 110.255637 -53.566108) (xy 110.26369 -53.650445) (xy 110.264194 -53.692806)
			(xy 110.26369 -53.735167) (xy 110.255637 -53.819504) (xy 110.239603 -53.902694) (xy 110.215735 -53.983984)
			(xy 110.184247 -54.062636) (xy 110.145425 -54.137939) (xy 110.099622 -54.209211) (xy 110.047251 -54.275807)
			(xy 109.988786 -54.337122) (xy 109.924758 -54.392603) (xy 109.855746 -54.441746) (xy 109.782376 -54.484106)
			(xy 109.705311 -54.519301) (xy 109.687801 -54.525361) (xy 110.388142 -54.525361) (xy 110.388142 -54.440639)
			(xy 110.396195 -54.356302) (xy 110.412229 -54.273112) (xy 110.436097 -54.191822) (xy 110.467585 -54.11317)
			(xy 110.506407 -54.037867) (xy 110.55221 -53.966595) (xy 110.604581 -53.899999) (xy 110.663046 -53.838684)
			(xy 110.727074 -53.783203) (xy 110.796086 -53.73406) (xy 110.869456 -53.6917) (xy 110.946521 -53.656505)
			(xy 111.026583 -53.628796) (xy 111.108916 -53.608822) (xy 111.192775 -53.596765) (xy 111.2774 -53.592734)
			(xy 111.362025 -53.596765) (xy 111.445884 -53.608822) (xy 111.528217 -53.628796) (xy 111.608279 -53.656505)
			(xy 111.685344 -53.6917) (xy 111.758714 -53.73406) (xy 111.827726 -53.783203) (xy 111.891754 -53.838684)
			(xy 111.950219 -53.899999) (xy 112.00259 -53.966595) (xy 112.048393 -54.037867) (xy 112.087215 -54.11317)
			(xy 112.118703 -54.191822) (xy 112.142571 -54.273112) (xy 112.158605 -54.356302) (xy 112.166658 -54.440639)
			(xy 112.167162 -54.483) (xy 112.166658 -54.525361) (xy 112.158605 -54.609698) (xy 112.142571 -54.692888)
			(xy 112.118703 -54.774178) (xy 112.087215 -54.85283) (xy 112.048393 -54.928133) (xy 112.00259 -54.999405)
			(xy 111.950219 -55.066001) (xy 111.891754 -55.127316) (xy 111.827726 -55.182797) (xy 111.758714 -55.23194)
			(xy 111.685344 -55.2743) (xy 111.608279 -55.309495) (xy 111.528217 -55.337204) (xy 111.445884 -55.357178)
			(xy 111.362025 -55.369235) (xy 111.2774 -55.373267) (xy 111.192775 -55.369235) (xy 111.108916 -55.357178)
			(xy 111.026583 -55.337204) (xy 110.946521 -55.309495) (xy 110.869456 -55.2743) (xy 110.796086 -55.23194)
			(xy 110.727074 -55.182797) (xy 110.663046 -55.127316) (xy 110.604581 -55.066001) (xy 110.55221 -54.999405)
			(xy 110.506407 -54.928133) (xy 110.467585 -54.85283) (xy 110.436097 -54.774178) (xy 110.412229 -54.692888)
			(xy 110.396195 -54.609698) (xy 110.388142 -54.525361) (xy 109.687801 -54.525361) (xy 109.625249 -54.54701)
			(xy 109.542916 -54.566984) (xy 109.459057 -54.579041) (xy 109.374432 -54.583073) (xy 109.289807 -54.579041)
			(xy 109.205948 -54.566984) (xy 109.123615 -54.54701) (xy 109.043553 -54.519301) (xy 108.966488 -54.484106)
			(xy 108.893118 -54.441746) (xy 108.824106 -54.392603) (xy 108.760078 -54.337122) (xy 108.701613 -54.275807)
			(xy 108.649242 -54.209211) (xy 108.603439 -54.137939) (xy 108.564617 -54.062636) (xy 108.533129 -53.983984)
			(xy 108.509261 -53.902694) (xy 108.493227 -53.819504) (xy 108.485174 -53.735167) (xy 23.720552 -53.735167)
			(xy 23.720552 -57.065361) (xy 102.768142 -57.065361) (xy 102.768142 -56.980639) (xy 102.776195 -56.896302)
			(xy 102.792229 -56.813112) (xy 102.816097 -56.731822) (xy 102.847585 -56.65317) (xy 102.886407 -56.577867)
			(xy 102.93221 -56.506595) (xy 102.984581 -56.439999) (xy 103.043046 -56.378684) (xy 103.107074 -56.323203)
			(xy 103.176086 -56.27406) (xy 103.249456 -56.2317) (xy 103.326521 -56.196505) (xy 103.406583 -56.168796)
			(xy 103.488916 -56.148822) (xy 103.572775 -56.136765) (xy 103.6574 -56.132734) (xy 103.742025 -56.136765)
			(xy 103.825884 -56.148822) (xy 103.834701 -56.150961) (xy 111.362994 -56.150961) (xy 111.362994 -56.066239)
			(xy 111.371047 -55.981902) (xy 111.387081 -55.898712) (xy 111.410949 -55.817422) (xy 111.442437 -55.73877)
			(xy 111.481259 -55.663467) (xy 111.527062 -55.592195) (xy 111.579433 -55.525599) (xy 111.637898 -55.464284)
			(xy 111.701926 -55.408803) (xy 111.770938 -55.35966) (xy 111.844308 -55.3173) (xy 111.921373 -55.282105)
			(xy 112.001435 -55.254396) (xy 112.083768 -55.234422) (xy 112.167627 -55.222365) (xy 112.252252 -55.218334)
			(xy 112.336877 -55.222365) (xy 112.420736 -55.234422) (xy 112.503069 -55.254396) (xy 112.583131 -55.282105)
			(xy 112.660196 -55.3173) (xy 112.733566 -55.35966) (xy 112.802578 -55.408803) (xy 112.866606 -55.464284)
			(xy 112.925071 -55.525599) (xy 112.977442 -55.592195) (xy 113.023245 -55.663467) (xy 113.062067 -55.73877)
			(xy 113.093555 -55.817422) (xy 113.117423 -55.898712) (xy 113.133457 -55.981902) (xy 113.14151 -56.066239)
			(xy 113.142014 -56.1086) (xy 113.14151 -56.150961) (xy 113.133457 -56.235298) (xy 113.117423 -56.318488)
			(xy 113.093555 -56.399778) (xy 113.062067 -56.47843) (xy 113.023245 -56.553733) (xy 112.977442 -56.625005)
			(xy 112.925071 -56.691601) (xy 112.866606 -56.752916) (xy 112.802578 -56.808397) (xy 112.733566 -56.85754)
			(xy 112.660196 -56.8999) (xy 112.583131 -56.935095) (xy 112.503069 -56.962804) (xy 112.420736 -56.982778)
			(xy 112.336877 -56.994835) (xy 112.252252 -56.998867) (xy 112.167627 -56.994835) (xy 112.083768 -56.982778)
			(xy 112.001435 -56.962804) (xy 111.921373 -56.935095) (xy 111.844308 -56.8999) (xy 111.770938 -56.85754)
			(xy 111.701926 -56.808397) (xy 111.637898 -56.752916) (xy 111.579433 -56.691601) (xy 111.527062 -56.625005)
			(xy 111.481259 -56.553733) (xy 111.442437 -56.47843) (xy 111.410949 -56.399778) (xy 111.387081 -56.318488)
			(xy 111.371047 -56.235298) (xy 111.362994 -56.150961) (xy 103.834701 -56.150961) (xy 103.908217 -56.168796)
			(xy 103.988279 -56.196505) (xy 104.065344 -56.2317) (xy 104.138714 -56.27406) (xy 104.207726 -56.323203)
			(xy 104.271754 -56.378684) (xy 104.330219 -56.439999) (xy 104.38259 -56.506595) (xy 104.428393 -56.577867)
			(xy 104.467215 -56.65317) (xy 104.498703 -56.731822) (xy 104.522571 -56.813112) (xy 104.538605 -56.896302)
			(xy 104.546658 -56.980639) (xy 104.547162 -57.023) (xy 104.546658 -57.065361) (xy 104.538605 -57.149698)
			(xy 104.522571 -57.232888) (xy 104.498703 -57.314178) (xy 104.467215 -57.39283) (xy 104.428393 -57.468133)
			(xy 104.38259 -57.539405) (xy 104.330219 -57.606001) (xy 104.271754 -57.667316) (xy 104.207726 -57.722797)
			(xy 104.138714 -57.77194) (xy 104.065344 -57.8143) (xy 103.988279 -57.849495) (xy 103.908217 -57.877204)
			(xy 103.825884 -57.897178) (xy 103.742025 -57.909235) (xy 103.6574 -57.913267) (xy 103.572775 -57.909235)
			(xy 103.488916 -57.897178) (xy 103.406583 -57.877204) (xy 103.326521 -57.849495) (xy 103.249456 -57.8143)
			(xy 103.176086 -57.77194) (xy 103.107074 -57.722797) (xy 103.043046 -57.667316) (xy 102.984581 -57.606001)
			(xy 102.93221 -57.539405) (xy 102.886407 -57.468133) (xy 102.847585 -57.39283) (xy 102.816097 -57.314178)
			(xy 102.792229 -57.232888) (xy 102.776195 -57.149698) (xy 102.768142 -57.065361) (xy 23.720552 -57.065361)
			(xy 23.720552 -58.42) (xy 41.345876 -58.42) (xy 41.349858 -58.330072) (xy 41.361772 -58.240848) (xy 41.381525 -58.153026)
			(xy 41.408962 -58.067293) (xy 41.443869 -57.984321) (xy 41.485973 -57.904758) (xy 41.534943 -57.829228)
			(xy 41.590398 -57.758322) (xy 41.651902 -57.692594) (xy 41.718974 -57.632559) (xy 41.79109 -57.578687)
			(xy 41.867685 -57.531399) (xy 41.948159 -57.491066) (xy 42.031883 -57.458003) (xy 42.118202 -57.432469)
			(xy 42.20644 -57.414664) (xy 42.295905 -57.404726) (xy 42.3859 -57.402735) (xy 42.475717 -57.408705)
			(xy 42.564656 -57.42259) (xy 42.65202 -57.444281) (xy 42.737125 -57.473608) (xy 42.819304 -57.510342)
			(xy 42.897916 -57.554196) (xy 42.972344 -57.604825) (xy 43.042006 -57.661835) (xy 43.106357 -57.724778)
			(xy 43.164894 -57.793162) (xy 43.217157 -57.866452) (xy 43.262739 -57.944074) (xy 43.301282 -58.025421)
			(xy 43.332485 -58.109856) (xy 43.356103 -58.196718) (xy 43.371952 -58.285328) (xy 43.379908 -58.374992)
			(xy 43.380406 -58.42) (xy 60.903876 -58.42) (xy 60.907858 -58.330072) (xy 60.919772 -58.240848) (xy 60.939525 -58.153026)
			(xy 60.966962 -58.067293) (xy 61.001869 -57.984321) (xy 61.043973 -57.904758) (xy 61.092943 -57.829228)
			(xy 61.148398 -57.758322) (xy 61.209902 -57.692594) (xy 61.276974 -57.632559) (xy 61.34909 -57.578687)
			(xy 61.425685 -57.531399) (xy 61.506159 -57.491066) (xy 61.589883 -57.458003) (xy 61.676202 -57.432469)
			(xy 61.76444 -57.414664) (xy 61.853905 -57.404726) (xy 61.9439 -57.402735) (xy 62.033717 -57.408705)
			(xy 62.122656 -57.42259) (xy 62.21002 -57.444281) (xy 62.295125 -57.473608) (xy 62.377304 -57.510342)
			(xy 62.455916 -57.554196) (xy 62.530344 -57.604825) (xy 62.600006 -57.661835) (xy 62.664357 -57.724778)
			(xy 62.722894 -57.793162) (xy 62.775157 -57.866452) (xy 62.820739 -57.944074) (xy 62.859282 -58.025421)
			(xy 62.890485 -58.109856) (xy 62.914103 -58.196718) (xy 62.929952 -58.285328) (xy 62.937908 -58.374992)
			(xy 62.938406 -58.42) (xy 62.937908 -58.465008) (xy 62.929952 -58.554672) (xy 62.914103 -58.643282)
			(xy 62.890485 -58.730144) (xy 62.859282 -58.814579) (xy 62.820739 -58.895926) (xy 62.775157 -58.973548)
			(xy 62.722894 -59.046838) (xy 62.664357 -59.115222) (xy 62.600006 -59.178165) (xy 62.530344 -59.235175)
			(xy 62.455916 -59.285804) (xy 62.377304 -59.329658) (xy 62.295125 -59.366392) (xy 62.21002 -59.395719)
			(xy 62.122656 -59.41741) (xy 62.033717 -59.431295) (xy 61.9439 -59.437265) (xy 61.853905 -59.435274)
			(xy 61.76444 -59.425336) (xy 61.676202 -59.407531) (xy 61.589883 -59.381997) (xy 61.506159 -59.348934)
			(xy 61.425685 -59.308601) (xy 61.34909 -59.261313) (xy 61.276974 -59.207441) (xy 61.209902 -59.147406)
			(xy 61.148398 -59.081678) (xy 61.092943 -59.010772) (xy 61.043973 -58.935242) (xy 61.001869 -58.855679)
			(xy 60.966962 -58.772707) (xy 60.939525 -58.686974) (xy 60.919772 -58.599152) (xy 60.907858 -58.509928)
			(xy 60.903876 -58.42) (xy 43.380406 -58.42) (xy 43.379908 -58.465008) (xy 43.371952 -58.554672) (xy 43.356103 -58.643282)
			(xy 43.332485 -58.730144) (xy 43.301282 -58.814579) (xy 43.262739 -58.895926) (xy 43.217157 -58.973548)
			(xy 43.164894 -59.046838) (xy 43.106357 -59.115222) (xy 43.042006 -59.178165) (xy 42.972344 -59.235175)
			(xy 42.897916 -59.285804) (xy 42.819304 -59.329658) (xy 42.737125 -59.366392) (xy 42.65202 -59.395719)
			(xy 42.564656 -59.41741) (xy 42.475717 -59.431295) (xy 42.3859 -59.437265) (xy 42.295905 -59.435274)
			(xy 42.20644 -59.425336) (xy 42.118202 -59.407531) (xy 42.031883 -59.381997) (xy 41.948159 -59.348934)
			(xy 41.867685 -59.308601) (xy 41.79109 -59.261313) (xy 41.718974 -59.207441) (xy 41.651902 -59.147406)
			(xy 41.590398 -59.081678) (xy 41.534943 -59.010772) (xy 41.485973 -58.935242) (xy 41.443869 -58.855679)
			(xy 41.408962 -58.772707) (xy 41.381525 -58.686974) (xy 41.361772 -58.599152) (xy 41.349858 -58.509928)
			(xy 41.345876 -58.42) (xy 23.720552 -58.42) (xy 23.720552 -67.428561) (xy 111.362994 -67.428561)
			(xy 111.362994 -67.343839) (xy 111.371047 -67.259502) (xy 111.387081 -67.176312) (xy 111.410949 -67.095022)
			(xy 111.442437 -67.01637) (xy 111.481259 -66.941067) (xy 111.527062 -66.869795) (xy 111.579433 -66.803199)
			(xy 111.637898 -66.741884) (xy 111.701926 -66.686403) (xy 111.770938 -66.63726) (xy 111.844308 -66.5949)
			(xy 111.921373 -66.559705) (xy 112.001435 -66.531996) (xy 112.083768 -66.512022) (xy 112.167627 -66.499965)
			(xy 112.252252 -66.495934) (xy 112.336877 -66.499965) (xy 112.420736 -66.512022) (xy 112.503069 -66.531996)
			(xy 112.583131 -66.559705) (xy 112.660196 -66.5949) (xy 112.733566 -66.63726) (xy 112.802578 -66.686403)
			(xy 112.866606 -66.741884) (xy 112.925071 -66.803199) (xy 112.977442 -66.869795) (xy 113.023245 -66.941067)
			(xy 113.062067 -67.01637) (xy 113.093555 -67.095022) (xy 113.117423 -67.176312) (xy 113.133457 -67.259502)
			(xy 113.14151 -67.343839) (xy 113.142014 -67.3862) (xy 113.14151 -67.428561) (xy 113.133457 -67.512898)
			(xy 113.117423 -67.596088) (xy 113.093555 -67.677378) (xy 113.062067 -67.75603) (xy 113.023245 -67.831333)
			(xy 112.977442 -67.902605) (xy 112.925071 -67.969201) (xy 112.866606 -68.030516) (xy 112.802578 -68.085997)
			(xy 112.733566 -68.13514) (xy 112.660196 -68.1775) (xy 112.583131 -68.212695) (xy 112.503069 -68.240404)
			(xy 112.420736 -68.260378) (xy 112.336877 -68.272435) (xy 112.252252 -68.276467) (xy 112.167627 -68.272435)
			(xy 112.083768 -68.260378) (xy 112.001435 -68.240404) (xy 111.921373 -68.212695) (xy 111.844308 -68.1775)
			(xy 111.770938 -68.13514) (xy 111.701926 -68.085997) (xy 111.637898 -68.030516) (xy 111.579433 -67.969201)
			(xy 111.527062 -67.902605) (xy 111.481259 -67.831333) (xy 111.442437 -67.75603) (xy 111.410949 -67.677378)
			(xy 111.387081 -67.596088) (xy 111.371047 -67.512898) (xy 111.362994 -67.428561) (xy 23.720552 -67.428561)
			(xy 23.720552 -71.239888) (xy 40.838131 -71.239888) (xy 40.842106 -71.129829) (xy 40.854014 -71.020343)
			(xy 40.87379 -70.912002) (xy 40.901333 -70.805371) (xy 40.936498 -70.701005) (xy 40.979102 -70.599448)
			(xy 41.028923 -70.501231) (xy 41.085702 -70.406864) (xy 41.149141 -70.31684) (xy 41.218912 -70.231629)
			(xy 41.294649 -70.151674) (xy 41.375958 -70.077393) (xy 41.462415 -70.009173) (xy 41.553569 -69.947368)
			(xy 41.648946 -69.892303) (xy 41.748047 -69.844263) (xy 41.850356 -69.803499) (xy 41.95534 -69.770224)
			(xy 42.062451 -69.744611) (xy 42.171131 -69.726794) (xy 42.280814 -69.716865) (xy 42.390927 -69.714877)
			(xy 42.500897 -69.720839) (xy 42.61015 -69.734721) (xy 42.718116 -69.756451) (xy 42.824233 -69.785914)
			(xy 42.927947 -69.822957) (xy 43.028718 -69.867388) (xy 43.12602 -69.918975) (xy 43.219346 -69.977447)
			(xy 43.308209 -70.042502) (xy 43.392147 -70.1138) (xy 43.470722 -70.190968) (xy 43.543523 -70.273605)
			(xy 43.610171 -70.361279) (xy 43.67032 -70.453535) (xy 43.723654 -70.54989) (xy 43.769897 -70.649842)
			(xy 43.808807 -70.75287) (xy 43.840181 -70.858438) (xy 43.863856 -70.965994) (xy 43.879708 -71.074978)
			(xy 43.887655 -71.184822) (xy 43.888152 -71.239888) (xy 60.396131 -71.239888) (xy 60.400106 -71.129829)
			(xy 60.412014 -71.020343) (xy 60.43179 -70.912002) (xy 60.459333 -70.805371) (xy 60.494498 -70.701005)
			(xy 60.537102 -70.599448) (xy 60.586923 -70.501231) (xy 60.643702 -70.406864) (xy 60.707141 -70.31684)
			(xy 60.776912 -70.231629) (xy 60.852649 -70.151674) (xy 60.933958 -70.077393) (xy 61.020415 -70.009173)
			(xy 61.111569 -69.947368) (xy 61.206946 -69.892303) (xy 61.306047 -69.844263) (xy 61.408356 -69.803499)
			(xy 61.51334 -69.770224) (xy 61.620451 -69.744611) (xy 61.729131 -69.726794) (xy 61.838814 -69.716865)
			(xy 61.948927 -69.714877) (xy 62.058897 -69.720839) (xy 62.16815 -69.734721) (xy 62.276116 -69.756451)
			(xy 62.382233 -69.785914) (xy 62.485947 -69.822957) (xy 62.586718 -69.867388) (xy 62.68402 -69.918975)
			(xy 62.777346 -69.977447) (xy 62.866209 -70.042502) (xy 62.950147 -70.1138) (xy 63.028722 -70.190968)
			(xy 63.101523 -70.273605) (xy 63.168171 -70.361279) (xy 63.22832 -70.453535) (xy 63.281654 -70.54989)
			(xy 63.327897 -70.649842) (xy 63.366807 -70.75287) (xy 63.398181 -70.858438) (xy 63.421856 -70.965994)
			(xy 63.437708 -71.074978) (xy 63.445655 -71.184822) (xy 63.446152 -71.239888) (xy 63.445655 -71.294954)
			(xy 63.437708 -71.404798) (xy 63.421856 -71.513782) (xy 63.398181 -71.621338) (xy 63.366807 -71.726906)
			(xy 63.327897 -71.829934) (xy 63.281654 -71.929886) (xy 63.22832 -72.026241) (xy 63.168171 -72.118497)
			(xy 63.101523 -72.206171) (xy 63.028722 -72.288808) (xy 62.950147 -72.365976) (xy 62.866209 -72.437274)
			(xy 62.777346 -72.502329) (xy 62.68402 -72.560801) (xy 62.586718 -72.612388) (xy 62.485947 -72.656819)
			(xy 62.382233 -72.693862) (xy 62.276116 -72.723325) (xy 62.16815 -72.745055) (xy 62.058897 -72.758937)
			(xy 61.948927 -72.764899) (xy 61.838814 -72.762911) (xy 61.729131 -72.752982) (xy 61.620451 -72.735165)
			(xy 61.51334 -72.709552) (xy 61.408356 -72.676277) (xy 61.306047 -72.635513) (xy 61.206946 -72.587473)
			(xy 61.111569 -72.532408) (xy 61.020415 -72.470603) (xy 60.933958 -72.402383) (xy 60.852649 -72.328102)
			(xy 60.776912 -72.248147) (xy 60.707141 -72.162936) (xy 60.643702 -72.072912) (xy 60.586923 -71.978545)
			(xy 60.537102 -71.880328) (xy 60.494498 -71.778771) (xy 60.459333 -71.674405) (xy 60.43179 -71.567774)
			(xy 60.412014 -71.459433) (xy 60.400106 -71.349947) (xy 60.396131 -71.239888) (xy 43.888152 -71.239888)
			(xy 43.887655 -71.294954) (xy 43.879708 -71.404798) (xy 43.863856 -71.513782) (xy 43.840181 -71.621338)
			(xy 43.808807 -71.726906) (xy 43.769897 -71.829934) (xy 43.723654 -71.929886) (xy 43.67032 -72.026241)
			(xy 43.610171 -72.118497) (xy 43.543523 -72.206171) (xy 43.470722 -72.288808) (xy 43.392147 -72.365976)
			(xy 43.308209 -72.437274) (xy 43.219346 -72.502329) (xy 43.12602 -72.560801) (xy 43.028718 -72.612388)
			(xy 42.927947 -72.656819) (xy 42.824233 -72.693862) (xy 42.718116 -72.723325) (xy 42.61015 -72.745055)
			(xy 42.500897 -72.758937) (xy 42.390927 -72.764899) (xy 42.280814 -72.762911) (xy 42.171131 -72.752982)
			(xy 42.062451 -72.735165) (xy 41.95534 -72.709552) (xy 41.850356 -72.676277) (xy 41.748047 -72.635513)
			(xy 41.648946 -72.587473) (xy 41.553569 -72.532408) (xy 41.462415 -72.470603) (xy 41.375958 -72.402383)
			(xy 41.294649 -72.328102) (xy 41.218912 -72.248147) (xy 41.149141 -72.162936) (xy 41.085702 -72.072912)
			(xy 41.028923 -71.978545) (xy 40.979102 -71.880328) (xy 40.936498 -71.778771) (xy 40.901333 -71.674405)
			(xy 40.87379 -71.567774) (xy 40.854014 -71.459433) (xy 40.842106 -71.349947) (xy 40.838131 -71.239888)
			(xy 23.720552 -71.239888) (xy 23.720552 -78.74) (xy 41.345876 -78.74) (xy 41.349858 -78.650072) (xy 41.361772 -78.560848)
			(xy 41.381525 -78.473026) (xy 41.408962 -78.387293) (xy 41.443869 -78.304321) (xy 41.485973 -78.224758)
			(xy 41.534943 -78.149228) (xy 41.590398 -78.078322) (xy 41.651902 -78.012594) (xy 41.718974 -77.952559)
			(xy 41.79109 -77.898687) (xy 41.867685 -77.851399) (xy 41.948159 -77.811066) (xy 42.031883 -77.778003)
			(xy 42.118202 -77.752469) (xy 42.20644 -77.734664) (xy 42.295905 -77.724726) (xy 42.3859 -77.722735)
			(xy 42.475717 -77.728705) (xy 42.564656 -77.74259) (xy 42.65202 -77.764281) (xy 42.737125 -77.793608)
			(xy 42.819304 -77.830342) (xy 42.897916 -77.874196) (xy 42.972344 -77.924825) (xy 43.042006 -77.981835)
			(xy 43.106357 -78.044778) (xy 43.164894 -78.113162) (xy 43.217157 -78.186452) (xy 43.262739 -78.264074)
			(xy 43.301282 -78.345421) (xy 43.332485 -78.429856) (xy 43.356103 -78.516718) (xy 43.371952 -78.605328)
			(xy 43.379908 -78.694992) (xy 43.380406 -78.74) (xy 60.903876 -78.74) (xy 60.907858 -78.650072) (xy 60.919772 -78.560848)
			(xy 60.939525 -78.473026) (xy 60.966962 -78.387293) (xy 61.001869 -78.304321) (xy 61.043973 -78.224758)
			(xy 61.092943 -78.149228) (xy 61.148398 -78.078322) (xy 61.209902 -78.012594) (xy 61.276974 -77.952559)
			(xy 61.34909 -77.898687) (xy 61.425685 -77.851399) (xy 61.506159 -77.811066) (xy 61.589883 -77.778003)
			(xy 61.676202 -77.752469) (xy 61.76444 -77.734664) (xy 61.853905 -77.724726) (xy 61.9439 -77.722735)
			(xy 62.033717 -77.728705) (xy 62.122656 -77.74259) (xy 62.21002 -77.764281) (xy 62.295125 -77.793608)
			(xy 62.377304 -77.830342) (xy 62.455916 -77.874196) (xy 62.530344 -77.924825) (xy 62.600006 -77.981835)
			(xy 62.664357 -78.044778) (xy 62.722894 -78.113162) (xy 62.775157 -78.186452) (xy 62.820739 -78.264074)
			(xy 62.859282 -78.345421) (xy 62.890485 -78.429856) (xy 62.914103 -78.516718) (xy 62.929952 -78.605328)
			(xy 62.937908 -78.694992) (xy 62.938032 -78.706161) (xy 111.362994 -78.706161) (xy 111.362994 -78.621439)
			(xy 111.371047 -78.537102) (xy 111.387081 -78.453912) (xy 111.410949 -78.372622) (xy 111.442437 -78.29397)
			(xy 111.481259 -78.218667) (xy 111.527062 -78.147395) (xy 111.579433 -78.080799) (xy 111.637898 -78.019484)
			(xy 111.701926 -77.964003) (xy 111.770938 -77.91486) (xy 111.844308 -77.8725) (xy 111.921373 -77.837305)
			(xy 112.001435 -77.809596) (xy 112.083768 -77.789622) (xy 112.167627 -77.777565) (xy 112.252252 -77.773534)
			(xy 112.336877 -77.777565) (xy 112.420736 -77.789622) (xy 112.503069 -77.809596) (xy 112.583131 -77.837305)
			(xy 112.660196 -77.8725) (xy 112.733566 -77.91486) (xy 112.802578 -77.964003) (xy 112.866606 -78.019484)
			(xy 112.925071 -78.080799) (xy 112.977442 -78.147395) (xy 113.023245 -78.218667) (xy 113.062067 -78.29397)
			(xy 113.093555 -78.372622) (xy 113.117423 -78.453912) (xy 113.133457 -78.537102) (xy 113.14151 -78.621439)
			(xy 113.142014 -78.6638) (xy 113.14151 -78.706161) (xy 113.133457 -78.790498) (xy 113.117423 -78.873688)
			(xy 113.093555 -78.954978) (xy 113.062067 -79.03363) (xy 113.023245 -79.108933) (xy 112.977442 -79.180205)
			(xy 112.925071 -79.246801) (xy 112.866606 -79.308116) (xy 112.802578 -79.363597) (xy 112.733566 -79.41274)
			(xy 112.660196 -79.4551) (xy 112.583131 -79.490295) (xy 112.503069 -79.518004) (xy 112.420736 -79.537978)
			(xy 112.336877 -79.550035) (xy 112.252252 -79.554067) (xy 112.167627 -79.550035) (xy 112.083768 -79.537978)
			(xy 112.001435 -79.518004) (xy 111.921373 -79.490295) (xy 111.844308 -79.4551) (xy 111.770938 -79.41274)
			(xy 111.701926 -79.363597) (xy 111.637898 -79.308116) (xy 111.579433 -79.246801) (xy 111.527062 -79.180205)
			(xy 111.481259 -79.108933) (xy 111.442437 -79.03363) (xy 111.410949 -78.954978) (xy 111.387081 -78.873688)
			(xy 111.371047 -78.790498) (xy 111.362994 -78.706161) (xy 62.938032 -78.706161) (xy 62.938406 -78.74)
			(xy 62.937908 -78.785008) (xy 62.929952 -78.874672) (xy 62.914103 -78.963282) (xy 62.890485 -79.050144)
			(xy 62.859282 -79.134579) (xy 62.820739 -79.215926) (xy 62.775157 -79.293548) (xy 62.722894 -79.366838)
			(xy 62.664357 -79.435222) (xy 62.600006 -79.498165) (xy 62.530344 -79.555175) (xy 62.455916 -79.605804)
			(xy 62.377304 -79.649658) (xy 62.295125 -79.686392) (xy 62.21002 -79.715719) (xy 62.122656 -79.73741)
			(xy 62.033717 -79.751295) (xy 61.9439 -79.757265) (xy 61.853905 -79.755274) (xy 61.76444 -79.745336)
			(xy 61.676202 -79.727531) (xy 61.589883 -79.701997) (xy 61.506159 -79.668934) (xy 61.425685 -79.628601)
			(xy 61.34909 -79.581313) (xy 61.276974 -79.527441) (xy 61.209902 -79.467406) (xy 61.148398 -79.401678)
			(xy 61.092943 -79.330772) (xy 61.043973 -79.255242) (xy 61.001869 -79.175679) (xy 60.966962 -79.092707)
			(xy 60.939525 -79.006974) (xy 60.919772 -78.919152) (xy 60.907858 -78.829928) (xy 60.903876 -78.74)
			(xy 43.380406 -78.74) (xy 43.379908 -78.785008) (xy 43.371952 -78.874672) (xy 43.356103 -78.963282)
			(xy 43.332485 -79.050144) (xy 43.301282 -79.134579) (xy 43.262739 -79.215926) (xy 43.217157 -79.293548)
			(xy 43.164894 -79.366838) (xy 43.106357 -79.435222) (xy 43.042006 -79.498165) (xy 42.972344 -79.555175)
			(xy 42.897916 -79.605804) (xy 42.819304 -79.649658) (xy 42.737125 -79.686392) (xy 42.65202 -79.715719)
			(xy 42.564656 -79.73741) (xy 42.475717 -79.751295) (xy 42.3859 -79.757265) (xy 42.295905 -79.755274)
			(xy 42.20644 -79.745336) (xy 42.118202 -79.727531) (xy 42.031883 -79.701997) (xy 41.948159 -79.668934)
			(xy 41.867685 -79.628601) (xy 41.79109 -79.581313) (xy 41.718974 -79.527441) (xy 41.651902 -79.467406)
			(xy 41.590398 -79.401678) (xy 41.534943 -79.330772) (xy 41.485973 -79.255242) (xy 41.443869 -79.175679)
			(xy 41.408962 -79.092707) (xy 41.381525 -79.006974) (xy 41.361772 -78.919152) (xy 41.349858 -78.829928)
			(xy 41.345876 -78.74) (xy 23.720552 -78.74) (xy 23.720552 -91.559888) (xy 40.838131 -91.559888) (xy 40.842106 -91.449829)
			(xy 40.854014 -91.340343) (xy 40.87379 -91.232002) (xy 40.901333 -91.125371) (xy 40.936498 -91.021005)
			(xy 40.979102 -90.919448) (xy 41.028923 -90.821231) (xy 41.085702 -90.726864) (xy 41.149141 -90.63684)
			(xy 41.218912 -90.551629) (xy 41.294649 -90.471674) (xy 41.375958 -90.397393) (xy 41.462415 -90.329173)
			(xy 41.553569 -90.267368) (xy 41.648946 -90.212303) (xy 41.748047 -90.164263) (xy 41.850356 -90.123499)
			(xy 41.95534 -90.090224) (xy 42.062451 -90.064611) (xy 42.171131 -90.046794) (xy 42.280814 -90.036865)
			(xy 42.390927 -90.034877) (xy 42.500897 -90.040839) (xy 42.61015 -90.054721) (xy 42.718116 -90.076451)
			(xy 42.824233 -90.105914) (xy 42.927947 -90.142957) (xy 43.028718 -90.187388) (xy 43.12602 -90.238975)
			(xy 43.219346 -90.297447) (xy 43.308209 -90.362502) (xy 43.392147 -90.4338) (xy 43.470722 -90.510968)
			(xy 43.543523 -90.593605) (xy 43.610171 -90.681279) (xy 43.67032 -90.773535) (xy 43.723654 -90.86989)
			(xy 43.769897 -90.969842) (xy 43.808807 -91.07287) (xy 43.840181 -91.178438) (xy 43.863856 -91.285994)
			(xy 43.879708 -91.394978) (xy 43.887655 -91.504822) (xy 43.888152 -91.559888) (xy 60.396131 -91.559888)
			(xy 60.400106 -91.449829) (xy 60.412014 -91.340343) (xy 60.43179 -91.232002) (xy 60.459333 -91.125371)
			(xy 60.494498 -91.021005) (xy 60.537102 -90.919448) (xy 60.586923 -90.821231) (xy 60.643702 -90.726864)
			(xy 60.707141 -90.63684) (xy 60.776912 -90.551629) (xy 60.852649 -90.471674) (xy 60.933958 -90.397393)
			(xy 61.020415 -90.329173) (xy 61.111569 -90.267368) (xy 61.206946 -90.212303) (xy 61.306047 -90.164263)
			(xy 61.408356 -90.123499) (xy 61.51334 -90.090224) (xy 61.620451 -90.064611) (xy 61.729131 -90.046794)
			(xy 61.838814 -90.036865) (xy 61.948927 -90.034877) (xy 62.058897 -90.040839) (xy 62.16815 -90.054721)
			(xy 62.276116 -90.076451) (xy 62.382233 -90.105914) (xy 62.485947 -90.142957) (xy 62.586718 -90.187388)
			(xy 62.68402 -90.238975) (xy 62.777346 -90.297447) (xy 62.866209 -90.362502) (xy 62.950147 -90.4338)
			(xy 63.028722 -90.510968) (xy 63.101523 -90.593605) (xy 63.168171 -90.681279) (xy 63.22832 -90.773535)
			(xy 63.281654 -90.86989) (xy 63.327897 -90.969842) (xy 63.366807 -91.07287) (xy 63.398181 -91.178438)
			(xy 63.421856 -91.285994) (xy 63.437708 -91.394978) (xy 63.445655 -91.504822) (xy 63.446152 -91.559888)
			(xy 63.445655 -91.614954) (xy 63.437708 -91.724798) (xy 63.421856 -91.833782) (xy 63.398181 -91.941338)
			(xy 63.366807 -92.046906) (xy 63.327897 -92.149934) (xy 63.281654 -92.249886) (xy 63.22832 -92.346241)
			(xy 63.168171 -92.438497) (xy 63.121269 -92.500196) (xy 94.864936 -92.500196) (xy 94.864936 -87.500206)
			(xy 94.865431 -87.399365) (xy 94.873349 -87.197838) (xy 94.889173 -86.996778) (xy 94.912878 -86.796494)
			(xy 94.944428 -86.597295) (xy 94.983774 -86.399488) (xy 95.030856 -86.203379) (xy 95.085601 -86.009269)
			(xy 95.147924 -85.817458) (xy 95.217729 -85.628241) (xy 95.29491 -85.441912) (xy 95.379346 -85.258755)
			(xy 95.470908 -85.079055) (xy 95.569454 -84.903089) (xy 95.674832 -84.731126) (xy 95.786881 -84.563434)
			(xy 95.905427 -84.40027) (xy 96.030287 -84.241885) (xy 96.161269 -84.088525) (xy 96.298171 -83.940425)
			(xy 96.440781 -83.797815) (xy 96.588881 -83.660913) (xy 96.742241 -83.529931) (xy 96.900626 -83.405071)
			(xy 97.06379 -83.286525) (xy 97.231482 -83.174476) (xy 97.403445 -83.069098) (xy 97.579411 -82.970552)
			(xy 97.759111 -82.87899) (xy 97.942268 -82.794554) (xy 98.128597 -82.717373) (xy 98.317814 -82.647568)
			(xy 98.509625 -82.585245) (xy 98.703735 -82.5305) (xy 98.899844 -82.483418) (xy 99.097651 -82.444072)
			(xy 99.29685 -82.412522) (xy 99.497134 -82.388817) (xy 99.698194 -82.372993) (xy 99.899721 -82.365075)
			(xy 100.101403 -82.365075) (xy 100.30293 -82.372993) (xy 100.50399 -82.388817) (xy 100.704274 -82.412522)
			(xy 100.903473 -82.444072) (xy 101.10128 -82.483418) (xy 101.297389 -82.5305) (xy 101.491499 -82.585245)
			(xy 101.68331 -82.647568) (xy 101.872527 -82.717373) (xy 102.058856 -82.794554) (xy 102.242013 -82.87899)
			(xy 102.421713 -82.970552) (xy 102.597679 -83.069098) (xy 102.769642 -83.174476) (xy 102.937334 -83.286525)
			(xy 103.100498 -83.405071) (xy 103.258883 -83.529931) (xy 103.412243 -83.660913) (xy 103.560343 -83.797815)
			(xy 103.702953 -83.940425) (xy 103.839855 -84.088525) (xy 103.970837 -84.241885) (xy 104.095697 -84.40027)
			(xy 104.214243 -84.563434) (xy 104.326292 -84.731126) (xy 104.43167 -84.903089) (xy 104.530216 -85.079055)
			(xy 104.621778 -85.258755) (xy 104.706214 -85.441912) (xy 104.783395 -85.628241) (xy 104.8532 -85.817458)
			(xy 104.915523 -86.009269) (xy 104.970268 -86.203379) (xy 105.01735 -86.399488) (xy 105.056696 -86.597295)
			(xy 105.088246 -86.796494) (xy 105.111951 -86.996778) (xy 105.127775 -87.197838) (xy 105.135693 -87.399365)
			(xy 105.136188 -87.500206) (xy 105.136188 -92.500196) (xy 105.135693 -92.601037) (xy 105.127775 -92.802564)
			(xy 105.111951 -93.003624) (xy 105.088246 -93.203908) (xy 105.056696 -93.403107) (xy 105.01735 -93.600914)
			(xy 104.970268 -93.797023) (xy 104.915523 -93.991133) (xy 104.8532 -94.182944) (xy 104.783395 -94.372161)
			(xy 104.706214 -94.55849) (xy 104.621778 -94.741647) (xy 104.530216 -94.921347) (xy 104.43167 -95.097313)
			(xy 104.326292 -95.269276) (xy 104.214243 -95.436968) (xy 104.095697 -95.600132) (xy 103.970837 -95.758517)
			(xy 103.839855 -95.911877) (xy 103.702953 -96.059977) (xy 103.560343 -96.202587) (xy 103.412243 -96.339489)
			(xy 103.258883 -96.470471) (xy 103.100498 -96.595331) (xy 102.937334 -96.713877) (xy 102.769642 -96.825926)
			(xy 102.597679 -96.931304) (xy 102.421713 -97.02985) (xy 102.242013 -97.121412) (xy 102.058856 -97.205848)
			(xy 101.872527 -97.283029) (xy 101.68331 -97.352834) (xy 101.491499 -97.415157) (xy 101.297389 -97.469902)
			(xy 101.10128 -97.516984) (xy 100.903473 -97.55633) (xy 100.704274 -97.58788) (xy 100.50399 -97.611585)
			(xy 100.30293 -97.627409) (xy 100.101403 -97.635327) (xy 99.899721 -97.635327) (xy 99.698194 -97.627409)
			(xy 99.497134 -97.611585) (xy 99.29685 -97.58788) (xy 99.097651 -97.55633) (xy 98.899844 -97.516984)
			(xy 98.703735 -97.469902) (xy 98.509625 -97.415157) (xy 98.317814 -97.352834) (xy 98.128597 -97.283029)
			(xy 97.942268 -97.205848) (xy 97.759111 -97.121412) (xy 97.579411 -97.02985) (xy 97.403445 -96.931304)
			(xy 97.231482 -96.825926) (xy 97.06379 -96.713877) (xy 96.900626 -96.595331) (xy 96.742241 -96.470471)
			(xy 96.588881 -96.339489) (xy 96.440781 -96.202587) (xy 96.298171 -96.059977) (xy 96.161269 -95.911877)
			(xy 96.030287 -95.758517) (xy 95.905427 -95.600132) (xy 95.786881 -95.436968) (xy 95.674832 -95.269276)
			(xy 95.569454 -95.097313) (xy 95.470908 -94.921347) (xy 95.379346 -94.741647) (xy 95.29491 -94.55849)
			(xy 95.217729 -94.372161) (xy 95.147924 -94.182944) (xy 95.085601 -93.991133) (xy 95.030856 -93.797023)
			(xy 94.983774 -93.600914) (xy 94.944428 -93.403107) (xy 94.912878 -93.203908) (xy 94.889173 -93.003624)
			(xy 94.873349 -92.802564) (xy 94.865431 -92.601037) (xy 94.864936 -92.500196) (xy 63.121269 -92.500196)
			(xy 63.101523 -92.526171) (xy 63.028722 -92.608808) (xy 62.950147 -92.685976) (xy 62.866209 -92.757274)
			(xy 62.777346 -92.822329) (xy 62.68402 -92.880801) (xy 62.586718 -92.932388) (xy 62.485947 -92.976819)
			(xy 62.382233 -93.013862) (xy 62.276116 -93.043325) (xy 62.16815 -93.065055) (xy 62.058897 -93.078937)
			(xy 61.948927 -93.084899) (xy 61.838814 -93.082911) (xy 61.729131 -93.072982) (xy 61.620451 -93.055165)
			(xy 61.51334 -93.029552) (xy 61.408356 -92.996277) (xy 61.306047 -92.955513) (xy 61.206946 -92.907473)
			(xy 61.111569 -92.852408) (xy 61.020415 -92.790603) (xy 60.933958 -92.722383) (xy 60.852649 -92.648102)
			(xy 60.776912 -92.568147) (xy 60.707141 -92.482936) (xy 60.643702 -92.392912) (xy 60.586923 -92.298545)
			(xy 60.537102 -92.200328) (xy 60.494498 -92.098771) (xy 60.459333 -91.994405) (xy 60.43179 -91.887774)
			(xy 60.412014 -91.779433) (xy 60.400106 -91.669947) (xy 60.396131 -91.559888) (xy 43.888152 -91.559888)
			(xy 43.887655 -91.614954) (xy 43.879708 -91.724798) (xy 43.863856 -91.833782) (xy 43.840181 -91.941338)
			(xy 43.808807 -92.046906) (xy 43.769897 -92.149934) (xy 43.723654 -92.249886) (xy 43.67032 -92.346241)
			(xy 43.610171 -92.438497) (xy 43.543523 -92.526171) (xy 43.470722 -92.608808) (xy 43.392147 -92.685976)
			(xy 43.308209 -92.757274) (xy 43.219346 -92.822329) (xy 43.12602 -92.880801) (xy 43.028718 -92.932388)
			(xy 42.927947 -92.976819) (xy 42.824233 -93.013862) (xy 42.718116 -93.043325) (xy 42.61015 -93.065055)
			(xy 42.500897 -93.078937) (xy 42.390927 -93.084899) (xy 42.280814 -93.082911) (xy 42.171131 -93.072982)
			(xy 42.062451 -93.055165) (xy 41.95534 -93.029552) (xy 41.850356 -92.996277) (xy 41.748047 -92.955513)
			(xy 41.648946 -92.907473) (xy 41.553569 -92.852408) (xy 41.462415 -92.790603) (xy 41.375958 -92.722383)
			(xy 41.294649 -92.648102) (xy 41.218912 -92.568147) (xy 41.149141 -92.482936) (xy 41.085702 -92.392912)
			(xy 41.028923 -92.298545) (xy 40.979102 -92.200328) (xy 40.936498 -92.098771) (xy 40.901333 -91.994405)
			(xy 40.87379 -91.887774) (xy 40.854014 -91.779433) (xy 40.842106 -91.669947) (xy 40.838131 -91.559888)
			(xy 23.720552 -91.559888) (xy 23.720552 -99.06) (xy 41.345876 -99.06) (xy 41.349858 -98.970072) (xy 41.361772 -98.880848)
			(xy 41.381525 -98.793026) (xy 41.408962 -98.707293) (xy 41.443869 -98.624321) (xy 41.485973 -98.544758)
			(xy 41.534943 -98.469228) (xy 41.590398 -98.398322) (xy 41.651902 -98.332594) (xy 41.718974 -98.272559)
			(xy 41.79109 -98.218687) (xy 41.867685 -98.171399) (xy 41.948159 -98.131066) (xy 42.031883 -98.098003)
			(xy 42.118202 -98.072469) (xy 42.20644 -98.054664) (xy 42.295905 -98.044726) (xy 42.3859 -98.042735)
			(xy 42.475717 -98.048705) (xy 42.564656 -98.06259) (xy 42.65202 -98.084281) (xy 42.737125 -98.113608)
			(xy 42.819304 -98.150342) (xy 42.897916 -98.194196) (xy 42.972344 -98.244825) (xy 43.042006 -98.301835)
			(xy 43.106357 -98.364778) (xy 43.164894 -98.433162) (xy 43.217157 -98.506452) (xy 43.262739 -98.584074)
			(xy 43.301282 -98.665421) (xy 43.332485 -98.749856) (xy 43.356103 -98.836718) (xy 43.371952 -98.925328)
			(xy 43.379908 -99.014992) (xy 43.380406 -99.06) (xy 60.903876 -99.06) (xy 60.907858 -98.970072) (xy 60.919772 -98.880848)
			(xy 60.939525 -98.793026) (xy 60.966962 -98.707293) (xy 61.001869 -98.624321) (xy 61.043973 -98.544758)
			(xy 61.092943 -98.469228) (xy 61.148398 -98.398322) (xy 61.209902 -98.332594) (xy 61.276974 -98.272559)
			(xy 61.34909 -98.218687) (xy 61.425685 -98.171399) (xy 61.506159 -98.131066) (xy 61.589883 -98.098003)
			(xy 61.676202 -98.072469) (xy 61.76444 -98.054664) (xy 61.853905 -98.044726) (xy 61.9439 -98.042735)
			(xy 62.033717 -98.048705) (xy 62.122656 -98.06259) (xy 62.21002 -98.084281) (xy 62.295125 -98.113608)
			(xy 62.377304 -98.150342) (xy 62.455916 -98.194196) (xy 62.530344 -98.244825) (xy 62.600006 -98.301835)
			(xy 62.664357 -98.364778) (xy 62.722894 -98.433162) (xy 62.775157 -98.506452) (xy 62.820739 -98.584074)
			(xy 62.859282 -98.665421) (xy 62.890485 -98.749856) (xy 62.914103 -98.836718) (xy 62.929952 -98.925328)
			(xy 62.937908 -99.014992) (xy 62.938406 -99.06) (xy 62.937908 -99.105008) (xy 62.929952 -99.194672)
			(xy 62.914103 -99.283282) (xy 62.890485 -99.370144) (xy 62.859282 -99.454579) (xy 62.820739 -99.535926)
			(xy 62.775157 -99.613548) (xy 62.722894 -99.686838) (xy 62.664357 -99.755222) (xy 62.600006 -99.818165)
			(xy 62.530344 -99.875175) (xy 62.455916 -99.925804) (xy 62.377304 -99.969658) (xy 62.295125 -100.006392)
			(xy 62.21002 -100.035719) (xy 62.122656 -100.05741) (xy 62.033717 -100.071295) (xy 61.9439 -100.077265)
			(xy 61.853905 -100.075274) (xy 61.76444 -100.065336) (xy 61.676202 -100.047531) (xy 61.589883 -100.021997)
			(xy 61.506159 -99.988934) (xy 61.425685 -99.948601) (xy 61.34909 -99.901313) (xy 61.276974 -99.847441)
			(xy 61.209902 -99.787406) (xy 61.148398 -99.721678) (xy 61.092943 -99.650772) (xy 61.043973 -99.575242)
			(xy 61.001869 -99.495679) (xy 60.966962 -99.412707) (xy 60.939525 -99.326974) (xy 60.919772 -99.239152)
			(xy 60.907858 -99.149928) (xy 60.903876 -99.06) (xy 43.380406 -99.06) (xy 43.379908 -99.105008) (xy 43.371952 -99.194672)
			(xy 43.356103 -99.283282) (xy 43.332485 -99.370144) (xy 43.301282 -99.454579) (xy 43.262739 -99.535926)
			(xy 43.217157 -99.613548) (xy 43.164894 -99.686838) (xy 43.106357 -99.755222) (xy 43.042006 -99.818165)
			(xy 42.972344 -99.875175) (xy 42.897916 -99.925804) (xy 42.819304 -99.969658) (xy 42.737125 -100.006392)
			(xy 42.65202 -100.035719) (xy 42.564656 -100.05741) (xy 42.475717 -100.071295) (xy 42.3859 -100.077265)
			(xy 42.295905 -100.075274) (xy 42.20644 -100.065336) (xy 42.118202 -100.047531) (xy 42.031883 -100.021997)
			(xy 41.948159 -99.988934) (xy 41.867685 -99.948601) (xy 41.79109 -99.901313) (xy 41.718974 -99.847441)
			(xy 41.651902 -99.787406) (xy 41.590398 -99.721678) (xy 41.534943 -99.650772) (xy 41.485973 -99.575242)
			(xy 41.443869 -99.495679) (xy 41.408962 -99.412707) (xy 41.381525 -99.326974) (xy 41.361772 -99.239152)
			(xy 41.349858 -99.149928) (xy 41.345876 -99.06) (xy 23.720552 -99.06) (xy 23.720552 -111.879888)
			(xy 40.838131 -111.879888) (xy 40.842106 -111.769829) (xy 40.854014 -111.660343) (xy 40.87379 -111.552002)
			(xy 40.901333 -111.445371) (xy 40.936498 -111.341005) (xy 40.979102 -111.239448) (xy 41.028923 -111.141231)
			(xy 41.085702 -111.046864) (xy 41.149141 -110.95684) (xy 41.218912 -110.871629) (xy 41.294649 -110.791674)
			(xy 41.375958 -110.717393) (xy 41.462415 -110.649173) (xy 41.553569 -110.587368) (xy 41.648946 -110.532303)
			(xy 41.748047 -110.484263) (xy 41.850356 -110.443499) (xy 41.95534 -110.410224) (xy 42.062451 -110.384611)
			(xy 42.171131 -110.366794) (xy 42.280814 -110.356865) (xy 42.390927 -110.354877) (xy 42.500897 -110.360839)
			(xy 42.61015 -110.374721) (xy 42.718116 -110.396451) (xy 42.824233 -110.425914) (xy 42.927947 -110.462957)
			(xy 43.028718 -110.507388) (xy 43.12602 -110.558975) (xy 43.219346 -110.617447) (xy 43.308209 -110.682502)
			(xy 43.392147 -110.7538) (xy 43.470722 -110.830968) (xy 43.543523 -110.913605) (xy 43.610171 -111.001279)
			(xy 43.67032 -111.093535) (xy 43.723654 -111.18989) (xy 43.769897 -111.289842) (xy 43.808807 -111.39287)
			(xy 43.840181 -111.498438) (xy 43.863856 -111.605994) (xy 43.879708 -111.714978) (xy 43.887655 -111.824822)
			(xy 43.888152 -111.879888) (xy 60.396131 -111.879888) (xy 60.400106 -111.769829) (xy 60.412014 -111.660343)
			(xy 60.43179 -111.552002) (xy 60.459333 -111.445371) (xy 60.494498 -111.341005) (xy 60.537102 -111.239448)
			(xy 60.586923 -111.141231) (xy 60.643702 -111.046864) (xy 60.707141 -110.95684) (xy 60.776912 -110.871629)
			(xy 60.852649 -110.791674) (xy 60.933958 -110.717393) (xy 61.020415 -110.649173) (xy 61.111569 -110.587368)
			(xy 61.206946 -110.532303) (xy 61.306047 -110.484263) (xy 61.408356 -110.443499) (xy 61.51334 -110.410224)
			(xy 61.620451 -110.384611) (xy 61.729131 -110.366794) (xy 61.838814 -110.356865) (xy 61.948927 -110.354877)
			(xy 62.058897 -110.360839) (xy 62.16815 -110.374721) (xy 62.276116 -110.396451) (xy 62.382233 -110.425914)
			(xy 62.485947 -110.462957) (xy 62.586718 -110.507388) (xy 62.68402 -110.558975) (xy 62.777346 -110.617447)
			(xy 62.866209 -110.682502) (xy 62.950147 -110.7538) (xy 63.028722 -110.830968) (xy 63.101523 -110.913605)
			(xy 63.168171 -111.001279) (xy 63.22832 -111.093535) (xy 63.281654 -111.18989) (xy 63.327897 -111.289842)
			(xy 63.366807 -111.39287) (xy 63.398181 -111.498438) (xy 63.421856 -111.605994) (xy 63.437708 -111.714978)
			(xy 63.445655 -111.824822) (xy 63.446152 -111.879888) (xy 63.445655 -111.934954) (xy 63.437708 -112.044798)
			(xy 63.421856 -112.153782) (xy 63.398181 -112.261338) (xy 63.366807 -112.366906) (xy 63.327897 -112.469934)
			(xy 63.281654 -112.569886) (xy 63.22832 -112.666241) (xy 63.168171 -112.758497) (xy 63.101523 -112.846171)
			(xy 63.028722 -112.928808) (xy 62.950147 -113.005976) (xy 62.866209 -113.077274) (xy 62.777346 -113.142329)
			(xy 62.68402 -113.200801) (xy 62.586718 -113.252388) (xy 62.485947 -113.296819) (xy 62.382233 -113.333862)
			(xy 62.276116 -113.363325) (xy 62.16815 -113.385055) (xy 62.058897 -113.398937) (xy 61.948927 -113.404899)
			(xy 61.838814 -113.402911) (xy 61.729131 -113.392982) (xy 61.620451 -113.375165) (xy 61.51334 -113.349552)
			(xy 61.408356 -113.316277) (xy 61.306047 -113.275513) (xy 61.206946 -113.227473) (xy 61.111569 -113.172408)
			(xy 61.020415 -113.110603) (xy 60.933958 -113.042383) (xy 60.852649 -112.968102) (xy 60.776912 -112.888147)
			(xy 60.707141 -112.802936) (xy 60.643702 -112.712912) (xy 60.586923 -112.618545) (xy 60.537102 -112.520328)
			(xy 60.494498 -112.418771) (xy 60.459333 -112.314405) (xy 60.43179 -112.207774) (xy 60.412014 -112.099433)
			(xy 60.400106 -111.989947) (xy 60.396131 -111.879888) (xy 43.888152 -111.879888) (xy 43.887655 -111.934954)
			(xy 43.879708 -112.044798) (xy 43.863856 -112.153782) (xy 43.840181 -112.261338) (xy 43.808807 -112.366906)
			(xy 43.769897 -112.469934) (xy 43.723654 -112.569886) (xy 43.67032 -112.666241) (xy 43.610171 -112.758497)
			(xy 43.543523 -112.846171) (xy 43.470722 -112.928808) (xy 43.392147 -113.005976) (xy 43.308209 -113.077274)
			(xy 43.219346 -113.142329) (xy 43.12602 -113.200801) (xy 43.028718 -113.252388) (xy 42.927947 -113.296819)
			(xy 42.824233 -113.333862) (xy 42.718116 -113.363325) (xy 42.61015 -113.385055) (xy 42.500897 -113.398937)
			(xy 42.390927 -113.404899) (xy 42.280814 -113.402911) (xy 42.171131 -113.392982) (xy 42.062451 -113.375165)
			(xy 41.95534 -113.349552) (xy 41.850356 -113.316277) (xy 41.748047 -113.275513) (xy 41.648946 -113.227473)
			(xy 41.553569 -113.172408) (xy 41.462415 -113.110603) (xy 41.375958 -113.042383) (xy 41.294649 -112.968102)
			(xy 41.218912 -112.888147) (xy 41.149141 -112.802936) (xy 41.085702 -112.712912) (xy 41.028923 -112.618545)
			(xy 40.979102 -112.520328) (xy 40.936498 -112.418771) (xy 40.901333 -112.314405) (xy 40.87379 -112.207774)
			(xy 40.854014 -112.099433) (xy 40.842106 -111.989947) (xy 40.838131 -111.879888) (xy 23.720552 -111.879888)
			(xy 23.720552 -119.38) (xy 41.345876 -119.38) (xy 41.349858 -119.290072) (xy 41.361772 -119.200848)
			(xy 41.381525 -119.113026) (xy 41.408962 -119.027293) (xy 41.443869 -118.944321) (xy 41.485973 -118.864758)
			(xy 41.534943 -118.789228) (xy 41.590398 -118.718322) (xy 41.651902 -118.652594) (xy 41.718974 -118.592559)
			(xy 41.79109 -118.538687) (xy 41.867685 -118.491399) (xy 41.948159 -118.451066) (xy 42.031883 -118.418003)
			(xy 42.118202 -118.392469) (xy 42.20644 -118.374664) (xy 42.295905 -118.364726) (xy 42.3859 -118.362735)
			(xy 42.475717 -118.368705) (xy 42.564656 -118.38259) (xy 42.65202 -118.404281) (xy 42.737125 -118.433608)
			(xy 42.819304 -118.470342) (xy 42.897916 -118.514196) (xy 42.972344 -118.564825) (xy 43.042006 -118.621835)
			(xy 43.106357 -118.684778) (xy 43.164894 -118.753162) (xy 43.217157 -118.826452) (xy 43.262739 -118.904074)
			(xy 43.301282 -118.985421) (xy 43.332485 -119.069856) (xy 43.356103 -119.156718) (xy 43.371952 -119.245328)
			(xy 43.379908 -119.334992) (xy 43.380406 -119.38) (xy 60.903876 -119.38) (xy 60.907858 -119.290072)
			(xy 60.919772 -119.200848) (xy 60.939525 -119.113026) (xy 60.966962 -119.027293) (xy 61.001869 -118.944321)
			(xy 61.043973 -118.864758) (xy 61.092943 -118.789228) (xy 61.148398 -118.718322) (xy 61.209902 -118.652594)
			(xy 61.276974 -118.592559) (xy 61.34909 -118.538687) (xy 61.425685 -118.491399) (xy 61.506159 -118.451066)
			(xy 61.589883 -118.418003) (xy 61.676202 -118.392469) (xy 61.76444 -118.374664) (xy 61.853905 -118.364726)
			(xy 61.9439 -118.362735) (xy 62.033717 -118.368705) (xy 62.122656 -118.38259) (xy 62.21002 -118.404281)
			(xy 62.295125 -118.433608) (xy 62.377304 -118.470342) (xy 62.455916 -118.514196) (xy 62.530344 -118.564825)
			(xy 62.600006 -118.621835) (xy 62.664357 -118.684778) (xy 62.722894 -118.753162) (xy 62.775157 -118.826452)
			(xy 62.820739 -118.904074) (xy 62.859282 -118.985421) (xy 62.890485 -119.069856) (xy 62.914103 -119.156718)
			(xy 62.929952 -119.245328) (xy 62.937908 -119.334992) (xy 62.938406 -119.38) (xy 62.937908 -119.425008)
			(xy 62.929952 -119.514672) (xy 62.914103 -119.603282) (xy 62.890485 -119.690144) (xy 62.859282 -119.774579)
			(xy 62.820739 -119.855926) (xy 62.775157 -119.933548) (xy 62.722894 -120.006838) (xy 62.664357 -120.075222)
			(xy 62.600006 -120.138165) (xy 62.530344 -120.195175) (xy 62.455916 -120.245804) (xy 62.377304 -120.289658)
			(xy 62.295125 -120.326392) (xy 62.21002 -120.355719) (xy 62.122656 -120.37741) (xy 62.033717 -120.391295)
			(xy 61.9439 -120.397265) (xy 61.853905 -120.395274) (xy 61.76444 -120.385336) (xy 61.676202 -120.367531)
			(xy 61.589883 -120.341997) (xy 61.506159 -120.308934) (xy 61.425685 -120.268601) (xy 61.34909 -120.221313)
			(xy 61.276974 -120.167441) (xy 61.209902 -120.107406) (xy 61.148398 -120.041678) (xy 61.092943 -119.970772)
			(xy 61.043973 -119.895242) (xy 61.001869 -119.815679) (xy 60.966962 -119.732707) (xy 60.939525 -119.646974)
			(xy 60.919772 -119.559152) (xy 60.907858 -119.469928) (xy 60.903876 -119.38) (xy 43.380406 -119.38)
			(xy 43.379908 -119.425008) (xy 43.371952 -119.514672) (xy 43.356103 -119.603282) (xy 43.332485 -119.690144)
			(xy 43.301282 -119.774579) (xy 43.262739 -119.855926) (xy 43.217157 -119.933548) (xy 43.164894 -120.006838)
			(xy 43.106357 -120.075222) (xy 43.042006 -120.138165) (xy 42.972344 -120.195175) (xy 42.897916 -120.245804)
			(xy 42.819304 -120.289658) (xy 42.737125 -120.326392) (xy 42.65202 -120.355719) (xy 42.564656 -120.37741)
			(xy 42.475717 -120.391295) (xy 42.3859 -120.397265) (xy 42.295905 -120.395274) (xy 42.20644 -120.385336)
			(xy 42.118202 -120.367531) (xy 42.031883 -120.341997) (xy 41.948159 -120.308934) (xy 41.867685 -120.268601)
			(xy 41.79109 -120.221313) (xy 41.718974 -120.167441) (xy 41.651902 -120.107406) (xy 41.590398 -120.041678)
			(xy 41.534943 -119.970772) (xy 41.485973 -119.895242) (xy 41.443869 -119.815679) (xy 41.408962 -119.732707)
			(xy 41.381525 -119.646974) (xy 41.361772 -119.559152) (xy 41.349858 -119.469928) (xy 41.345876 -119.38)
			(xy 23.720552 -119.38) (xy 23.720552 -132.199888) (xy 40.838131 -132.199888) (xy 40.842106 -132.089829)
			(xy 40.854014 -131.980343) (xy 40.87379 -131.872002) (xy 40.901333 -131.765371) (xy 40.936498 -131.661005)
			(xy 40.979102 -131.559448) (xy 41.028923 -131.461231) (xy 41.085702 -131.366864) (xy 41.149141 -131.27684)
			(xy 41.218912 -131.191629) (xy 41.294649 -131.111674) (xy 41.375958 -131.037393) (xy 41.462415 -130.969173)
			(xy 41.553569 -130.907368) (xy 41.648946 -130.852303) (xy 41.748047 -130.804263) (xy 41.850356 -130.763499)
			(xy 41.95534 -130.730224) (xy 42.062451 -130.704611) (xy 42.171131 -130.686794) (xy 42.280814 -130.676865)
			(xy 42.390927 -130.674877) (xy 42.500897 -130.680839) (xy 42.61015 -130.694721) (xy 42.718116 -130.716451)
			(xy 42.824233 -130.745914) (xy 42.927947 -130.782957) (xy 43.028718 -130.827388) (xy 43.12602 -130.878975)
			(xy 43.219346 -130.937447) (xy 43.308209 -131.002502) (xy 43.392147 -131.0738) (xy 43.470722 -131.150968)
			(xy 43.543523 -131.233605) (xy 43.610171 -131.321279) (xy 43.67032 -131.413535) (xy 43.723654 -131.50989)
			(xy 43.769897 -131.609842) (xy 43.808807 -131.71287) (xy 43.840181 -131.818438) (xy 43.863856 -131.925994)
			(xy 43.879708 -132.034978) (xy 43.887655 -132.144822) (xy 43.888152 -132.199888) (xy 60.396131 -132.199888)
			(xy 60.400106 -132.089829) (xy 60.412014 -131.980343) (xy 60.43179 -131.872002) (xy 60.459333 -131.765371)
			(xy 60.494498 -131.661005) (xy 60.537102 -131.559448) (xy 60.586923 -131.461231) (xy 60.643702 -131.366864)
			(xy 60.707141 -131.27684) (xy 60.776912 -131.191629) (xy 60.852649 -131.111674) (xy 60.933958 -131.037393)
			(xy 61.020415 -130.969173) (xy 61.111569 -130.907368) (xy 61.206946 -130.852303) (xy 61.306047 -130.804263)
			(xy 61.408356 -130.763499) (xy 61.51334 -130.730224) (xy 61.620451 -130.704611) (xy 61.729131 -130.686794)
			(xy 61.838814 -130.676865) (xy 61.948927 -130.674877) (xy 62.058897 -130.680839) (xy 62.16815 -130.694721)
			(xy 62.276116 -130.716451) (xy 62.382233 -130.745914) (xy 62.485947 -130.782957) (xy 62.586718 -130.827388)
			(xy 62.68402 -130.878975) (xy 62.777346 -130.937447) (xy 62.866209 -131.002502) (xy 62.950147 -131.0738)
			(xy 63.028722 -131.150968) (xy 63.101523 -131.233605) (xy 63.168171 -131.321279) (xy 63.22832 -131.413535)
			(xy 63.281654 -131.50989) (xy 63.327897 -131.609842) (xy 63.366807 -131.71287) (xy 63.398181 -131.818438)
			(xy 63.421856 -131.925994) (xy 63.437708 -132.034978) (xy 63.445655 -132.144822) (xy 63.446152 -132.199888)
			(xy 63.445655 -132.254954) (xy 63.437708 -132.364798) (xy 63.421856 -132.473782) (xy 63.398181 -132.581338)
			(xy 63.366807 -132.686906) (xy 63.327897 -132.789934) (xy 63.281654 -132.889886) (xy 63.22832 -132.986241)
			(xy 63.168171 -133.078497) (xy 63.101523 -133.166171) (xy 63.028722 -133.248808) (xy 62.950147 -133.325976)
			(xy 62.866209 -133.397274) (xy 62.777346 -133.462329) (xy 62.68402 -133.520801) (xy 62.586718 -133.572388)
			(xy 62.485947 -133.616819) (xy 62.382233 -133.653862) (xy 62.276116 -133.683325) (xy 62.16815 -133.705055)
			(xy 62.058897 -133.718937) (xy 61.948927 -133.724899) (xy 61.838814 -133.722911) (xy 61.729131 -133.712982)
			(xy 61.620451 -133.695165) (xy 61.51334 -133.669552) (xy 61.408356 -133.636277) (xy 61.306047 -133.595513)
			(xy 61.206946 -133.547473) (xy 61.111569 -133.492408) (xy 61.020415 -133.430603) (xy 60.933958 -133.362383)
			(xy 60.852649 -133.288102) (xy 60.776912 -133.208147) (xy 60.707141 -133.122936) (xy 60.643702 -133.032912)
			(xy 60.586923 -132.938545) (xy 60.537102 -132.840328) (xy 60.494498 -132.738771) (xy 60.459333 -132.634405)
			(xy 60.43179 -132.527774) (xy 60.412014 -132.419433) (xy 60.400106 -132.309947) (xy 60.396131 -132.199888)
			(xy 43.888152 -132.199888) (xy 43.887655 -132.254954) (xy 43.879708 -132.364798) (xy 43.863856 -132.473782)
			(xy 43.840181 -132.581338) (xy 43.808807 -132.686906) (xy 43.769897 -132.789934) (xy 43.723654 -132.889886)
			(xy 43.67032 -132.986241) (xy 43.610171 -133.078497) (xy 43.543523 -133.166171) (xy 43.470722 -133.248808)
			(xy 43.392147 -133.325976) (xy 43.308209 -133.397274) (xy 43.219346 -133.462329) (xy 43.12602 -133.520801)
			(xy 43.028718 -133.572388) (xy 42.927947 -133.616819) (xy 42.824233 -133.653862) (xy 42.718116 -133.683325)
			(xy 42.61015 -133.705055) (xy 42.500897 -133.718937) (xy 42.390927 -133.724899) (xy 42.280814 -133.722911)
			(xy 42.171131 -133.712982) (xy 42.062451 -133.695165) (xy 41.95534 -133.669552) (xy 41.850356 -133.636277)
			(xy 41.748047 -133.595513) (xy 41.648946 -133.547473) (xy 41.553569 -133.492408) (xy 41.462415 -133.430603)
			(xy 41.375958 -133.362383) (xy 41.294649 -133.288102) (xy 41.218912 -133.208147) (xy 41.149141 -133.122936)
			(xy 41.085702 -133.032912) (xy 41.028923 -132.938545) (xy 40.979102 -132.840328) (xy 40.936498 -132.738771)
			(xy 40.901333 -132.634405) (xy 40.87379 -132.527774) (xy 40.854014 -132.419433) (xy 40.842106 -132.309947)
			(xy 40.838131 -132.199888) (xy 23.720552 -132.199888) (xy 23.720552 -139.7) (xy 41.345876 -139.7)
			(xy 41.349858 -139.610072) (xy 41.361772 -139.520848) (xy 41.381525 -139.433026) (xy 41.408962 -139.347293)
			(xy 41.443869 -139.264321) (xy 41.485973 -139.184758) (xy 41.534943 -139.109228) (xy 41.590398 -139.038322)
			(xy 41.651902 -138.972594) (xy 41.718974 -138.912559) (xy 41.79109 -138.858687) (xy 41.867685 -138.811399)
			(xy 41.948159 -138.771066) (xy 42.031883 -138.738003) (xy 42.118202 -138.712469) (xy 42.20644 -138.694664)
			(xy 42.295905 -138.684726) (xy 42.3859 -138.682735) (xy 42.475717 -138.688705) (xy 42.564656 -138.70259)
			(xy 42.65202 -138.724281) (xy 42.737125 -138.753608) (xy 42.819304 -138.790342) (xy 42.897916 -138.834196)
			(xy 42.972344 -138.884825) (xy 43.042006 -138.941835) (xy 43.106357 -139.004778) (xy 43.164894 -139.073162)
			(xy 43.217157 -139.146452) (xy 43.262739 -139.224074) (xy 43.301282 -139.305421) (xy 43.332485 -139.389856)
			(xy 43.356103 -139.476718) (xy 43.371952 -139.565328) (xy 43.379908 -139.654992) (xy 43.380406 -139.7)
			(xy 60.903876 -139.7) (xy 60.907858 -139.610072) (xy 60.919772 -139.520848) (xy 60.939525 -139.433026)
			(xy 60.966962 -139.347293) (xy 61.001869 -139.264321) (xy 61.043973 -139.184758) (xy 61.092943 -139.109228)
			(xy 61.148398 -139.038322) (xy 61.209902 -138.972594) (xy 61.276974 -138.912559) (xy 61.34909 -138.858687)
			(xy 61.425685 -138.811399) (xy 61.506159 -138.771066) (xy 61.589883 -138.738003) (xy 61.676202 -138.712469)
			(xy 61.76444 -138.694664) (xy 61.853905 -138.684726) (xy 61.9439 -138.682735) (xy 62.033717 -138.688705)
			(xy 62.122656 -138.70259) (xy 62.21002 -138.724281) (xy 62.295125 -138.753608) (xy 62.377304 -138.790342)
			(xy 62.455916 -138.834196) (xy 62.530344 -138.884825) (xy 62.600006 -138.941835) (xy 62.664357 -139.004778)
			(xy 62.722894 -139.073162) (xy 62.775157 -139.146452) (xy 62.820739 -139.224074) (xy 62.859282 -139.305421)
			(xy 62.890485 -139.389856) (xy 62.914103 -139.476718) (xy 62.929952 -139.565328) (xy 62.937908 -139.654992)
			(xy 62.938406 -139.7) (xy 62.937908 -139.745008) (xy 62.929952 -139.834672) (xy 62.914103 -139.923282)
			(xy 62.890485 -140.010144) (xy 62.859282 -140.094579) (xy 62.820739 -140.175926) (xy 62.775157 -140.253548)
			(xy 62.722894 -140.326838) (xy 62.664357 -140.395222) (xy 62.600006 -140.458165) (xy 62.530344 -140.515175)
			(xy 62.455916 -140.565804) (xy 62.377304 -140.609658) (xy 62.295125 -140.646392) (xy 62.21002 -140.675719)
			(xy 62.122656 -140.69741) (xy 62.033717 -140.711295) (xy 61.9439 -140.717265) (xy 61.853905 -140.715274)
			(xy 61.76444 -140.705336) (xy 61.676202 -140.687531) (xy 61.589883 -140.661997) (xy 61.506159 -140.628934)
			(xy 61.425685 -140.588601) (xy 61.34909 -140.541313) (xy 61.276974 -140.487441) (xy 61.209902 -140.427406)
			(xy 61.148398 -140.361678) (xy 61.092943 -140.290772) (xy 61.043973 -140.215242) (xy 61.001869 -140.135679)
			(xy 60.966962 -140.052707) (xy 60.939525 -139.966974) (xy 60.919772 -139.879152) (xy 60.907858 -139.789928)
			(xy 60.903876 -139.7) (xy 43.380406 -139.7) (xy 43.379908 -139.745008) (xy 43.371952 -139.834672)
			(xy 43.356103 -139.923282) (xy 43.332485 -140.010144) (xy 43.301282 -140.094579) (xy 43.262739 -140.175926)
			(xy 43.217157 -140.253548) (xy 43.164894 -140.326838) (xy 43.106357 -140.395222) (xy 43.042006 -140.458165)
			(xy 42.972344 -140.515175) (xy 42.897916 -140.565804) (xy 42.819304 -140.609658) (xy 42.737125 -140.646392)
			(xy 42.65202 -140.675719) (xy 42.564656 -140.69741) (xy 42.475717 -140.711295) (xy 42.3859 -140.717265)
			(xy 42.295905 -140.715274) (xy 42.20644 -140.705336) (xy 42.118202 -140.687531) (xy 42.031883 -140.661997)
			(xy 41.948159 -140.628934) (xy 41.867685 -140.588601) (xy 41.79109 -140.541313) (xy 41.718974 -140.487441)
			(xy 41.651902 -140.427406) (xy 41.590398 -140.361678) (xy 41.534943 -140.290772) (xy 41.485973 -140.215242)
			(xy 41.443869 -140.135679) (xy 41.408962 -140.052707) (xy 41.381525 -139.966974) (xy 41.361772 -139.879152)
			(xy 41.349858 -139.789928) (xy 41.345876 -139.7) (xy 23.720552 -139.7) (xy 23.720552 -147.500086)
			(xy 74.864468 -147.500086) (xy 74.864468 -142.500096) (xy 74.864963 -142.399255) (xy 74.872881 -142.197728)
			(xy 74.888705 -141.996668) (xy 74.91241 -141.796384) (xy 74.94396 -141.597185) (xy 74.983306 -141.399378)
			(xy 75.030388 -141.203269) (xy 75.085133 -141.009159) (xy 75.147456 -140.817348) (xy 75.217261 -140.628131)
			(xy 75.294442 -140.441802) (xy 75.378878 -140.258645) (xy 75.47044 -140.078945) (xy 75.568986 -139.902979)
			(xy 75.674364 -139.731016) (xy 75.786413 -139.563324) (xy 75.904959 -139.40016) (xy 76.029819 -139.241775)
			(xy 76.160801 -139.088415) (xy 76.297703 -138.940315) (xy 76.440313 -138.797705) (xy 76.588413 -138.660803)
			(xy 76.741773 -138.529821) (xy 76.900158 -138.404961) (xy 77.063322 -138.286415) (xy 77.231014 -138.174366)
			(xy 77.402977 -138.068988) (xy 77.578943 -137.970442) (xy 77.758643 -137.87888) (xy 77.9418 -137.794444)
			(xy 78.128129 -137.717263) (xy 78.317346 -137.647458) (xy 78.509157 -137.585135) (xy 78.703267 -137.53039)
			(xy 78.899376 -137.483308) (xy 79.097183 -137.443962) (xy 79.296382 -137.412412) (xy 79.496666 -137.388707)
			(xy 79.697726 -137.372883) (xy 79.899253 -137.364965) (xy 80.100935 -137.364965) (xy 80.302462 -137.372883)
			(xy 80.503522 -137.388707) (xy 80.703806 -137.412412) (xy 80.903005 -137.443962) (xy 81.100812 -137.483308)
			(xy 81.296921 -137.53039) (xy 81.491031 -137.585135) (xy 81.682842 -137.647458) (xy 81.872059 -137.717263)
			(xy 82.058388 -137.794444) (xy 82.241545 -137.87888) (xy 82.421245 -137.970442) (xy 82.597211 -138.068988)
			(xy 82.769174 -138.174366) (xy 82.936866 -138.286415) (xy 83.10003 -138.404961) (xy 83.258415 -138.529821)
			(xy 83.411775 -138.660803) (xy 83.559875 -138.797705) (xy 83.702485 -138.940315) (xy 83.839387 -139.088415)
			(xy 83.970369 -139.241775) (xy 84.095229 -139.40016) (xy 84.213775 -139.563324) (xy 84.325824 -139.731016)
			(xy 84.431202 -139.902979) (xy 84.529748 -140.078945) (xy 84.62131 -140.258645) (xy 84.705746 -140.441802)
			(xy 84.782927 -140.628131) (xy 84.852732 -140.817348) (xy 84.915055 -141.009159) (xy 84.9698 -141.203269)
			(xy 85.016882 -141.399378) (xy 85.056228 -141.597185) (xy 85.087778 -141.796384) (xy 85.111483 -141.996668)
			(xy 85.127307 -142.197728) (xy 85.135225 -142.399255) (xy 85.13572 -142.500096) (xy 85.13572 -147.500086)
			(xy 85.135225 -147.600927) (xy 85.127307 -147.802454) (xy 85.111483 -148.003514) (xy 85.087778 -148.203798)
			(xy 85.056228 -148.402997) (xy 85.016882 -148.600804) (xy 84.9698 -148.796913) (xy 84.915055 -148.991023)
			(xy 84.852732 -149.182834) (xy 84.782927 -149.372051) (xy 84.705746 -149.55838) (xy 84.62131 -149.741537)
			(xy 84.529748 -149.921237) (xy 84.431202 -150.097203) (xy 84.325824 -150.269166) (xy 84.213775 -150.436858)
			(xy 84.095229 -150.600022) (xy 83.970369 -150.758407) (xy 83.839387 -150.911767) (xy 83.702485 -151.059867)
			(xy 83.559875 -151.202477) (xy 83.411775 -151.339379) (xy 83.258415 -151.470361) (xy 83.10003 -151.595221)
			(xy 82.936866 -151.713767) (xy 82.769174 -151.825816) (xy 82.597211 -151.931194) (xy 82.421245 -152.02974)
			(xy 82.241545 -152.121302) (xy 82.058388 -152.205738) (xy 81.872059 -152.282919) (xy 81.682842 -152.352724)
			(xy 81.491031 -152.415047) (xy 81.296921 -152.469792) (xy 81.100812 -152.516874) (xy 80.903005 -152.55622)
			(xy 80.703806 -152.58777) (xy 80.503522 -152.611475) (xy 80.302462 -152.627299) (xy 80.100935 -152.635217)
			(xy 79.899253 -152.635217) (xy 79.697726 -152.627299) (xy 79.496666 -152.611475) (xy 79.296382 -152.58777)
			(xy 79.097183 -152.55622) (xy 78.899376 -152.516874) (xy 78.703267 -152.469792) (xy 78.509157 -152.415047)
			(xy 78.317346 -152.352724) (xy 78.128129 -152.282919) (xy 77.9418 -152.205738) (xy 77.758643 -152.121302)
			(xy 77.578943 -152.02974) (xy 77.402977 -151.931194) (xy 77.231014 -151.825816) (xy 77.063322 -151.713767)
			(xy 76.900158 -151.595221) (xy 76.741773 -151.470361) (xy 76.588413 -151.339379) (xy 76.440313 -151.202477)
			(xy 76.297703 -151.059867) (xy 76.160801 -150.911767) (xy 76.029819 -150.758407) (xy 75.904959 -150.600022)
			(xy 75.786413 -150.436858) (xy 75.674364 -150.269166) (xy 75.568986 -150.097203) (xy 75.47044 -149.921237)
			(xy 75.378878 -149.741537) (xy 75.294442 -149.55838) (xy 75.217261 -149.372051) (xy 75.147456 -149.182834)
			(xy 75.085133 -148.991023) (xy 75.030388 -148.796913) (xy 74.983306 -148.600804) (xy 74.94396 -148.402997)
			(xy 74.91241 -148.203798) (xy 74.888705 -148.003514) (xy 74.872881 -147.802454) (xy 74.864963 -147.600927)
			(xy 74.864468 -147.500086) (xy 23.720552 -147.500086) (xy 23.720552 -156.57703) (xy 23.720982 -156.587097)
			(xy 23.72871 -156.605688) (xy 23.735538 -156.613098) (xy 23.839424 -156.716984) (xy 23.870158 -156.722572)
			(xy 23.884636 -156.716222) (xy 23.927326 -156.697947) (xy 24.015676 -156.669341) (xy 24.106524 -156.650085)
			(xy 24.198883 -156.64039) (xy 24.245316 -156.639768) (xy 24.24557 -156.639768) (xy 24.288357 -156.64028)
			(xy 24.373534 -156.648504) (xy 24.457528 -156.664868) (xy 24.539562 -156.689223) (xy 24.618879 -156.721341)
			(xy 24.694745 -156.760928) (xy 24.76646 -156.807616) (xy 24.833359 -156.860975) (xy 24.894827 -156.920511)
			(xy 24.950293 -156.985675) (xy 24.999246 -157.055863) (xy 25.041233 -157.130427) (xy 25.075866 -157.208679)
			(xy 25.089866 -157.249114) (xy 25.094946 -157.264608) (xy 25.121616 -157.283912) (xy 26.000456 -157.283912)
			(xy 26.109441 -157.284408) (xy 26.327267 -157.292313) (xy 26.544663 -157.308104) (xy 26.761345 -157.33176)
			(xy 26.977028 -157.363249) (xy 27.191428 -157.402531) (xy 27.404265 -157.449554) (xy 27.615259 -157.504256)
			(xy 27.824132 -157.566566) (xy 28.030612 -157.636401) (xy 28.234426 -157.713669) (xy 28.435307 -157.798271)
			(xy 28.53436 -157.843728) (xy 28.55595 -157.848554) (xy 28.589986 -157.835346) (xy 28.62069 -157.807856)
			(xy 28.686361 -157.758054) (xy 28.75636 -157.714545) (xy 28.830086 -157.677702) (xy 28.906906 -157.647841)
			(xy 28.986159 -157.625219) (xy 29.067167 -157.61003) (xy 29.149232 -157.602405) (xy 29.190442 -157.60192)
			(xy 29.231543 -157.602397) (xy 29.313393 -157.609985) (xy 29.394195 -157.625093) (xy 29.473257 -157.647592)
			(xy 29.549907 -157.67729) (xy 29.623489 -157.713934) (xy 29.693376 -157.75721) (xy 29.758972 -157.80675)
			(xy 29.819718 -157.862132) (xy 29.875094 -157.922881) (xy 29.924629 -157.988482) (xy 29.9679 -158.058372)
			(xy 30.004538 -158.131958) (xy 30.03423 -158.208609) (xy 30.056723 -158.287674) (xy 30.071825 -158.368476)
			(xy 30.079407 -158.450327) (xy 30.07995 -158.491428) (xy 30.07954 -158.529447) (xy 30.07303 -158.605205)
			(xy 30.060077 -158.680131) (xy 30.040775 -158.753678) (xy 30.028388 -158.789624) (xy 30.02534 -158.806642)
			(xy 30.042104 -158.844234) (xy 30.124801 -158.919959) (xy 30.285164 -159.076725) (xy 30.439573 -159.239358)
			(xy 30.587815 -159.407631) (xy 30.729684 -159.581311) (xy 30.864983 -159.760157) (xy 30.993524 -159.94392)
			(xy 31.115128 -160.132345) (xy 31.229627 -160.325171) (xy 31.336861 -160.522129) (xy 31.436681 -160.722946)
			(xy 31.52895 -160.927343) (xy 31.613538 -161.135036) (xy 31.690328 -161.345737) (xy 31.759214 -161.559153)
			(xy 31.790132 -161.666936) (xy 31.832804 -161.703766) (xy 31.875396 -161.709498) (xy 31.959303 -161.728113)
			(xy 32.041022 -161.754735) (xy 32.119793 -161.789114) (xy 32.194881 -161.830931) (xy 32.265585 -161.879796)
			(xy 32.331247 -161.935252) (xy 32.391253 -161.996782) (xy 32.445045 -162.063814) (xy 32.492121 -162.135722)
			(xy 32.532041 -162.211834) (xy 32.564434 -162.291443) (xy 32.588998 -162.373804) (xy 32.605503 -162.458151)
			(xy 32.613796 -162.543697) (xy 32.614362 -162.58667) (xy 32.613888 -162.627686) (xy 32.606328 -162.709368)
			(xy 32.591279 -162.790007) (xy 32.568869 -162.868918) (xy 32.539289 -162.94543) (xy 32.502788 -163.018894)
			(xy 32.459679 -163.088684) (xy 32.410326 -163.154208) (xy 32.355149 -163.21491) (xy 32.294618 -163.270273)
			(xy 32.229246 -163.319828) (xy 32.159589 -163.363152) (xy 32.086238 -163.399879) (xy 32.048196 -163.415218)
			(xy 32.038888 -163.419353) (xy 32.024309 -163.43355) (xy 32.016372 -163.452288) (xy 32.015938 -163.462462)
			(xy 32.015938 -166.649908) (xy 32.01644 -166.739312) (xy 32.024462 -166.917941) (xy 32.04049 -167.09603)
			(xy 32.064492 -167.27322) (xy 32.096419 -167.449155) (xy 32.136208 -167.623481) (xy 32.183778 -167.795846)
			(xy 32.239032 -167.965903) (xy 32.301861 -168.13331) (xy 32.372137 -168.297729) (xy 32.449719 -168.45883)
			(xy 32.534451 -168.616289) (xy 32.626162 -168.769787) (xy 32.724667 -168.919016) (xy 32.829768 -169.063675)
			(xy 32.941253 -169.203473) (xy 33.058898 -169.338129) (xy 33.182466 -169.467371) (xy 33.311708 -169.590939)
			(xy 33.446364 -169.708584) (xy 33.586162 -169.82007) (xy 33.730821 -169.925171) (xy 33.88005 -170.023676)
			(xy 34.033548 -170.115387) (xy 34.191006 -170.200119) (xy 34.352107 -170.277701) (xy 34.516526 -170.347977)
			(xy 34.683933 -170.410806) (xy 34.85399 -170.466061) (xy 35.026355 -170.513631) (xy 35.200681 -170.55342)
			(xy 35.376616 -170.585347) (xy 35.553806 -170.60935) (xy 35.731895 -170.625378) (xy 35.910524 -170.6334)
			(xy 35.999928 -170.633898)
		)
		(stroke
			(width 0)
			(type solid)
		)
		(fill yes)
		(layer "In4.Cu")
		(net "P52V_HS2")
	)
	(gr_poly
		(pts
			(xy 366.350296 -170.633898) (xy 366.36087 -170.633377) (xy 366.380219 -170.624851) (xy 366.394455 -170.609216)
			(xy 366.398302 -170.599354) (xy 366.412463 -170.559233) (xy 366.44741 -170.481655) (xy 366.489605 -170.407767)
			(xy 366.538663 -170.338246) (xy 366.594134 -170.273727) (xy 366.655512 -170.214799) (xy 366.722237 -170.162001)
			(xy 366.793698 -170.115816) (xy 366.869242 -170.076664) (xy 366.94818 -170.044905) (xy 367.029789 -170.020828)
			(xy 367.113324 -170.004654) (xy 367.198023 -169.996529) (xy 367.283109 -169.996529) (xy 367.367808 -170.004654)
			(xy 367.451343 -170.020828) (xy 367.532952 -170.044905) (xy 367.61189 -170.076664) (xy 367.687434 -170.115816)
			(xy 367.758895 -170.162001) (xy 367.82562 -170.214799) (xy 367.886998 -170.273727) (xy 367.942469 -170.338246)
			(xy 367.991527 -170.407767) (xy 368.033722 -170.481655) (xy 368.068669 -170.559233) (xy 368.08283 -170.599354)
			(xy 368.086731 -170.609178) (xy 368.100982 -170.624757) (xy 368.120282 -170.633319) (xy 368.130836 -170.633898)
			(xy 371.430296 -170.633898) (xy 371.44087 -170.633377) (xy 371.460219 -170.624851) (xy 371.474455 -170.609216)
			(xy 371.478302 -170.599354) (xy 371.492463 -170.559233) (xy 371.52741 -170.481655) (xy 371.569605 -170.407767)
			(xy 371.618663 -170.338246) (xy 371.674134 -170.273727) (xy 371.735512 -170.214799) (xy 371.802237 -170.162001)
			(xy 371.873698 -170.115816) (xy 371.949242 -170.076664) (xy 372.02818 -170.044905) (xy 372.109789 -170.020828)
			(xy 372.193324 -170.004654) (xy 372.278023 -169.996529) (xy 372.363109 -169.996529) (xy 372.447808 -170.004654)
			(xy 372.531343 -170.020828) (xy 372.612952 -170.044905) (xy 372.69189 -170.076664) (xy 372.767434 -170.115816)
			(xy 372.838895 -170.162001) (xy 372.90562 -170.214799) (xy 372.966998 -170.273727) (xy 373.022469 -170.338246)
			(xy 373.071527 -170.407767) (xy 373.113722 -170.481655) (xy 373.148669 -170.559233) (xy 373.16283 -170.599354)
			(xy 373.166731 -170.609178) (xy 373.180982 -170.624757) (xy 373.200282 -170.633319) (xy 373.210836 -170.633898)
			(xy 376.510296 -170.633898) (xy 376.52087 -170.633377) (xy 376.540219 -170.624851) (xy 376.554455 -170.609216)
			(xy 376.558302 -170.599354) (xy 376.571819 -170.561041) (xy 376.6049 -170.48683) (xy 376.644608 -170.415944)
			(xy 376.690613 -170.348972) (xy 376.74253 -170.286472) (xy 376.799928 -170.228965) (xy 376.830844 -170.202606)
			(xy 376.831098 -170.202352) (xy 376.838158 -170.19585) (xy 376.847261 -170.178968) (xy 376.849583 -170.15993)
			(xy 376.847608 -170.150536) (xy 376.823986 -170.061382) (xy 376.821121 -170.052203) (xy 376.809728 -170.036729)
			(xy 376.793472 -170.026483) (xy 376.784108 -170.024298) (xy 376.783854 -170.024298) (xy 376.732833 -170.014507)
			(xy 376.632552 -169.987334) (xy 376.53496 -169.951688) (xy 376.440773 -169.907831) (xy 376.350679 -169.856084)
			(xy 376.265338 -169.796824) (xy 376.185375 -169.730487) (xy 376.111375 -169.657557) (xy 376.077226 -169.618406)
			(xy 376.069656 -169.610377) (xy 376.049639 -169.601146) (xy 376.038618 -169.600626) (xy 375.961402 -169.600626)
			(xy 375.950384 -169.601167) (xy 375.930371 -169.610388) (xy 375.922794 -169.618406) (xy 375.891484 -169.654345)
			(xy 375.824081 -169.721752) (xy 375.751597 -169.783662) (xy 375.674479 -169.839696) (xy 375.593203 -169.889506)
			(xy 375.50827 -169.932787) (xy 375.420203 -169.969271) (xy 375.329545 -169.998734) (xy 375.236855 -170.020994)
			(xy 375.142705 -170.035913) (xy 375.047675 -170.043401) (xy 375.000012 -170.043856) (xy 374.949844 -170.043339)
			(xy 374.84985 -170.035055) (xy 374.750881 -170.018544) (xy 374.653614 -169.993917) (xy 374.558712 -169.961344)
			(xy 374.466824 -169.921046) (xy 374.378576 -169.873298) (xy 374.294573 -169.818427) (xy 374.215386 -169.756808)
			(xy 374.141558 -169.688861) (xy 374.073592 -169.61505) (xy 374.011953 -169.53588) (xy 373.957061 -169.45189)
			(xy 373.909291 -169.363655) (xy 373.868969 -169.271777) (xy 373.836371 -169.176883) (xy 373.81172 -169.079622)
			(xy 373.795183 -168.980658) (xy 373.786874 -168.880666) (xy 373.7864 -168.830498) (xy 373.7864 -168.82999)
			(xy 373.786867 -168.782334) (xy 373.794343 -168.687314) (xy 373.809246 -168.593174) (xy 373.831487 -168.500493)
			(xy 373.860927 -168.40984) (xy 373.897385 -168.321776) (xy 373.940637 -168.236842) (xy 373.990416 -168.155562)
			(xy 374.046417 -168.078435) (xy 374.108293 -168.005938) (xy 374.175664 -167.938516) (xy 374.211596 -167.907208)
			(xy 374.219622 -167.899637) (xy 374.228846 -167.87962) (xy 374.229376 -167.8686) (xy 374.229376 -167.791384)
			(xy 374.228832 -167.780368) (xy 374.219606 -167.76036) (xy 374.211596 -167.752776) (xy 374.173973 -167.719952)
			(xy 374.103654 -167.649058) (xy 374.039397 -167.572628) (xy 373.981636 -167.491176) (xy 373.930762 -167.405255)
			(xy 373.887119 -167.315445) (xy 373.851001 -167.222353) (xy 373.822653 -167.126609) (xy 373.802266 -167.028859)
			(xy 373.789979 -166.929765) (xy 373.785874 -166.829996) (xy 373.78998 -166.730228) (xy 373.802267 -166.631133)
			(xy 373.822655 -166.533384) (xy 373.851003 -166.43764) (xy 373.887122 -166.344548) (xy 373.930766 -166.254738)
			(xy 373.981641 -166.168817) (xy 374.039402 -166.087366) (xy 374.10366 -166.010936) (xy 374.173979 -165.940043)
			(xy 374.211596 -165.907212) (xy 374.219622 -165.899641) (xy 374.228848 -165.879624) (xy 374.229376 -165.868604)
			(xy 374.229376 -165.791388) (xy 374.228833 -165.780372) (xy 374.219608 -165.760363) (xy 374.211596 -165.75278)
			(xy 374.175673 -165.721462) (xy 374.108299 -165.654044) (xy 374.046421 -165.58155) (xy 373.990419 -165.504425)
			(xy 373.94064 -165.423145) (xy 373.897389 -165.338212) (xy 373.860932 -165.250148) (xy 373.831496 -165.159495)
			(xy 373.80926 -165.066813) (xy 373.794363 -164.972673) (xy 373.786895 -164.877654) (xy 373.7864 -164.829998)
			(xy 373.786918 -164.77982) (xy 373.795204 -164.679806) (xy 373.81172 -164.580818) (xy 373.836353 -164.483532)
			(xy 373.868934 -164.388611) (xy 373.909241 -164.296705) (xy 373.956999 -164.208441) (xy 374.011881 -164.124421)
			(xy 374.073514 -164.045219) (xy 374.141475 -163.971377) (xy 374.215301 -163.903399) (xy 374.294488 -163.841748)
			(xy 374.378495 -163.786845) (xy 374.466748 -163.739067) (xy 374.558645 -163.698738) (xy 374.653557 -163.666134)
			(xy 374.750838 -163.641479) (xy 374.849822 -163.62494) (xy 374.949834 -163.61663) (xy 375.000012 -163.616132)
			(xy 375.047673 -163.616611) (xy 375.1427 -163.624111) (xy 375.236846 -163.639039) (xy 375.329531 -163.661303)
			(xy 375.420186 -163.690768) (xy 375.50825 -163.72725) (xy 375.593183 -163.770526) (xy 375.67446 -163.820329)
			(xy 375.751582 -163.876352) (xy 375.824072 -163.938251) (xy 375.891486 -164.005643) (xy 375.922794 -164.041582)
			(xy 375.930364 -164.049609) (xy 375.950381 -164.058835) (xy 375.961402 -164.059362) (xy 376.038618 -164.059362)
			(xy 376.049636 -164.05882) (xy 376.069654 -164.049604) (xy 376.077226 -164.041582) (xy 376.108536 -164.005643)
			(xy 376.17594 -163.938239) (xy 376.248425 -163.87633) (xy 376.325543 -163.820298) (xy 376.406819 -163.77049)
			(xy 376.491753 -163.727211) (xy 376.579819 -163.690728) (xy 376.670477 -163.661267) (xy 376.763166 -163.639009)
			(xy 376.857316 -163.624092) (xy 376.952346 -163.616606) (xy 377.000008 -163.616132) (xy 377.050174 -163.61665)
			(xy 377.150164 -163.624935) (xy 377.249129 -163.641448) (xy 377.346392 -163.666076) (xy 377.44129 -163.698652)
			(xy 377.533173 -163.738951) (xy 377.621416 -163.7867) (xy 377.705414 -163.841571) (xy 377.784595 -163.903192)
			(xy 377.858418 -163.971139) (xy 377.926378 -164.044951) (xy 377.988011 -164.124121) (xy 378.042897 -164.208111)
			(xy 378.09066 -164.296345) (xy 378.130975 -164.388222) (xy 378.163566 -164.483114) (xy 378.18821 -164.580373)
			(xy 378.20474 -164.679335) (xy 378.213041 -164.779324) (xy 378.21362 -164.82949) (xy 378.21362 -164.829998)
			(xy 378.213153 -164.877655) (xy 378.205679 -164.972674) (xy 378.190776 -165.066816) (xy 378.168537 -165.159498)
			(xy 378.139098 -165.250151) (xy 378.102641 -165.338216) (xy 378.059389 -165.423151) (xy 378.009611 -165.504433)
			(xy 377.953612 -165.581561) (xy 377.891736 -165.65406) (xy 377.824367 -165.721483) (xy 377.788424 -165.75278)
			(xy 377.780394 -165.760349) (xy 377.771161 -165.780366) (xy 377.770644 -165.791388) (xy 377.770644 -165.868604)
			(xy 377.771183 -165.879624) (xy 377.780396 -165.899645) (xy 377.788424 -165.907212) (xy 377.826049 -165.940035)
			(xy 377.896374 -166.010926) (xy 377.960636 -166.087356) (xy 378.018401 -166.168806) (xy 378.06928 -166.254728)
			(xy 378.112927 -166.344538) (xy 378.149049 -166.437631) (xy 378.1774 -166.533377) (xy 378.197788 -166.631129)
			(xy 378.210077 -166.730225) (xy 378.214183 -166.829996) (xy 378.210078 -166.929767) (xy 378.19779 -167.028863)
			(xy 378.177402 -167.126615) (xy 378.149051 -167.222361) (xy 378.112931 -167.315455) (xy 378.069284 -167.405266)
			(xy 378.018406 -167.491187) (xy 377.960641 -167.572638) (xy 377.896379 -167.649068) (xy 377.826055 -167.71996)
			(xy 377.788424 -167.752776) (xy 377.780393 -167.760345) (xy 377.771159 -167.780362) (xy 377.770644 -167.791384)
			(xy 377.770644 -167.8686) (xy 377.771183 -167.87962) (xy 377.780395 -167.899642) (xy 377.788424 -167.907208)
			(xy 377.82435 -167.938525) (xy 377.891728 -168.00594) (xy 377.953611 -168.078433) (xy 378.009617 -168.155557)
			(xy 378.059401 -168.236836) (xy 378.102656 -168.321769) (xy 378.139115 -168.409834) (xy 378.168555 -168.500487)
			(xy 378.190793 -168.593171) (xy 378.205693 -168.687313) (xy 378.213162 -168.782333) (xy 378.21362 -168.82999)
			(xy 378.21362 -168.830244) (xy 378.213101 -168.881165) (xy 378.20457 -168.982649) (xy 378.187564 -169.083061)
			(xy 378.162202 -169.181694) (xy 378.128663 -169.277855) (xy 378.087182 -169.370866) (xy 378.038052 -169.460074)
			(xy 377.981618 -169.54485) (xy 377.918277 -169.624598) (xy 377.848476 -169.698757) (xy 377.772705 -169.766804)
			(xy 377.691497 -169.828262) (xy 377.648724 -169.855896) (xy 377.640765 -169.861405) (xy 377.629374 -169.877037)
			(xy 377.624579 -169.895775) (xy 377.625356 -169.905426) (xy 377.63704 -169.996612) (xy 377.671838 -170.038522)
			(xy 377.711227 -170.051644) (xy 377.787594 -170.084229) (xy 377.860594 -170.123786) (xy 377.929592 -170.169969)
			(xy 377.993989 -170.222379) (xy 378.053225 -170.280558) (xy 378.106785 -170.344001) (xy 378.154204 -170.412157)
			(xy 378.195068 -170.484433) (xy 378.229023 -170.5602) (xy 378.24283 -170.599354) (xy 378.246731 -170.609178)
			(xy 378.260982 -170.624757) (xy 378.280282 -170.633319) (xy 378.290836 -170.633898) (xy 381.590296 -170.633898)
			(xy 381.60087 -170.633377) (xy 381.620219 -170.624851) (xy 381.634455 -170.609216) (xy 381.638302 -170.599354)
			(xy 381.65185 -170.560908) (xy 381.685031 -170.486444) (xy 381.72489 -170.41533) (xy 381.77109 -170.348164)
			(xy 381.823245 -170.285508) (xy 381.880917 -170.22789) (xy 381.943621 -170.175793) (xy 382.01083 -170.129655)
			(xy 382.08198 -170.089862) (xy 382.156475 -170.05675) (xy 382.233688 -170.030595) (xy 382.31297 -170.011619)
			(xy 382.393657 -169.999979) (xy 382.434338 -169.997374) (xy 382.434592 -169.997374) (xy 382.444997 -169.996296)
			(xy 382.463682 -169.986941) (xy 382.477102 -169.970923) (xy 382.480566 -169.961052) (xy 382.507744 -169.869104)
			(xy 382.510253 -169.858893) (xy 382.50768 -169.838047) (xy 382.496945 -169.819995) (xy 382.488694 -169.813478)
			(xy 382.450238 -169.78511) (xy 382.37743 -169.723202) (xy 382.309716 -169.655761) (xy 382.247516 -169.583202)
			(xy 382.191215 -169.505977) (xy 382.141161 -169.424564) (xy 382.097666 -169.339466) (xy 382.060997 -169.251211)
			(xy 382.031382 -169.160345) (xy 382.009006 -169.067432) (xy 381.994006 -168.973047) (xy 381.986475 -168.877775)
			(xy 381.986028 -168.82999) (xy 381.986507 -168.782329) (xy 381.994006 -168.687302) (xy 382.008934 -168.593156)
			(xy 382.031199 -168.50047) (xy 382.060663 -168.409816) (xy 382.097145 -168.321751) (xy 382.140421 -168.236818)
			(xy 382.190224 -168.155541) (xy 382.246247 -168.078419) (xy 382.308145 -168.005928) (xy 382.375537 -167.938514)
			(xy 382.411478 -167.907208) (xy 382.419506 -167.899638) (xy 382.428734 -167.879621) (xy 382.429258 -167.8686)
			(xy 382.429258 -167.791384) (xy 382.428716 -167.780366) (xy 382.4195 -167.760348) (xy 382.411478 -167.752776)
			(xy 382.375539 -167.721466) (xy 382.308135 -167.654061) (xy 382.246226 -167.581577) (xy 382.190195 -167.504459)
			(xy 382.140386 -167.423183) (xy 382.097107 -167.338249) (xy 382.060625 -167.250183) (xy 382.031164 -167.159525)
			(xy 382.008905 -167.066836) (xy 381.993988 -166.972686) (xy 381.986502 -166.877656) (xy 381.986028 -166.829994)
			(xy 381.986507 -166.782333) (xy 381.994006 -166.687306) (xy 382.008933 -166.593159) (xy 382.031198 -166.500474)
			(xy 382.060662 -166.409819) (xy 382.097144 -166.321754) (xy 382.14042 -166.236821) (xy 382.190222 -166.155543)
			(xy 382.246245 -166.078421) (xy 382.308143 -166.00593) (xy 382.375535 -165.938516) (xy 382.411478 -165.907212)
			(xy 382.419507 -165.899642) (xy 382.428736 -165.879625) (xy 382.429258 -165.868604) (xy 382.429258 -165.791388)
			(xy 382.428717 -165.780369) (xy 382.419502 -165.76035) (xy 382.411478 -165.75278) (xy 382.375539 -165.72147)
			(xy 382.308135 -165.654066) (xy 382.246226 -165.581581) (xy 382.190194 -165.504463) (xy 382.140385 -165.423187)
			(xy 382.097106 -165.338254) (xy 382.060623 -165.250187) (xy 382.031162 -165.159529) (xy 382.008903 -165.06684)
			(xy 381.993985 -164.97269) (xy 381.986499 -164.87766) (xy 381.986028 -164.829998) (xy 381.986546 -164.779814)
			(xy 381.994835 -164.679787) (xy 382.011355 -164.580787) (xy 382.035994 -164.48349) (xy 382.068584 -164.388559)
			(xy 382.108902 -164.296644) (xy 382.156672 -164.208372) (xy 382.211569 -164.124346) (xy 382.273217 -164.045141)
			(xy 382.341194 -163.971297) (xy 382.415038 -163.903319) (xy 382.494243 -163.841671) (xy 382.578269 -163.786774)
			(xy 382.66654 -163.739004) (xy 382.758455 -163.698686) (xy 382.853386 -163.666096) (xy 382.950683 -163.641456)
			(xy 383.049683 -163.624935) (xy 383.14971 -163.616647) (xy 383.199894 -163.616132) (xy 383.247555 -163.61661)
			(xy 383.342583 -163.624109) (xy 383.43673 -163.639035) (xy 383.529416 -163.661299) (xy 383.620071 -163.690762)
			(xy 383.708137 -163.727244) (xy 383.79307 -163.770519) (xy 383.874349 -163.820322) (xy 383.951471 -163.876344)
			(xy 384.023963 -163.938242) (xy 384.091378 -164.005634) (xy 384.122676 -164.041582) (xy 384.130245 -164.049612)
			(xy 384.150262 -164.058845) (xy 384.161284 -164.059362) (xy 384.2385 -164.059362) (xy 384.24952 -164.058824)
			(xy 384.269543 -164.049612) (xy 384.277108 -164.041582) (xy 384.308418 -164.005643) (xy 384.375822 -163.938237)
			(xy 384.448306 -163.876327) (xy 384.525424 -163.820295) (xy 384.6067 -163.770485) (xy 384.691633 -163.727205)
			(xy 384.7797 -163.690721) (xy 384.870358 -163.661258) (xy 384.963047 -163.638999) (xy 385.057197 -163.62408)
			(xy 385.152228 -163.616593) (xy 385.19989 -163.616132) (xy 385.250075 -163.616636) (xy 385.350103 -163.624924)
			(xy 385.449105 -163.641443) (xy 385.546404 -163.666082) (xy 385.641337 -163.698672) (xy 385.733254 -163.73899)
			(xy 385.821527 -163.78676) (xy 385.905555 -163.841657) (xy 385.984762 -163.903306) (xy 386.058607 -163.971285)
			(xy 386.126586 -164.045129) (xy 386.188236 -164.124336) (xy 386.243134 -164.208362) (xy 386.290905 -164.296635)
			(xy 386.331224 -164.388552) (xy 386.363814 -164.483484) (xy 386.388454 -164.580783) (xy 386.404975 -164.679785)
			(xy 386.413264 -164.779813) (xy 386.413756 -164.829998) (xy 386.413277 -164.877659) (xy 386.405779 -164.972686)
			(xy 386.390852 -165.066833) (xy 386.368588 -165.159519) (xy 386.339124 -165.250174) (xy 386.302642 -165.338239)
			(xy 386.259366 -165.423172) (xy 386.209563 -165.50445) (xy 386.15354 -165.581572) (xy 386.091642 -165.654063)
			(xy 386.024249 -165.721477) (xy 385.988306 -165.75278) (xy 385.980278 -165.76035) (xy 385.971049 -165.780367)
			(xy 385.970526 -165.791388) (xy 385.970526 -165.868604) (xy 385.971068 -165.879621) (xy 385.980291 -165.899632)
			(xy 385.988306 -165.907212) (xy 386.024245 -165.938522) (xy 386.091651 -166.005926) (xy 386.153562 -166.07841)
			(xy 386.209594 -166.155528) (xy 386.259405 -166.236804) (xy 386.302685 -166.321737) (xy 386.339169 -166.409804)
			(xy 386.368631 -166.500461) (xy 386.390891 -166.593151) (xy 386.40581 -166.687301) (xy 386.413296 -166.782332)
			(xy 386.413756 -166.829994) (xy 386.413277 -166.877655) (xy 386.405779 -166.972683) (xy 386.390852 -167.066829)
			(xy 386.368589 -167.159516) (xy 386.339125 -167.250171) (xy 386.302643 -167.338236) (xy 386.259368 -167.423169)
			(xy 386.209565 -167.504447) (xy 386.153542 -167.581569) (xy 386.091644 -167.654061) (xy 386.024251 -167.721475)
			(xy 385.988306 -167.752776) (xy 385.980278 -167.760346) (xy 385.971047 -167.780363) (xy 385.970526 -167.791384)
			(xy 385.970526 -167.8686) (xy 385.971067 -167.879618) (xy 385.980289 -167.89963) (xy 385.988306 -167.907208)
			(xy 386.024245 -167.938518) (xy 386.091652 -168.005921) (xy 386.153562 -168.078406) (xy 386.209595 -168.155523)
			(xy 386.259406 -168.236799) (xy 386.302686 -168.321732) (xy 386.339171 -168.409799) (xy 386.368633 -168.500457)
			(xy 386.390893 -168.593147) (xy 386.405812 -168.687297) (xy 386.413299 -168.782328) (xy 386.413756 -168.82999)
			(xy 387.986016 -168.82999) (xy 387.986483 -168.782328) (xy 387.993969 -168.687298) (xy 388.008888 -168.593148)
			(xy 388.031147 -168.500459) (xy 388.060609 -168.409801) (xy 388.097093 -168.321734) (xy 388.140372 -168.236801)
			(xy 388.190181 -168.155525) (xy 388.246213 -168.078407) (xy 388.308123 -168.005923) (xy 388.375527 -167.938518)
			(xy 388.411466 -167.907208) (xy 388.419494 -167.899641) (xy 388.428707 -167.87962) (xy 388.429246 -167.8686)
			(xy 388.429246 -167.791384) (xy 388.428734 -167.780361) (xy 388.419498 -167.760344) (xy 388.411466 -167.752776)
			(xy 388.375515 -167.721482) (xy 388.308123 -167.654066) (xy 388.246226 -167.581574) (xy 388.190204 -167.504451)
			(xy 388.140402 -167.423172) (xy 388.097127 -167.338238) (xy 388.060646 -167.250172) (xy 388.031183 -167.159517)
			(xy 388.008919 -167.06683) (xy 387.993992 -166.972683) (xy 387.986494 -166.877655) (xy 387.986016 -166.829994)
			(xy 387.986485 -166.782332) (xy 387.993972 -166.687302) (xy 388.008891 -166.593152) (xy 388.031149 -166.500463)
			(xy 388.060611 -166.409805) (xy 388.097094 -166.321739) (xy 388.140373 -166.236806) (xy 388.190182 -166.155529)
			(xy 388.246214 -166.078411) (xy 388.308123 -166.005927) (xy 388.375527 -165.938522) (xy 388.411466 -165.907212)
			(xy 388.419492 -165.899643) (xy 388.428706 -165.879623) (xy 388.429246 -165.868604) (xy 388.429246 -165.791388)
			(xy 388.428732 -165.780366) (xy 388.419498 -165.760348) (xy 388.411466 -165.75278) (xy 388.375517 -165.721484)
			(xy 388.308125 -165.654068) (xy 388.246228 -165.581576) (xy 388.190205 -165.504453) (xy 388.140403 -165.423174)
			(xy 388.097128 -165.338241) (xy 388.060647 -165.250175) (xy 388.031184 -165.15952) (xy 388.00892 -165.066834)
			(xy 387.993993 -164.972687) (xy 387.986495 -164.877659) (xy 387.986016 -164.829998) (xy 387.98655 -164.779814)
			(xy 387.994839 -164.679789) (xy 388.011359 -164.58079) (xy 388.035998 -164.483493) (xy 388.068587 -164.388563)
			(xy 388.108904 -164.296649) (xy 388.156674 -164.208378) (xy 388.211569 -164.124353) (xy 388.273216 -164.045148)
			(xy 388.341193 -163.971304) (xy 388.415036 -163.903326) (xy 388.49424 -163.841679) (xy 388.578264 -163.786782)
			(xy 388.666534 -163.739011) (xy 388.758448 -163.698693) (xy 388.853378 -163.666102) (xy 388.950674 -163.641462)
			(xy 389.049673 -163.624941) (xy 389.149698 -163.616651) (xy 389.199882 -163.616132) (xy 389.247544 -163.616613)
			(xy 389.342574 -163.624098) (xy 389.436723 -163.639015) (xy 389.529413 -163.661272) (xy 389.62007 -163.690732)
			(xy 389.708137 -163.727214) (xy 389.79307 -163.770492) (xy 389.874346 -163.820301) (xy 389.951464 -163.876331)
			(xy 390.023949 -163.93824) (xy 390.091354 -164.005644) (xy 390.122664 -164.041582) (xy 390.13024 -164.0496)
			(xy 390.150255 -164.058818) (xy 390.161272 -164.059362) (xy 390.238488 -164.059362) (xy 390.249508 -164.05883)
			(xy 390.269525 -164.049608) (xy 390.277096 -164.041582) (xy 390.308409 -164.005648) (xy 390.375822 -163.938255)
			(xy 390.448313 -163.876357) (xy 390.525434 -163.820333) (xy 390.60671 -163.77053) (xy 390.691642 -163.727254)
			(xy 390.779706 -163.690771) (xy 390.87036 -163.661306) (xy 390.963045 -163.63904) (xy 391.057191 -163.624112)
			(xy 391.152217 -163.616612) (xy 391.199878 -163.616132) (xy 391.250063 -163.616659) (xy 391.350089 -163.624946)
			(xy 391.44909 -163.641465) (xy 391.546388 -163.666102) (xy 391.64132 -163.698691) (xy 391.733236 -163.739008)
			(xy 391.821508 -163.786777) (xy 391.905535 -163.841673) (xy 391.984741 -163.90332) (xy 392.058586 -163.971297)
			(xy 392.126565 -164.045141) (xy 392.188213 -164.124346) (xy 392.243111 -164.208371) (xy 392.290882 -164.296643)
			(xy 392.3312 -164.388558) (xy 392.363791 -164.483489) (xy 392.38843 -164.580787) (xy 392.404951 -164.679787)
			(xy 392.41324 -164.779813) (xy 392.413744 -164.829998) (xy 392.413283 -164.87766) (xy 392.405797 -164.972691)
			(xy 392.390878 -165.066841) (xy 392.368619 -165.159531) (xy 392.339157 -165.250189) (xy 392.302673 -165.338256)
			(xy 392.259393 -165.423189) (xy 392.209583 -165.504465) (xy 392.15355 -165.581583) (xy 392.09164 -165.654067)
			(xy 392.024233 -165.72147) (xy 391.988294 -165.75278) (xy 391.980281 -165.760361) (xy 391.971057 -165.780371)
			(xy 391.970514 -165.791388) (xy 391.970514 -165.868604) (xy 391.971045 -165.879624) (xy 391.980269 -165.89964)
			(xy 391.988294 -165.907212) (xy 392.024231 -165.938522) (xy 392.091624 -166.005935) (xy 392.153523 -166.078426)
			(xy 392.209546 -166.155547) (xy 392.25935 -166.236824) (xy 392.302626 -166.321756) (xy 392.339109 -166.40982)
			(xy 392.368573 -166.500475) (xy 392.390838 -166.59316) (xy 392.405766 -166.687306) (xy 392.413265 -166.782333)
			(xy 392.413744 -166.829994) (xy 392.41328 -166.877656) (xy 392.405794 -166.972687) (xy 392.390876 -167.066837)
			(xy 392.368617 -167.159527) (xy 392.339155 -167.250184) (xy 392.302672 -167.338251) (xy 392.259392 -167.423185)
			(xy 392.209582 -167.504461) (xy 392.153549 -167.581578) (xy 392.091639 -167.654063) (xy 392.024233 -167.721466)
			(xy 391.988294 -167.752776) (xy 391.980283 -167.760359) (xy 391.971058 -167.780368) (xy 391.970514 -167.791384)
			(xy 391.970514 -167.8686) (xy 391.971048 -167.879619) (xy 391.98027 -167.899636) (xy 391.988294 -167.907208)
			(xy 392.024229 -167.93852) (xy 392.091622 -168.005933) (xy 392.153521 -168.078423) (xy 392.209545 -168.155544)
			(xy 392.259348 -168.236821) (xy 392.302625 -168.321753) (xy 392.339108 -168.409817) (xy 392.368572 -168.500471)
			(xy 392.390837 -168.593157) (xy 392.405766 -168.687302) (xy 392.413265 -168.782329) (xy 392.413744 -168.82999)
			(xy 392.413252 -168.880175) (xy 392.404964 -168.980204) (xy 392.388444 -169.079206) (xy 392.363805 -169.176505)
			(xy 392.331215 -169.271438) (xy 392.290896 -169.363355) (xy 392.243125 -169.451628) (xy 392.188227 -169.535655)
			(xy 392.126578 -169.614862) (xy 392.058598 -169.688707) (xy 391.984753 -169.756686) (xy 391.905546 -169.818334)
			(xy 391.821518 -169.873231) (xy 391.733244 -169.921002) (xy 391.641327 -169.961319) (xy 391.546394 -169.993908)
			(xy 391.449094 -170.018547) (xy 391.350092 -170.035066) (xy 391.250063 -170.043352) (xy 391.199878 -170.043856)
			(xy 391.152215 -170.043408) (xy 391.057185 -170.03592) (xy 390.963034 -170.021) (xy 390.870344 -169.998739)
			(xy 390.779686 -169.969276) (xy 390.69162 -169.932791) (xy 390.606686 -169.889509) (xy 390.525411 -169.839698)
			(xy 390.448293 -169.783664) (xy 390.375809 -169.721753) (xy 390.308406 -169.654346) (xy 390.277096 -169.618406)
			(xy 390.269523 -169.610384) (xy 390.249507 -169.601165) (xy 390.238488 -169.600626) (xy 390.161272 -169.600626)
			(xy 390.15025 -169.60114) (xy 390.130233 -169.610375) (xy 390.122664 -169.618406) (xy 390.09137 -169.654357)
			(xy 390.023955 -169.721749) (xy 389.951462 -169.783647) (xy 389.874339 -169.83967) (xy 389.793061 -169.889472)
			(xy 389.708127 -169.932747) (xy 389.620061 -169.969229) (xy 389.529405 -169.998692) (xy 389.436719 -170.020955)
			(xy 389.342571 -170.035881) (xy 389.247543 -170.043378) (xy 389.199882 -170.043856) (xy 389.149697 -170.043365)
			(xy 389.04967 -170.035075) (xy 388.950669 -170.018553) (xy 388.853371 -169.993912) (xy 388.75844 -169.961321)
			(xy 388.666524 -169.921002) (xy 388.578252 -169.87323) (xy 388.494226 -169.818332) (xy 388.415021 -169.756682)
			(xy 388.341177 -169.688703) (xy 388.2732 -169.614857) (xy 388.211552 -169.535651) (xy 388.156656 -169.451624)
			(xy 388.108886 -169.363351) (xy 388.068569 -169.271434) (xy 388.03598 -169.176502) (xy 388.011341 -169.079203)
			(xy 387.994822 -168.980202) (xy 387.986534 -168.880175) (xy 387.986016 -168.82999) (xy 386.413756 -168.82999)
			(xy 386.413252 -168.880175) (xy 386.404964 -168.980203) (xy 386.388444 -169.079204) (xy 386.363806 -169.176503)
			(xy 386.331216 -169.271435) (xy 386.290898 -169.363352) (xy 386.243127 -169.451625) (xy 386.18823 -169.535652)
			(xy 386.126582 -169.614858) (xy 386.058603 -169.688703) (xy 385.984758 -169.756682) (xy 385.905552 -169.81833)
			(xy 385.821525 -169.873227) (xy 385.733252 -169.920998) (xy 385.641335 -169.961316) (xy 385.546403 -169.993906)
			(xy 385.449104 -170.018544) (xy 385.350103 -170.035064) (xy 385.250075 -170.043352) (xy 385.19989 -170.043856)
			(xy 385.152229 -170.043377) (xy 385.057202 -170.035878) (xy 384.963056 -170.02095) (xy 384.870371 -169.998685)
			(xy 384.779717 -169.96922) (xy 384.691652 -169.932738) (xy 384.60672 -169.889461) (xy 384.525443 -169.839658)
			(xy 384.448321 -169.783635) (xy 384.375831 -169.721736) (xy 384.308418 -169.654343) (xy 384.277108 -169.618406)
			(xy 384.269537 -169.61038) (xy 384.24952 -169.601156) (xy 384.2385 -169.600626) (xy 384.161284 -169.600626)
			(xy 384.150268 -169.60117) (xy 384.13026 -169.610397) (xy 384.122676 -169.618406) (xy 384.091366 -169.654345)
			(xy 384.023962 -169.72175) (xy 383.951478 -169.78366) (xy 383.87436 -169.839692) (xy 383.793084 -169.889501)
			(xy 383.70815 -169.932781) (xy 383.620084 -169.969264) (xy 383.529426 -169.998725) (xy 383.436737 -170.020984)
			(xy 383.342586 -170.035902) (xy 383.247556 -170.043388) (xy 383.199894 -170.043856) (xy 383.142998 -170.042332)
			(xy 383.14249 -170.042332) (xy 383.132013 -170.042357) (xy 383.11247 -170.049847) (xy 383.097582 -170.064557)
			(xy 383.093214 -170.074082) (xy 383.057146 -170.162728) (xy 383.053691 -170.172632) (xy 383.054234 -170.193578)
			(xy 383.063086 -170.212569) (xy 383.070608 -170.219878) (xy 383.104714 -170.250884) (xy 383.167006 -170.31883)
			(xy 383.221939 -170.392854) (xy 383.268921 -170.472161) (xy 383.30745 -170.555902) (xy 383.32283 -170.599354)
			(xy 383.326731 -170.609178) (xy 383.340982 -170.624757) (xy 383.360282 -170.633319) (xy 383.370836 -170.633898)
			(xy 386.670296 -170.633898) (xy 386.68087 -170.633377) (xy 386.700219 -170.624851) (xy 386.714455 -170.609216)
			(xy 386.718302 -170.599354) (xy 386.732463 -170.559233) (xy 386.76741 -170.481655) (xy 386.809605 -170.407767)
			(xy 386.858663 -170.338246) (xy 386.914134 -170.273727) (xy 386.975512 -170.214799) (xy 387.042237 -170.162001)
			(xy 387.113698 -170.115816) (xy 387.189242 -170.076664) (xy 387.26818 -170.044905) (xy 387.349789 -170.020828)
			(xy 387.433324 -170.004654) (xy 387.518023 -169.996529) (xy 387.603109 -169.996529) (xy 387.687808 -170.004654)
			(xy 387.771343 -170.020828) (xy 387.852952 -170.044905) (xy 387.93189 -170.076664) (xy 388.007434 -170.115816)
			(xy 388.078895 -170.162001) (xy 388.14562 -170.214799) (xy 388.206998 -170.273727) (xy 388.262469 -170.338246)
			(xy 388.311527 -170.407767) (xy 388.353722 -170.481655) (xy 388.388669 -170.559233) (xy 388.40283 -170.599354)
			(xy 388.406731 -170.609178) (xy 388.420982 -170.624757) (xy 388.440282 -170.633319) (xy 388.450836 -170.633898)
			(xy 391.750296 -170.633898) (xy 391.76087 -170.633377) (xy 391.780219 -170.624851) (xy 391.794455 -170.609216)
			(xy 391.798302 -170.599354) (xy 391.812463 -170.559233) (xy 391.84741 -170.481655) (xy 391.889605 -170.407767)
			(xy 391.938663 -170.338246) (xy 391.994134 -170.273727) (xy 392.055512 -170.214799) (xy 392.122237 -170.162001)
			(xy 392.193698 -170.115816) (xy 392.269242 -170.076664) (xy 392.34818 -170.044905) (xy 392.429789 -170.020828)
			(xy 392.513324 -170.004654) (xy 392.598023 -169.996529) (xy 392.683109 -169.996529) (xy 392.767808 -170.004654)
			(xy 392.851343 -170.020828) (xy 392.932952 -170.044905) (xy 393.01189 -170.076664) (xy 393.087434 -170.115816)
			(xy 393.158895 -170.162001) (xy 393.22562 -170.214799) (xy 393.286998 -170.273727) (xy 393.342469 -170.338246)
			(xy 393.391527 -170.407767) (xy 393.433722 -170.481655) (xy 393.468669 -170.559233) (xy 393.48283 -170.599354)
			(xy 393.486731 -170.609178) (xy 393.500982 -170.624757) (xy 393.520282 -170.633319) (xy 393.530836 -170.633898)
			(xy 396.830296 -170.633898) (xy 396.84087 -170.633377) (xy 396.860219 -170.624851) (xy 396.874455 -170.609216)
			(xy 396.878302 -170.599354) (xy 396.892463 -170.559233) (xy 396.92741 -170.481655) (xy 396.969605 -170.407767)
			(xy 397.018663 -170.338246) (xy 397.074134 -170.273727) (xy 397.135512 -170.214799) (xy 397.202237 -170.162001)
			(xy 397.273698 -170.115816) (xy 397.349242 -170.076664) (xy 397.42818 -170.044905) (xy 397.509789 -170.020828)
			(xy 397.593324 -170.004654) (xy 397.678023 -169.996529) (xy 397.763109 -169.996529) (xy 397.847808 -170.004654)
			(xy 397.931343 -170.020828) (xy 398.012952 -170.044905) (xy 398.09189 -170.076664) (xy 398.167434 -170.115816)
			(xy 398.238895 -170.162001) (xy 398.30562 -170.214799) (xy 398.366998 -170.273727) (xy 398.422469 -170.338246)
			(xy 398.471527 -170.407767) (xy 398.513722 -170.481655) (xy 398.548669 -170.559233) (xy 398.56283 -170.599354)
			(xy 398.566731 -170.609178) (xy 398.580982 -170.624757) (xy 398.600282 -170.633319) (xy 398.610836 -170.633898)
			(xy 401.910296 -170.633898) (xy 401.92087 -170.633377) (xy 401.940219 -170.624851) (xy 401.954455 -170.609216)
			(xy 401.958302 -170.599354) (xy 401.972815 -170.55828) (xy 402.008771 -170.478926) (xy 402.052316 -170.403469)
			(xy 402.103033 -170.332634) (xy 402.160436 -170.267099) (xy 402.223974 -170.207494) (xy 402.293037 -170.15439)
			(xy 402.366964 -170.108296) (xy 402.445045 -170.069654) (xy 402.485606 -170.053762) (xy 402.48586 -170.053762)
			(xy 402.494641 -170.050011) (xy 402.508764 -170.03718) (xy 402.517185 -170.020058) (xy 402.518372 -170.010582)
			(xy 402.5265 -169.91965) (xy 402.526979 -169.910149) (xy 402.521687 -169.891891) (xy 402.510089 -169.87683)
			(xy 402.502116 -169.871644) (xy 402.501862 -169.87139) (xy 402.46078 -169.846255) (xy 402.382308 -169.790405)
			(xy 402.308509 -169.728511) (xy 402.239849 -169.660962) (xy 402.176757 -169.588185) (xy 402.119633 -169.510635)
			(xy 402.068834 -169.428802) (xy 402.024682 -169.343201) (xy 401.987452 -169.254369) (xy 401.957381 -169.162866)
			(xy 401.934656 -169.069267) (xy 401.919422 -168.974162) (xy 401.911773 -168.878149) (xy 401.911312 -168.82999)
			(xy 401.911791 -168.782329) (xy 401.91929 -168.687302) (xy 401.934218 -168.593155) (xy 401.956482 -168.500469)
			(xy 401.985946 -168.409815) (xy 402.022428 -168.32175) (xy 402.065704 -168.236817) (xy 402.115506 -168.155539)
			(xy 402.171528 -168.078416) (xy 402.233426 -168.005925) (xy 402.300818 -167.93851) (xy 402.336762 -167.907208)
			(xy 402.344792 -167.899639) (xy 402.354022 -167.879622) (xy 402.354542 -167.8686) (xy 402.354542 -167.791384)
			(xy 402.353999 -167.780366) (xy 402.344782 -167.76035) (xy 402.336762 -167.752776) (xy 402.300824 -167.721466)
			(xy 402.23342 -167.654061) (xy 402.171512 -167.581576) (xy 402.115482 -167.504458) (xy 402.065673 -167.423181)
			(xy 402.022395 -167.338248) (xy 401.985913 -167.250181) (xy 401.956452 -167.159524) (xy 401.934195 -167.066835)
			(xy 401.919277 -166.972686) (xy 401.911792 -166.877656) (xy 401.911312 -166.829994) (xy 401.911791 -166.782333)
			(xy 401.91929 -166.687306) (xy 401.934217 -166.593159) (xy 401.956481 -166.500473) (xy 401.985945 -166.409818)
			(xy 402.022427 -166.321753) (xy 402.065702 -166.23682) (xy 402.115504 -166.155541) (xy 402.171527 -166.078419)
			(xy 402.233424 -166.005927) (xy 402.300816 -165.938512) (xy 402.336762 -165.907212) (xy 402.344793 -165.899643)
			(xy 402.354025 -165.879626) (xy 402.354542 -165.868604) (xy 402.354542 -165.791388) (xy 402.354 -165.78037)
			(xy 402.344784 -165.760353) (xy 402.336762 -165.75278) (xy 402.300824 -165.72147) (xy 402.23342 -165.654065)
			(xy 402.171512 -165.58158) (xy 402.115481 -165.504462) (xy 402.065672 -165.423186) (xy 402.022394 -165.338252)
			(xy 401.985911 -165.250186) (xy 401.95645 -165.159528) (xy 401.934192 -165.066839) (xy 401.919275 -164.97269)
			(xy 401.911789 -164.87766) (xy 401.911312 -164.829998) (xy 401.911791 -164.782337) (xy 401.919289 -164.687309)
			(xy 401.934217 -164.593163) (xy 401.95648 -164.500476) (xy 401.985944 -164.409821) (xy 402.022425 -164.321756)
			(xy 402.065701 -164.236822) (xy 402.115503 -164.155544) (xy 402.171525 -164.078421) (xy 402.233422 -164.005929)
			(xy 402.300814 -163.938513) (xy 402.336762 -163.907216) (xy 402.344793 -163.899648) (xy 402.354027 -163.87963)
			(xy 402.354542 -163.868608) (xy 402.354542 -163.791392) (xy 402.354001 -163.780373) (xy 402.344785 -163.760355)
			(xy 402.336762 -163.752784) (xy 402.300824 -163.721474) (xy 402.23342 -163.654069) (xy 402.171511 -163.581584)
			(xy 402.11548 -163.504466) (xy 402.065671 -163.42319) (xy 402.022392 -163.338257) (xy 401.98591 -163.25019)
			(xy 401.956449 -163.159533) (xy 401.93419 -163.066844) (xy 401.919272 -162.972694) (xy 401.911786 -162.877664)
			(xy 401.911312 -162.830002) (xy 401.911791 -162.782341) (xy 401.919289 -162.687313) (xy 401.934216 -162.593166)
			(xy 401.956479 -162.50048) (xy 401.985943 -162.409825) (xy 402.022424 -162.321759) (xy 402.065699 -162.236825)
			(xy 402.115501 -162.155546) (xy 402.171523 -162.078423) (xy 402.23342 -162.005931) (xy 402.300812 -161.938515)
			(xy 402.336762 -161.90722) (xy 402.344794 -161.899652) (xy 402.354029 -161.879634) (xy 402.354542 -161.868612)
			(xy 402.354542 -161.791396) (xy 402.354002 -161.780377) (xy 402.344787 -161.760358) (xy 402.336762 -161.752788)
			(xy 402.300824 -161.721478) (xy 402.233419 -161.654073) (xy 402.17151 -161.581588) (xy 402.115479 -161.50447)
			(xy 402.06567 -161.423194) (xy 402.022391 -161.338261) (xy 401.985908 -161.250194) (xy 401.956447 -161.159537)
			(xy 401.934188 -161.066848) (xy 401.919269 -160.972698) (xy 401.911783 -160.877668) (xy 401.911312 -160.830006)
			(xy 401.91179 -160.782345) (xy 401.919288 -160.687317) (xy 401.934215 -160.59317) (xy 401.956478 -160.500483)
			(xy 401.985942 -160.409828) (xy 402.022423 -160.321762) (xy 402.065697 -160.236828) (xy 402.115499 -160.155549)
			(xy 402.171521 -160.078426) (xy 402.233419 -160.005933) (xy 402.30081 -159.938517) (xy 402.336762 -159.907224)
			(xy 402.344795 -159.899656) (xy 402.354031 -159.879639) (xy 402.354542 -159.868616) (xy 402.354542 -159.7914)
			(xy 402.354003 -159.780381) (xy 402.344789 -159.76036) (xy 402.336762 -159.752792) (xy 402.300823 -159.721482)
			(xy 402.233419 -159.654077) (xy 402.17151 -159.581593) (xy 402.115478 -159.504474) (xy 402.065669 -159.423198)
			(xy 402.02239 -159.338265) (xy 401.985906 -159.250199) (xy 401.956445 -159.159541) (xy 401.934186 -159.066852)
			(xy 401.919267 -158.972702) (xy 401.91178 -158.877672) (xy 401.911312 -158.83001) (xy 401.91179 -158.782349)
			(xy 401.919288 -158.687321) (xy 401.934214 -158.593173) (xy 401.956477 -158.500487) (xy 401.98594 -158.409831)
			(xy 402.022421 -158.321765) (xy 402.065696 -158.236831) (xy 402.115498 -158.155552) (xy 402.171519 -158.078428)
			(xy 402.233417 -158.005935) (xy 402.300808 -157.938519) (xy 402.336762 -157.907228) (xy 402.344795 -157.89966)
			(xy 402.354034 -157.879643) (xy 402.354542 -157.86862) (xy 402.354542 -157.791404) (xy 402.354003 -157.780384)
			(xy 402.344791 -157.760362) (xy 402.336762 -157.752796) (xy 402.300823 -157.721486) (xy 402.233419 -157.654081)
			(xy 402.171509 -157.581597) (xy 402.115477 -157.504479) (xy 402.065668 -157.423203) (xy 402.022388 -157.338269)
			(xy 401.985905 -157.250203) (xy 401.956443 -157.159545) (xy 401.934183 -157.066856) (xy 401.919264 -156.972706)
			(xy 401.911777 -156.877676) (xy 401.911312 -156.830014) (xy 401.91179 -156.782352) (xy 401.919288 -156.687324)
			(xy 401.934214 -156.593177) (xy 401.956477 -156.50049) (xy 401.985939 -156.409834) (xy 402.02242 -156.321768)
			(xy 402.065694 -156.236833) (xy 402.115496 -156.155554) (xy 402.171518 -156.07843) (xy 402.233415 -156.005937)
			(xy 402.300806 -155.938521) (xy 402.336762 -155.907232) (xy 402.344796 -155.899665) (xy 402.354036 -155.879647)
			(xy 402.354542 -155.868624) (xy 402.354542 -155.791408) (xy 402.354004 -155.780388) (xy 402.344793 -155.760365)
			(xy 402.336762 -155.7528) (xy 402.300823 -155.72149) (xy 402.233418 -155.654085) (xy 402.171509 -155.581601)
			(xy 402.115476 -155.504483) (xy 402.065667 -155.423207) (xy 402.022387 -155.338274) (xy 401.985903 -155.250207)
			(xy 401.956441 -155.15955) (xy 401.934181 -155.06686) (xy 401.919262 -154.97271) (xy 401.911774 -154.87768)
			(xy 401.911312 -154.830018) (xy 401.91179 -154.782356) (xy 401.919287 -154.687328) (xy 401.934213 -154.593181)
			(xy 401.956476 -154.500493) (xy 401.985938 -154.409837) (xy 402.022419 -154.321771) (xy 402.065693 -154.236836)
			(xy 402.115494 -154.155557) (xy 402.171516 -154.078433) (xy 402.233413 -154.005939) (xy 402.300804 -153.938523)
			(xy 402.336762 -153.907236) (xy 402.344797 -153.899669) (xy 402.354038 -153.879651) (xy 402.354542 -153.868628)
			(xy 402.354542 -153.791412) (xy 402.354005 -153.780391) (xy 402.344794 -153.760367) (xy 402.336762 -153.752804)
			(xy 402.300823 -153.721494) (xy 402.233418 -153.65409) (xy 402.171508 -153.581605) (xy 402.115476 -153.504487)
			(xy 402.065666 -153.423211) (xy 402.022385 -153.338278) (xy 401.985901 -153.250211) (xy 401.956439 -153.159554)
			(xy 401.934179 -153.066865) (xy 401.919259 -152.972715) (xy 401.911771 -152.877684) (xy 401.911312 -152.830022)
			(xy 401.911829 -152.779837) (xy 401.920116 -152.679809) (xy 401.936635 -152.580807) (xy 401.961273 -152.483507)
			(xy 401.993861 -152.388574) (xy 402.034178 -152.296656) (xy 402.081948 -152.208382) (xy 402.136844 -152.124354)
			(xy 402.198491 -152.045146) (xy 402.266469 -151.9713) (xy 402.340313 -151.90332) (xy 402.419518 -151.841669)
			(xy 402.503544 -151.78677) (xy 402.591817 -151.738997) (xy 402.683733 -151.698677) (xy 402.778665 -151.666085)
			(xy 402.875964 -151.641444) (xy 402.974965 -151.624922) (xy 403.074993 -151.616631) (xy 403.125178 -151.616156)
			(xy 403.172839 -151.616634) (xy 403.267867 -151.624131) (xy 403.362015 -151.639057) (xy 403.454701 -151.66132)
			(xy 403.545357 -151.690783) (xy 403.633423 -151.727264) (xy 403.718357 -151.770539) (xy 403.799635 -151.820342)
			(xy 403.876758 -151.876365) (xy 403.94925 -151.938263) (xy 404.016665 -152.005655) (xy 404.04796 -152.041606)
			(xy 404.05553 -152.049636) (xy 404.075546 -152.05887) (xy 404.086568 -152.059386) (xy 404.163784 -152.059386)
			(xy 404.174803 -152.058848) (xy 404.194822 -152.049632) (xy 404.202392 -152.041606) (xy 404.233701 -152.005666)
			(xy 404.301104 -151.938258) (xy 404.373588 -151.876346) (xy 404.450706 -151.820311) (xy 404.531981 -151.770499)
			(xy 404.616914 -151.727217) (xy 404.704981 -151.690731) (xy 404.795639 -151.661267) (xy 404.888329 -151.639006)
			(xy 404.98248 -151.624085) (xy 405.077511 -151.616597) (xy 405.125174 -151.616156) (xy 405.175359 -151.616659)
			(xy 405.275387 -151.624946) (xy 405.37439 -151.641465) (xy 405.471689 -151.666103) (xy 405.566622 -151.698692)
			(xy 405.658539 -151.739009) (xy 405.746813 -151.78678) (xy 405.830841 -151.841677) (xy 405.910047 -151.903325)
			(xy 405.983893 -151.971304) (xy 406.051872 -152.045149) (xy 406.113521 -152.124356) (xy 406.168418 -152.208383)
			(xy 406.216189 -152.296657) (xy 406.256507 -152.388574) (xy 406.289096 -152.483507) (xy 406.313734 -152.580807)
			(xy 406.330254 -152.679809) (xy 406.33854 -152.779837) (xy 406.33904 -152.830022) (xy 406.33856 -152.877683)
			(xy 406.33106 -152.972709) (xy 406.316131 -153.066854) (xy 406.293865 -153.159539) (xy 406.2644 -153.250192)
			(xy 406.227916 -153.338256) (xy 406.184639 -153.423187) (xy 406.134835 -153.504463) (xy 406.078811 -153.581583)
			(xy 406.016912 -153.654072) (xy 405.949518 -153.721484) (xy 405.91359 -153.752804) (xy 405.905568 -153.760377)
			(xy 405.896351 -153.780393) (xy 405.89581 -153.791412) (xy 405.89581 -153.868628) (xy 405.896356 -153.879643)
			(xy 405.905584 -153.899649) (xy 405.91359 -153.907236) (xy 405.949529 -153.938546) (xy 406.016934 -154.00595)
			(xy 406.078844 -154.078434) (xy 406.134876 -154.155552) (xy 406.184685 -154.236828) (xy 406.227965 -154.321761)
			(xy 406.264447 -154.409828) (xy 406.293908 -154.500486) (xy 406.316166 -154.593175) (xy 406.331084 -154.687326)
			(xy 406.338569 -154.782356) (xy 406.33904 -154.830018) (xy 406.338561 -154.877679) (xy 406.331061 -154.972705)
			(xy 406.316132 -155.066851) (xy 406.293866 -155.159536) (xy 406.264401 -155.250189) (xy 406.227918 -155.338253)
			(xy 406.184641 -155.423184) (xy 406.134837 -155.50446) (xy 406.078813 -155.581581) (xy 406.016913 -155.65407)
			(xy 405.94952 -155.721482) (xy 405.91359 -155.7528) (xy 405.905567 -155.760372) (xy 405.896349 -155.780389)
			(xy 405.89581 -155.791408) (xy 405.89581 -155.868624) (xy 405.896356 -155.87964) (xy 405.905582 -155.899647)
			(xy 405.91359 -155.907232) (xy 405.949529 -155.938542) (xy 406.016935 -156.005945) (xy 406.078845 -156.07843)
			(xy 406.134877 -156.155548) (xy 406.184687 -156.236824) (xy 406.227966 -156.321757) (xy 406.264449 -156.409824)
			(xy 406.29391 -156.500482) (xy 406.316169 -156.593171) (xy 406.331086 -156.687321) (xy 406.338572 -156.782352)
			(xy 406.33904 -156.830014) (xy 406.338561 -156.877675) (xy 406.331061 -156.972701) (xy 406.316133 -157.066847)
			(xy 406.293867 -157.159532) (xy 406.264402 -157.250186) (xy 406.227919 -157.33825) (xy 406.184642 -157.423181)
			(xy 406.134839 -157.504458) (xy 406.078815 -157.581578) (xy 406.016915 -157.654068) (xy 405.949522 -157.72148)
			(xy 405.91359 -157.752796) (xy 405.905567 -157.760368) (xy 405.896347 -157.780385) (xy 405.89581 -157.791404)
			(xy 405.89581 -157.86862) (xy 405.896355 -157.879636) (xy 405.90558 -157.899644) (xy 405.91359 -157.907228)
			(xy 405.949529 -157.938538) (xy 406.016935 -158.005941) (xy 406.078845 -158.078425) (xy 406.134878 -158.155543)
			(xy 406.184688 -158.236819) (xy 406.227968 -158.321753) (xy 406.264451 -158.40982) (xy 406.293912 -158.500477)
			(xy 406.316171 -158.593167) (xy 406.331089 -158.687317) (xy 406.338574 -158.782348) (xy 406.33904 -158.83001)
			(xy 406.338561 -158.877671) (xy 406.331062 -158.972698) (xy 406.316133 -159.066843) (xy 406.293868 -159.159529)
			(xy 406.264404 -159.250183) (xy 406.227921 -159.338247) (xy 406.184644 -159.423179) (xy 406.13484 -159.504455)
			(xy 406.078816 -159.581576) (xy 406.016917 -159.654066) (xy 405.949524 -159.721479) (xy 405.91359 -159.752792)
			(xy 405.905566 -159.760364) (xy 405.896345 -159.780381) (xy 405.89581 -159.7914) (xy 405.89581 -159.868616)
			(xy 405.896354 -159.879632) (xy 405.905578 -159.899642) (xy 405.91359 -159.907224) (xy 405.949529 -159.938534)
			(xy 406.016935 -160.005937) (xy 406.078846 -160.078421) (xy 406.134879 -160.155539) (xy 406.184689 -160.236815)
			(xy 406.227969 -160.321748) (xy 406.264452 -160.409815) (xy 406.293914 -160.500473) (xy 406.316173 -160.593163)
			(xy 406.331091 -160.687313) (xy 406.338577 -160.782344) (xy 406.33904 -160.830006) (xy 406.338561 -160.877667)
			(xy 406.331062 -160.972694) (xy 406.316134 -161.06684) (xy 406.293869 -161.159525) (xy 406.264405 -161.250179)
			(xy 406.227922 -161.338244) (xy 406.184645 -161.423176) (xy 406.134842 -161.504453) (xy 406.078818 -161.581574)
			(xy 406.016919 -161.654064) (xy 405.949526 -161.721477) (xy 405.91359 -161.752788) (xy 405.905566 -161.76036)
			(xy 405.896343 -161.780376) (xy 405.89581 -161.791396) (xy 405.89581 -161.868612) (xy 405.896353 -161.879629)
			(xy 405.905576 -161.899639) (xy 405.91359 -161.90722) (xy 405.949529 -161.93853) (xy 406.016936 -162.005933)
			(xy 406.078846 -162.078417) (xy 406.13488 -162.155535) (xy 406.18469 -162.236811) (xy 406.22797 -162.321744)
			(xy 406.264454 -162.409811) (xy 406.293916 -162.500469) (xy 406.316175 -162.593159) (xy 406.331094 -162.687309)
			(xy 406.33858 -162.78234) (xy 406.33904 -162.830002) (xy 406.338561 -162.877663) (xy 406.331062 -162.97269)
			(xy 406.316135 -163.066836) (xy 406.29387 -163.159522) (xy 406.264406 -163.250176) (xy 406.227923 -163.338241)
			(xy 406.184647 -163.423173) (xy 406.134844 -163.50445) (xy 406.07882 -163.581571) (xy 406.016921 -163.654062)
			(xy 405.949528 -163.721475) (xy 405.91359 -163.752784) (xy 405.905565 -163.760356) (xy 405.896341 -163.780372)
			(xy 405.89581 -163.791392) (xy 405.89581 -163.868608) (xy 405.896352 -163.879625) (xy 405.905575 -163.899637)
			(xy 405.91359 -163.907216) (xy 405.94953 -163.938526) (xy 406.016936 -164.005929) (xy 406.078847 -164.078413)
			(xy 406.13488 -164.155531) (xy 406.184691 -164.236807) (xy 406.227972 -164.32174) (xy 406.264456 -164.409807)
			(xy 406.293918 -164.500465) (xy 406.316178 -164.593154) (xy 406.331097 -164.687305) (xy 406.338583 -164.782335)
			(xy 406.33904 -164.829998) (xy 406.338561 -164.877659) (xy 406.331063 -164.972686) (xy 406.316136 -165.066833)
			(xy 406.293871 -165.159518) (xy 406.264407 -165.250173) (xy 406.227925 -165.338238) (xy 406.184649 -165.42317)
			(xy 406.134845 -165.504448) (xy 406.078822 -165.581569) (xy 406.016923 -165.65406) (xy 405.94953 -165.721473)
			(xy 405.91359 -165.75278) (xy 405.905564 -165.760351) (xy 405.896338 -165.780368) (xy 405.89581 -165.791388)
			(xy 405.89581 -165.868604) (xy 405.896352 -165.879622) (xy 405.905573 -165.899635) (xy 405.91359 -165.907212)
			(xy 405.94953 -165.938521) (xy 406.016936 -166.005925) (xy 406.078848 -166.078409) (xy 406.134881 -166.155526)
			(xy 406.184692 -166.236802) (xy 406.227973 -166.321736) (xy 406.264457 -166.409802) (xy 406.29392 -166.50046)
			(xy 406.31618 -166.59315) (xy 406.331099 -166.687301) (xy 406.338586 -166.782331) (xy 406.33904 -166.829994)
			(xy 406.338561 -166.877655) (xy 406.331063 -166.972682) (xy 406.316136 -167.066829) (xy 406.293872 -167.159515)
			(xy 406.264408 -167.25017) (xy 406.227926 -167.338235) (xy 406.18465 -167.423167) (xy 406.134847 -167.504445)
			(xy 406.078824 -167.581567) (xy 406.016925 -167.654058) (xy 405.949532 -167.721471) (xy 405.91359 -167.752776)
			(xy 405.905563 -167.760347) (xy 405.896336 -167.780364) (xy 405.89581 -167.791384) (xy 405.89581 -167.8686)
			(xy 405.896351 -167.879618) (xy 405.905571 -167.899632) (xy 405.91359 -167.907208) (xy 405.952204 -167.940888)
			(xy 406.024236 -168.01377) (xy 406.089866 -168.092466) (xy 406.148626 -168.176416) (xy 406.200097 -168.265022)
			(xy 406.243913 -168.357654) (xy 406.279761 -168.45365) (xy 406.307387 -168.552327) (xy 406.326593 -168.652982)
			(xy 406.337242 -168.754899) (xy 406.338786 -168.806114) (xy 406.338786 -168.806368) (xy 406.339394 -168.8158)
			(xy 406.346684 -168.833224) (xy 406.359822 -168.846793) (xy 406.36825 -168.851072) (xy 406.449784 -168.889172)
			(xy 406.458545 -168.892789) (xy 406.47745 -168.893951) (xy 406.495494 -168.888193) (xy 406.503124 -168.882568)
			(xy 406.536984 -168.856106) (xy 406.608922 -168.809085) (xy 406.685054 -168.769211) (xy 406.764672 -168.736853)
			(xy 406.847036 -168.712313) (xy 406.93138 -168.695818) (xy 407.016921 -168.687522) (xy 407.059892 -168.686988)
			(xy 407.060146 -168.686988) (xy 407.109046 -168.687686) (xy 407.206253 -168.698458) (xy 407.301697 -168.719801)
			(xy 407.348182 -168.734994) (xy 407.364692 -168.737788) (xy 407.373423 -168.737439) (xy 407.389863 -168.73156)
			(xy 407.403339 -168.72046) (xy 407.408126 -168.71315) (xy 407.454482 -168.635599) (xy 407.540958 -168.476938)
			(xy 407.620151 -168.314519) (xy 407.691897 -168.148677) (xy 407.756049 -167.979751) (xy 407.812476 -167.808091)
			(xy 407.86106 -167.634048) (xy 407.901702 -167.457981) (xy 407.934318 -167.280252) (xy 407.958842 -167.101228)
			(xy 407.975223 -166.921275) (xy 407.983426 -166.740764) (xy 407.983944 -166.650416) (xy 407.983944 -166.104062)
			(xy 407.983414 -166.093496) (xy 407.974875 -166.074169) (xy 407.959236 -166.059961) (xy 407.9494 -166.056056)
			(xy 407.909271 -166.041904) (xy 407.831674 -166.006972) (xy 407.757768 -165.964789) (xy 407.688229 -165.91574)
			(xy 407.623692 -165.860274) (xy 407.564747 -165.798899) (xy 407.511933 -165.732174) (xy 407.465733 -165.66071)
			(xy 407.426569 -165.585161) (xy 407.3948 -165.506216) (xy 407.370715 -165.424599) (xy 407.354535 -165.341054)
			(xy 407.346408 -165.256346) (xy 407.346408 -165.171249) (xy 407.354536 -165.086541) (xy 407.370716 -165.002996)
			(xy 407.394801 -164.921379) (xy 407.426571 -164.842435) (xy 407.465735 -164.766885) (xy 407.511936 -164.695422)
			(xy 407.56475 -164.628697) (xy 407.623695 -164.567322) (xy 407.688233 -164.511857) (xy 407.757773 -164.462808)
			(xy 407.831679 -164.420626) (xy 407.909276 -164.385694) (xy 407.9494 -164.371528) (xy 407.959213 -164.36762)
			(xy 407.974766 -164.353363) (xy 407.983304 -164.334069) (xy 407.983944 -164.323522) (xy 407.983944 -163.299648)
			(xy 407.98443 -163.191212) (xy 407.992244 -162.974482) (xy 408.007865 -162.758173) (xy 408.031272 -162.542569)
			(xy 408.062434 -162.327948) (xy 408.101311 -162.114589) (xy 408.147852 -161.902771) (xy 408.201998 -161.692767)
			(xy 408.263677 -161.484851) (xy 408.332809 -161.279294) (xy 408.409305 -161.076361) (xy 408.493065 -160.876318)
			(xy 408.583981 -160.679423) (xy 408.681934 -160.485933) (xy 408.786797 -160.296098) (xy 408.898433 -160.110167)
			(xy 409.016699 -159.92838) (xy 409.078684 -159.839406) (xy 409.087828 -159.810196) (xy 409.080208 -159.783272)
			(xy 409.058868 -159.748013) (xy 409.022058 -159.674267) (xy 408.992222 -159.597434) (xy 408.969618 -159.518172)
			(xy 408.954437 -159.43716) (xy 408.94681 -159.355091) (xy 408.94635 -159.31388) (xy 408.946826 -159.272777)
			(xy 408.954412 -159.190923) (xy 408.969518 -159.110118) (xy 408.992016 -159.031051) (xy 409.021712 -158.954397)
			(xy 409.058354 -158.88081) (xy 409.10163 -158.810918) (xy 409.151169 -158.745316) (xy 409.20655 -158.684565)
			(xy 409.267299 -158.629183) (xy 409.332899 -158.579642) (xy 409.402791 -158.536365) (xy 409.476377 -158.499721)
			(xy 409.55303 -158.470023) (xy 409.632096 -158.447523) (xy 409.712901 -158.432415) (xy 409.794755 -158.424827)
			(xy 409.835858 -158.424372) (xy 409.881425 -158.424963) (xy 409.972077 -158.434313) (xy 410.061298 -158.452888)
			(xy 410.14815 -158.480494) (xy 410.231721 -158.51684) (xy 410.271722 -158.538672) (xy 410.280647 -158.543133)
			(xy 410.300433 -158.545559) (xy 410.319662 -158.540303) (xy 410.327856 -158.534608) (xy 410.43606 -158.453074)
			(xy 410.522722 -158.389943) (xy 410.699899 -158.269153) (xy 410.881268 -158.154752) (xy 411.066598 -158.046887)
			(xy 411.255654 -157.945694) (xy 411.448196 -157.851302) (xy 411.643979 -157.763832) (xy 411.842755 -157.683393)
			(xy 412.044271 -157.610089) (xy 412.248271 -157.544012) (xy 412.454496 -157.485247) (xy 412.662684 -157.433867)
			(xy 412.767526 -157.41142) (xy 412.806896 -157.371796) (xy 412.81598 -157.329112) (xy 412.841402 -157.245621)
			(xy 412.874878 -157.165023) (xy 412.916087 -157.08809) (xy 412.964632 -157.015563) (xy 413.020048 -156.948139)
			(xy 413.0818 -156.886467) (xy 413.149296 -156.83114) (xy 413.221887 -156.782689) (xy 413.298873 -156.74158)
			(xy 413.379516 -156.70821) (xy 413.463039 -156.682898) (xy 413.54864 -156.665887) (xy 413.635495 -156.657343)
			(xy 413.679132 -156.656786) (xy 413.721267 -156.657276) (xy 413.805161 -156.665241) (xy 413.887925 -156.681105)
			(xy 413.968818 -156.704727) (xy 414.047113 -156.735895) (xy 414.122109 -156.774328) (xy 414.193134 -156.819683)
			(xy 414.25955 -156.871553) (xy 414.320762 -156.929472) (xy 414.376221 -156.992922) (xy 414.42543 -157.061333)
			(xy 414.467947 -157.134092) (xy 414.503392 -157.210547) (xy 414.51784 -157.25013) (xy 414.52183 -157.25977)
			(xy 414.53607 -157.274989) (xy 414.555173 -157.283322) (xy 414.565592 -157.283912) (xy 417.346892 -157.283912)
			(xy 417.356963 -157.283491) (xy 417.375571 -157.27578) (xy 417.38296 -157.268926) (xy 418.07003 -156.581856)
			(xy 418.076877 -156.574459) (xy 418.084607 -156.55586) (xy 418.085016 -156.545788) (xy 418.085016 -78.79461)
			(xy 418.084595 -78.784539) (xy 418.076885 -78.76593) (xy 418.07003 -78.758542) (xy 417.431474 -78.119986)
			(xy 417.424078 -78.113134) (xy 417.405479 -78.105396) (xy 417.395406 -78.105) (xy 405.6634 -78.105)
			(xy 405.63014 -78.104479) (xy 405.56419 -78.095791) (xy 405.499939 -78.078566) (xy 405.438488 -78.053097)
			(xy 405.380889 -78.019821) (xy 405.328129 -77.979308) (xy 405.304244 -77.956156) (xy 401.748244 -74.400156)
			(xy 401.725088 -74.376276) (xy 401.684582 -74.323512) (xy 401.651311 -74.265911) (xy 401.625847 -74.20446)
			(xy 401.608625 -74.140209) (xy 401.599939 -74.074259) (xy 401.5994 -74.041) (xy 401.5994 -44.782486)
			(xy 401.598974 -44.772417) (xy 401.591256 -44.753816) (xy 401.584414 -44.746418) (xy 389.364982 -32.526986)
			(xy 389.357587 -32.520133) (xy 389.338988 -32.512392) (xy 389.328914 -32.512) (xy 370.3066 -32.512)
			(xy 370.27334 -32.511479) (xy 370.20739 -32.502791) (xy 370.143139 -32.485566) (xy 370.081688 -32.460097)
			(xy 370.024089 -32.426821) (xy 369.971329 -32.386308) (xy 369.947444 -32.363156) (xy 353.702874 -16.118586)
			(xy 353.695478 -16.111734) (xy 353.676879 -16.103996) (xy 353.666806 -16.1036) (xy 330.101956 -16.1036)
			(xy 330.068697 -16.103076) (xy 330.00275 -16.094383) (xy 329.938502 -16.077153) (xy 329.877055 -16.051681)
			(xy 329.81946 -16.018402) (xy 329.766705 -15.977886) (xy 329.7428 -15.954756) (xy 325.206614 -11.41857)
			(xy 325.199212 -11.411887) (xy 325.180798 -11.404285) (xy 325.160877 -11.40427) (xy 325.151496 -11.407648)
			(xy 325.137018 -11.41349) (xy 325.12 -11.439144) (xy 325.12 -17.288961) (xy 334.478626 -17.288961)
			(xy 334.478626 -17.204239) (xy 334.486679 -17.119902) (xy 334.502713 -17.036712) (xy 334.526581 -16.955422)
			(xy 334.558069 -16.87677) (xy 334.596891 -16.801467) (xy 334.642694 -16.730195) (xy 334.695065 -16.663599)
			(xy 334.75353 -16.602284) (xy 334.817558 -16.546803) (xy 334.88657 -16.49766) (xy 334.95994 -16.4553)
			(xy 335.037005 -16.420105) (xy 335.117067 -16.392396) (xy 335.1994 -16.372422) (xy 335.283259 -16.360365)
			(xy 335.367884 -16.356334) (xy 335.452509 -16.360365) (xy 335.536368 -16.372422) (xy 335.618701 -16.392396)
			(xy 335.698763 -16.420105) (xy 335.775828 -16.4553) (xy 335.849198 -16.49766) (xy 335.91821 -16.546803)
			(xy 335.982238 -16.602284) (xy 336.040703 -16.663599) (xy 336.093074 -16.730195) (xy 336.138877 -16.801467)
			(xy 336.177699 -16.87677) (xy 336.209187 -16.955422) (xy 336.233055 -17.036712) (xy 336.249089 -17.119902)
			(xy 336.257142 -17.204239) (xy 336.257646 -17.2466) (xy 336.257142 -17.288961) (xy 336.249089 -17.373298)
			(xy 336.233055 -17.456488) (xy 336.209187 -17.537778) (xy 336.177699 -17.61643) (xy 336.138877 -17.691733)
			(xy 336.093074 -17.763005) (xy 336.040703 -17.829601) (xy 335.982238 -17.890916) (xy 335.91821 -17.946397)
			(xy 335.849198 -17.99554) (xy 335.775828 -18.0379) (xy 335.698763 -18.073095) (xy 335.618701 -18.100804)
			(xy 335.536368 -18.120778) (xy 335.452509 -18.132835) (xy 335.367884 -18.136867) (xy 335.283259 -18.132835)
			(xy 335.1994 -18.120778) (xy 335.117067 -18.100804) (xy 335.037005 -18.073095) (xy 334.95994 -18.0379)
			(xy 334.88657 -17.99554) (xy 334.817558 -17.946397) (xy 334.75353 -17.890916) (xy 334.695065 -17.829601)
			(xy 334.642694 -17.763005) (xy 334.596891 -17.691733) (xy 334.558069 -17.61643) (xy 334.526581 -17.537778)
			(xy 334.502713 -17.456488) (xy 334.486679 -17.373298) (xy 334.478626 -17.288961) (xy 325.12 -17.288961)
			(xy 325.12 -28.566561) (xy 334.478626 -28.566561) (xy 334.478626 -28.481839) (xy 334.486679 -28.397502)
			(xy 334.502713 -28.314312) (xy 334.526581 -28.233022) (xy 334.558069 -28.15437) (xy 334.596891 -28.079067)
			(xy 334.642694 -28.007795) (xy 334.695065 -27.941199) (xy 334.75353 -27.879884) (xy 334.817558 -27.824403)
			(xy 334.88657 -27.77526) (xy 334.95994 -27.7329) (xy 335.037005 -27.697705) (xy 335.117067 -27.669996)
			(xy 335.1994 -27.650022) (xy 335.283259 -27.637965) (xy 335.367884 -27.633934) (xy 335.452509 -27.637965)
			(xy 335.536368 -27.650022) (xy 335.618701 -27.669996) (xy 335.698763 -27.697705) (xy 335.775828 -27.7329)
			(xy 335.849198 -27.77526) (xy 335.91821 -27.824403) (xy 335.982238 -27.879884) (xy 336.040703 -27.941199)
			(xy 336.093074 -28.007795) (xy 336.138877 -28.079067) (xy 336.177699 -28.15437) (xy 336.209187 -28.233022)
			(xy 336.233055 -28.314312) (xy 336.249089 -28.397502) (xy 336.257142 -28.481839) (xy 336.257646 -28.5242)
			(xy 336.257142 -28.566561) (xy 336.249089 -28.650898) (xy 336.233055 -28.734088) (xy 336.209187 -28.815378)
			(xy 336.177699 -28.89403) (xy 336.138877 -28.969333) (xy 336.093074 -29.040605) (xy 336.040703 -29.107201)
			(xy 335.982238 -29.168516) (xy 335.91821 -29.223997) (xy 335.849198 -29.27314) (xy 335.775828 -29.3155)
			(xy 335.698763 -29.350695) (xy 335.618701 -29.378404) (xy 335.536368 -29.398378) (xy 335.452509 -29.410435)
			(xy 335.367884 -29.414467) (xy 335.283259 -29.410435) (xy 335.1994 -29.398378) (xy 335.117067 -29.378404)
			(xy 335.037005 -29.350695) (xy 334.95994 -29.3155) (xy 334.88657 -29.27314) (xy 334.817558 -29.223997)
			(xy 334.75353 -29.168516) (xy 334.695065 -29.107201) (xy 334.642694 -29.040605) (xy 334.596891 -28.969333)
			(xy 334.558069 -28.89403) (xy 334.526581 -28.815378) (xy 334.502713 -28.734088) (xy 334.486679 -28.650898)
			(xy 334.478626 -28.566561) (xy 325.12 -28.566561) (xy 325.12 -37.289429) (xy 337.982302 -37.289429)
			(xy 337.982302 -37.204707) (xy 337.990355 -37.12037) (xy 338.006389 -37.03718) (xy 338.030257 -36.95589)
			(xy 338.061745 -36.877238) (xy 338.100567 -36.801935) (xy 338.14637 -36.730663) (xy 338.198741 -36.664067)
			(xy 338.257206 -36.602752) (xy 338.321234 -36.547271) (xy 338.390246 -36.498128) (xy 338.463616 -36.455768)
			(xy 338.540681 -36.420573) (xy 338.620743 -36.392864) (xy 338.703076 -36.37289) (xy 338.786935 -36.360833)
			(xy 338.87156 -36.356802) (xy 338.956185 -36.360833) (xy 339.040044 -36.37289) (xy 339.122377 -36.392864)
			(xy 339.202439 -36.420573) (xy 339.279504 -36.455768) (xy 339.352874 -36.498128) (xy 339.421886 -36.547271)
			(xy 339.485914 -36.602752) (xy 339.544379 -36.664067) (xy 339.59675 -36.730663) (xy 339.642553 -36.801935)
			(xy 339.681375 -36.877238) (xy 339.712863 -36.95589) (xy 339.736731 -37.03718) (xy 339.752765 -37.12037)
			(xy 339.760818 -37.204707) (xy 339.761322 -37.247068) (xy 339.760818 -37.289429) (xy 339.752765 -37.373766)
			(xy 339.736731 -37.456956) (xy 339.712863 -37.538246) (xy 339.681375 -37.616898) (xy 339.642553 -37.692201)
			(xy 339.59675 -37.763473) (xy 339.544379 -37.830069) (xy 339.485914 -37.891384) (xy 339.421886 -37.946865)
			(xy 339.352874 -37.996008) (xy 339.279504 -38.038368) (xy 339.202439 -38.073563) (xy 339.122377 -38.101272)
			(xy 339.040044 -38.121246) (xy 338.956185 -38.133303) (xy 338.87156 -38.137335) (xy 338.786935 -38.133303)
			(xy 338.703076 -38.121246) (xy 338.620743 -38.101272) (xy 338.540681 -38.073563) (xy 338.463616 -38.038368)
			(xy 338.390246 -37.996008) (xy 338.321234 -37.946865) (xy 338.257206 -37.891384) (xy 338.198741 -37.830069)
			(xy 338.14637 -37.763473) (xy 338.100567 -37.692201) (xy 338.061745 -37.616898) (xy 338.030257 -37.538246)
			(xy 338.006389 -37.456956) (xy 337.990355 -37.373766) (xy 337.982302 -37.289429) (xy 325.12 -37.289429)
			(xy 325.12 -39.787831) (xy 334.477997 -39.787831) (xy 334.483261 -39.704146) (xy 334.496377 -39.621328)
			(xy 334.517229 -39.540112) (xy 334.545631 -39.461218) (xy 334.581332 -39.385348) (xy 334.624014 -39.313173)
			(xy 334.673299 -39.245336) (xy 334.728749 -39.182438) (xy 334.789873 -39.125038) (xy 334.856127 -39.073645)
			(xy 334.926923 -39.028714) (xy 335.001634 -38.990646) (xy 335.079595 -38.959777) (xy 335.160116 -38.936382)
			(xy 335.242481 -38.920669) (xy 335.325959 -38.912776) (xy 335.367884 -38.912292) (xy 335.368392 -38.912292)
			(xy 335.404819 -38.912666) (xy 335.477428 -38.918641) (xy 335.513426 -38.92423) (xy 335.528472 -38.926165)
			(xy 335.558521 -38.922119) (xy 335.586063 -38.909441) (xy 335.608678 -38.889246) (xy 335.624379 -38.863308)
			(xy 335.631785 -38.833906) (xy 335.630246 -38.803626) (xy 335.619897 -38.775127) (xy 335.611216 -38.762686)
			(xy 335.586864 -38.729613) (xy 335.543671 -38.659752) (xy 335.507099 -38.586206) (xy 335.477461 -38.509604)
			(xy 335.455009 -38.430596) (xy 335.439934 -38.349855) (xy 335.432365 -38.268068) (xy 335.431892 -38.227)
			(xy 335.432376 -38.185075) (xy 335.440267 -38.101596) (xy 335.455979 -38.019231) (xy 335.479372 -37.938709)
			(xy 335.51024 -37.860747) (xy 335.548307 -37.786036) (xy 335.593237 -37.715238) (xy 335.644629 -37.648983)
			(xy 335.702029 -37.587859) (xy 335.764926 -37.532407) (xy 335.832763 -37.483121) (xy 335.904937 -37.440438)
			(xy 335.980807 -37.404736) (xy 336.0597 -37.376332) (xy 336.140917 -37.355479) (xy 336.223735 -37.342362)
			(xy 336.30742 -37.337097) (xy 336.39123 -37.339731) (xy 336.474419 -37.35024) (xy 336.55625 -37.368532)
			(xy 336.635997 -37.394443) (xy 336.712951 -37.427744) (xy 336.78643 -37.46814) (xy 336.855782 -37.515271)
			(xy 336.92039 -37.568719) (xy 336.979681 -37.62801) (xy 337.033129 -37.692618) (xy 337.08026 -37.76197)
			(xy 337.120656 -37.835449) (xy 337.153957 -37.912403) (xy 337.179868 -37.99215) (xy 337.19816 -38.073981)
			(xy 337.208669 -38.15717) (xy 337.211303 -38.24098) (xy 337.206038 -38.324665) (xy 337.192921 -38.407483)
			(xy 337.172068 -38.4887) (xy 337.143664 -38.567593) (xy 337.107962 -38.643463) (xy 337.065279 -38.715637)
			(xy 337.015993 -38.783474) (xy 336.960541 -38.846371) (xy 336.899417 -38.903771) (xy 336.833162 -38.955163)
			(xy 336.762364 -39.000093) (xy 336.687653 -39.03816) (xy 336.609691 -39.069028) (xy 336.529169 -39.092421)
			(xy 336.446804 -39.108133) (xy 336.363325 -39.116024) (xy 336.3214 -39.116508) (xy 336.320892 -39.116508)
			(xy 336.284465 -39.116136) (xy 336.211856 -39.110159) (xy 336.175858 -39.10457) (xy 336.160814 -39.102622)
			(xy 336.130765 -39.106672) (xy 336.103223 -39.119352) (xy 336.080609 -39.139549) (xy 336.064909 -39.165489)
			(xy 336.057502 -39.194891) (xy 336.05904 -39.225172) (xy 336.069388 -39.253672) (xy 336.078068 -39.266114)
			(xy 336.102418 -39.299188) (xy 336.145612 -39.36905) (xy 336.182184 -39.442594) (xy 336.211822 -39.519197)
			(xy 336.234274 -39.598205) (xy 336.249349 -39.678945) (xy 336.256919 -39.760732) (xy 336.257392 -39.8018)
			(xy 336.256924 -39.843725) (xy 336.249033 -39.927203) (xy 336.233322 -40.009569) (xy 336.209928 -40.090089)
			(xy 336.179061 -40.168052) (xy 336.140994 -40.242763) (xy 336.096065 -40.31356) (xy 336.044672 -40.379815)
			(xy 335.987273 -40.440939) (xy 335.924376 -40.496391) (xy 335.85654 -40.545677) (xy 335.784367 -40.588361)
			(xy 335.708497 -40.624063) (xy 335.629604 -40.652466) (xy 335.548388 -40.67332) (xy 335.491305 -40.682361)
			(xy 343.306142 -40.682361) (xy 343.306142 -40.597639) (xy 343.314195 -40.513302) (xy 343.330229 -40.430112)
			(xy 343.354097 -40.348822) (xy 343.385585 -40.27017) (xy 343.424407 -40.194867) (xy 343.47021 -40.123595)
			(xy 343.522581 -40.056999) (xy 343.581046 -39.995684) (xy 343.645074 -39.940203) (xy 343.714086 -39.89106)
			(xy 343.787456 -39.8487) (xy 343.864521 -39.813505) (xy 343.944583 -39.785796) (xy 344.026916 -39.765822)
			(xy 344.110775 -39.753765) (xy 344.1954 -39.749734) (xy 344.280025 -39.753765) (xy 344.363884 -39.765822)
			(xy 344.446217 -39.785796) (xy 344.526279 -39.813505) (xy 344.603344 -39.8487) (xy 344.676714 -39.89106)
			(xy 344.745726 -39.940203) (xy 344.809754 -39.995684) (xy 344.868219 -40.056999) (xy 344.92059 -40.123595)
			(xy 344.966393 -40.194867) (xy 345.005215 -40.27017) (xy 345.036703 -40.348822) (xy 345.060571 -40.430112)
			(xy 345.076605 -40.513302) (xy 345.084658 -40.597639) (xy 345.085162 -40.64) (xy 345.084658 -40.682361)
			(xy 345.076605 -40.766698) (xy 345.060571 -40.849888) (xy 345.036703 -40.931178) (xy 345.005215 -41.00983)
			(xy 344.966393 -41.085133) (xy 344.92059 -41.156405) (xy 344.868219 -41.223001) (xy 344.809754 -41.284316)
			(xy 344.745726 -41.339797) (xy 344.676714 -41.38894) (xy 344.603344 -41.4313) (xy 344.526279 -41.466495)
			(xy 344.446217 -41.494204) (xy 344.363884 -41.514178) (xy 344.280025 -41.526235) (xy 344.1954 -41.530267)
			(xy 344.110775 -41.526235) (xy 344.026916 -41.514178) (xy 343.944583 -41.494204) (xy 343.864521 -41.466495)
			(xy 343.787456 -41.4313) (xy 343.714086 -41.38894) (xy 343.645074 -41.339797) (xy 343.581046 -41.284316)
			(xy 343.522581 -41.223001) (xy 343.47021 -41.156405) (xy 343.424407 -41.085133) (xy 343.385585 -41.00983)
			(xy 343.354097 -40.931178) (xy 343.330229 -40.849888) (xy 343.314195 -40.766698) (xy 343.306142 -40.682361)
			(xy 335.491305 -40.682361) (xy 335.46557 -40.686437) (xy 335.381885 -40.691703) (xy 335.298076 -40.689069)
			(xy 335.214887 -40.678561) (xy 335.133056 -40.66027) (xy 335.053309 -40.634359) (xy 334.976355 -40.601059)
			(xy 334.902876 -40.560664) (xy 334.833525 -40.513534) (xy 334.768916 -40.460086) (xy 334.709625 -40.400796)
			(xy 334.656176 -40.336188) (xy 334.609044 -40.266838) (xy 334.568648 -40.19336) (xy 334.535346 -40.116406)
			(xy 334.509434 -40.03666) (xy 334.491142 -39.954829) (xy 334.480632 -39.87164) (xy 334.477997 -39.787831)
			(xy 325.12 -39.787831) (xy 325.12 -48.465937) (xy 337.609176 -48.465937) (xy 337.609176 -48.381215)
			(xy 337.617229 -48.296878) (xy 337.633263 -48.213688) (xy 337.657131 -48.132398) (xy 337.688619 -48.053746)
			(xy 337.727441 -47.978443) (xy 337.773244 -47.907171) (xy 337.825615 -47.840575) (xy 337.88408 -47.77926)
			(xy 337.948108 -47.723779) (xy 338.01712 -47.674636) (xy 338.09049 -47.632276) (xy 338.167555 -47.597081)
			(xy 338.247617 -47.569372) (xy 338.32995 -47.549398) (xy 338.413809 -47.537341) (xy 338.498434 -47.53331)
			(xy 338.583059 -47.537341) (xy 338.666918 -47.549398) (xy 338.749251 -47.569372) (xy 338.829313 -47.597081)
			(xy 338.906378 -47.632276) (xy 338.979748 -47.674636) (xy 339.04876 -47.723779) (xy 339.112788 -47.77926)
			(xy 339.171253 -47.840575) (xy 339.223624 -47.907171) (xy 339.269427 -47.978443) (xy 339.308249 -48.053746)
			(xy 339.339737 -48.132398) (xy 339.363605 -48.213688) (xy 339.379639 -48.296878) (xy 339.387692 -48.381215)
			(xy 339.388196 -48.423576) (xy 339.387692 -48.465937) (xy 339.379639 -48.550274) (xy 339.363605 -48.633464)
			(xy 339.339737 -48.714754) (xy 339.308249 -48.793406) (xy 339.269427 -48.868709) (xy 339.223624 -48.939981)
			(xy 339.171253 -49.006577) (xy 339.112788 -49.067892) (xy 339.04876 -49.123373) (xy 338.979748 -49.172516)
			(xy 338.906378 -49.214876) (xy 338.829313 -49.250071) (xy 338.749251 -49.27778) (xy 338.666918 -49.297754)
			(xy 338.583059 -49.309811) (xy 338.498434 -49.313843) (xy 338.413809 -49.309811) (xy 338.32995 -49.297754)
			(xy 338.247617 -49.27778) (xy 338.167555 -49.250071) (xy 338.09049 -49.214876) (xy 338.01712 -49.172516)
			(xy 337.948108 -49.123373) (xy 337.88408 -49.067892) (xy 337.825615 -49.006577) (xy 337.773244 -48.939981)
			(xy 337.727441 -48.868709) (xy 337.688619 -48.793406) (xy 337.657131 -48.714754) (xy 337.633263 -48.633464)
			(xy 337.617229 -48.550274) (xy 337.609176 -48.465937) (xy 325.12 -48.465937) (xy 325.12 -51.065431)
			(xy 334.477997 -51.065431) (xy 334.483261 -50.981746) (xy 334.496377 -50.898928) (xy 334.517229 -50.817712)
			(xy 334.545631 -50.738818) (xy 334.581332 -50.662948) (xy 334.624014 -50.590773) (xy 334.673299 -50.522936)
			(xy 334.728749 -50.460038) (xy 334.789873 -50.402638) (xy 334.856127 -50.351245) (xy 334.926923 -50.306314)
			(xy 335.001634 -50.268246) (xy 335.079595 -50.237377) (xy 335.160116 -50.213982) (xy 335.242481 -50.198269)
			(xy 335.325959 -50.190376) (xy 335.367884 -50.189892) (xy 335.368392 -50.189892) (xy 335.404819 -50.190266)
			(xy 335.477428 -50.196241) (xy 335.513426 -50.20183) (xy 335.528472 -50.203765) (xy 335.558521 -50.199719)
			(xy 335.586063 -50.187041) (xy 335.608678 -50.166846) (xy 335.624379 -50.140908) (xy 335.631785 -50.111506)
			(xy 335.630246 -50.081226) (xy 335.619897 -50.052727) (xy 335.611216 -50.040286) (xy 335.586864 -50.007213)
			(xy 335.543671 -49.937352) (xy 335.507099 -49.863806) (xy 335.477461 -49.787204) (xy 335.455009 -49.708196)
			(xy 335.439934 -49.627455) (xy 335.432365 -49.545668) (xy 335.431892 -49.5046) (xy 335.432376 -49.462675)
			(xy 335.440267 -49.379196) (xy 335.455979 -49.296831) (xy 335.479372 -49.216309) (xy 335.51024 -49.138347)
			(xy 335.548307 -49.063636) (xy 335.593237 -48.992838) (xy 335.644629 -48.926583) (xy 335.702029 -48.865459)
			(xy 335.764926 -48.810007) (xy 335.832763 -48.760721) (xy 335.904937 -48.718038) (xy 335.980807 -48.682336)
			(xy 336.0597 -48.653932) (xy 336.140917 -48.633079) (xy 336.223735 -48.619962) (xy 336.30742 -48.614697)
			(xy 336.39123 -48.617331) (xy 336.474419 -48.62784) (xy 336.55625 -48.646132) (xy 336.635997 -48.672043)
			(xy 336.712951 -48.705344) (xy 336.78643 -48.74574) (xy 336.855782 -48.792871) (xy 336.92039 -48.846319)
			(xy 336.979681 -48.90561) (xy 337.033129 -48.970218) (xy 337.08026 -49.03957) (xy 337.120656 -49.113049)
			(xy 337.153957 -49.190003) (xy 337.179868 -49.26975) (xy 337.19816 -49.351581) (xy 337.208669 -49.43477)
			(xy 337.211303 -49.51858) (xy 337.206038 -49.602265) (xy 337.192921 -49.685083) (xy 337.172068 -49.7663)
			(xy 337.143664 -49.845193) (xy 337.107962 -49.921063) (xy 337.065279 -49.993237) (xy 337.015993 -50.061074)
			(xy 336.960541 -50.123971) (xy 336.899417 -50.181371) (xy 336.833162 -50.232763) (xy 336.762364 -50.277693)
			(xy 336.687653 -50.31576) (xy 336.609691 -50.346628) (xy 336.529169 -50.370021) (xy 336.446804 -50.385733)
			(xy 336.363325 -50.393624) (xy 336.3214 -50.394108) (xy 336.320892 -50.394108) (xy 336.284465 -50.393736)
			(xy 336.211856 -50.387759) (xy 336.175858 -50.38217) (xy 336.160814 -50.380222) (xy 336.130765 -50.384272)
			(xy 336.103223 -50.396952) (xy 336.080609 -50.417149) (xy 336.064909 -50.443089) (xy 336.057502 -50.472491)
			(xy 336.05904 -50.502772) (xy 336.069388 -50.531272) (xy 336.078068 -50.543714) (xy 336.102418 -50.576788)
			(xy 336.145612 -50.64665) (xy 336.182184 -50.720194) (xy 336.211822 -50.796797) (xy 336.234274 -50.875805)
			(xy 336.242505 -50.919888) (xy 376.553741 -50.919888) (xy 376.557716 -50.809829) (xy 376.569624 -50.700343)
			(xy 376.5894 -50.592002) (xy 376.616943 -50.485371) (xy 376.652108 -50.381005) (xy 376.694712 -50.279448)
			(xy 376.744533 -50.181231) (xy 376.801312 -50.086864) (xy 376.864751 -49.99684) (xy 376.934522 -49.911629)
			(xy 377.010259 -49.831674) (xy 377.091568 -49.757393) (xy 377.178025 -49.689173) (xy 377.269179 -49.627368)
			(xy 377.364556 -49.572303) (xy 377.463657 -49.524263) (xy 377.565966 -49.483499) (xy 377.67095 -49.450224)
			(xy 377.778061 -49.424611) (xy 377.886741 -49.406794) (xy 377.996424 -49.396865) (xy 378.106537 -49.394877)
			(xy 378.216507 -49.400839) (xy 378.32576 -49.414721) (xy 378.433726 -49.436451) (xy 378.539843 -49.465914)
			(xy 378.643557 -49.502957) (xy 378.744328 -49.547388) (xy 378.84163 -49.598975) (xy 378.934956 -49.657447)
			(xy 379.023819 -49.722502) (xy 379.107757 -49.7938) (xy 379.186332 -49.870968) (xy 379.259133 -49.953605)
			(xy 379.325781 -50.041279) (xy 379.38593 -50.133535) (xy 379.439264 -50.22989) (xy 379.485507 -50.329842)
			(xy 379.524417 -50.43287) (xy 379.555791 -50.538438) (xy 379.579466 -50.645994) (xy 379.595318 -50.754978)
			(xy 379.603265 -50.864822) (xy 379.603762 -50.919888) (xy 396.111741 -50.919888) (xy 396.115716 -50.809829)
			(xy 396.127624 -50.700343) (xy 396.1474 -50.592002) (xy 396.174943 -50.485371) (xy 396.210108 -50.381005)
			(xy 396.252712 -50.279448) (xy 396.302533 -50.181231) (xy 396.359312 -50.086864) (xy 396.422751 -49.99684)
			(xy 396.492522 -49.911629) (xy 396.568259 -49.831674) (xy 396.649568 -49.757393) (xy 396.736025 -49.689173)
			(xy 396.827179 -49.627368) (xy 396.922556 -49.572303) (xy 397.021657 -49.524263) (xy 397.123966 -49.483499)
			(xy 397.22895 -49.450224) (xy 397.336061 -49.424611) (xy 397.444741 -49.406794) (xy 397.554424 -49.396865)
			(xy 397.664537 -49.394877) (xy 397.774507 -49.400839) (xy 397.88376 -49.414721) (xy 397.991726 -49.436451)
			(xy 398.097843 -49.465914) (xy 398.201557 -49.502957) (xy 398.302328 -49.547388) (xy 398.39963 -49.598975)
			(xy 398.492956 -49.657447) (xy 398.581819 -49.722502) (xy 398.665757 -49.7938) (xy 398.744332 -49.870968)
			(xy 398.817133 -49.953605) (xy 398.883781 -50.041279) (xy 398.94393 -50.133535) (xy 398.997264 -50.22989)
			(xy 399.043507 -50.329842) (xy 399.082417 -50.43287) (xy 399.113791 -50.538438) (xy 399.137466 -50.645994)
			(xy 399.153318 -50.754978) (xy 399.161265 -50.864822) (xy 399.161762 -50.919888) (xy 399.161265 -50.974954)
			(xy 399.153318 -51.084798) (xy 399.137466 -51.193782) (xy 399.113791 -51.301338) (xy 399.082417 -51.406906)
			(xy 399.043507 -51.509934) (xy 398.997264 -51.609886) (xy 398.94393 -51.706241) (xy 398.883781 -51.798497)
			(xy 398.817133 -51.886171) (xy 398.744332 -51.968808) (xy 398.665757 -52.045976) (xy 398.581819 -52.117274)
			(xy 398.492956 -52.182329) (xy 398.39963 -52.240801) (xy 398.302328 -52.292388) (xy 398.201557 -52.336819)
			(xy 398.097843 -52.373862) (xy 397.991726 -52.403325) (xy 397.88376 -52.425055) (xy 397.774507 -52.438937)
			(xy 397.664537 -52.444899) (xy 397.554424 -52.442911) (xy 397.444741 -52.432982) (xy 397.336061 -52.415165)
			(xy 397.22895 -52.389552) (xy 397.123966 -52.356277) (xy 397.021657 -52.315513) (xy 396.922556 -52.267473)
			(xy 396.827179 -52.212408) (xy 396.736025 -52.150603) (xy 396.649568 -52.082383) (xy 396.568259 -52.008102)
			(xy 396.492522 -51.928147) (xy 396.422751 -51.842936) (xy 396.359312 -51.752912) (xy 396.302533 -51.658545)
			(xy 396.252712 -51.560328) (xy 396.210108 -51.458771) (xy 396.174943 -51.354405) (xy 396.1474 -51.247774)
			(xy 396.127624 -51.139433) (xy 396.115716 -51.029947) (xy 396.111741 -50.919888) (xy 379.603762 -50.919888)
			(xy 379.603265 -50.974954) (xy 379.595318 -51.084798) (xy 379.579466 -51.193782) (xy 379.555791 -51.301338)
			(xy 379.524417 -51.406906) (xy 379.485507 -51.509934) (xy 379.439264 -51.609886) (xy 379.38593 -51.706241)
			(xy 379.325781 -51.798497) (xy 379.259133 -51.886171) (xy 379.186332 -51.968808) (xy 379.107757 -52.045976)
			(xy 379.023819 -52.117274) (xy 378.934956 -52.182329) (xy 378.84163 -52.240801) (xy 378.744328 -52.292388)
			(xy 378.643557 -52.336819) (xy 378.539843 -52.373862) (xy 378.433726 -52.403325) (xy 378.32576 -52.425055)
			(xy 378.216507 -52.438937) (xy 378.106537 -52.444899) (xy 377.996424 -52.442911) (xy 377.886741 -52.432982)
			(xy 377.778061 -52.415165) (xy 377.67095 -52.389552) (xy 377.565966 -52.356277) (xy 377.463657 -52.315513)
			(xy 377.364556 -52.267473) (xy 377.269179 -52.212408) (xy 377.178025 -52.150603) (xy 377.091568 -52.082383)
			(xy 377.010259 -52.008102) (xy 376.934522 -51.928147) (xy 376.864751 -51.842936) (xy 376.801312 -51.752912)
			(xy 376.744533 -51.658545) (xy 376.694712 -51.560328) (xy 376.652108 -51.458771) (xy 376.616943 -51.354405)
			(xy 376.5894 -51.247774) (xy 376.569624 -51.139433) (xy 376.557716 -51.029947) (xy 376.553741 -50.919888)
			(xy 336.242505 -50.919888) (xy 336.249349 -50.956545) (xy 336.256919 -51.038332) (xy 336.257392 -51.0794)
			(xy 336.256924 -51.121325) (xy 336.249033 -51.204803) (xy 336.233322 -51.287169) (xy 336.209928 -51.367689)
			(xy 336.179061 -51.445652) (xy 336.140994 -51.520363) (xy 336.096065 -51.59116) (xy 336.044672 -51.657415)
			(xy 335.987273 -51.718539) (xy 335.924376 -51.773991) (xy 335.85654 -51.823277) (xy 335.784367 -51.865961)
			(xy 335.708497 -51.901663) (xy 335.629604 -51.930066) (xy 335.548388 -51.95092) (xy 335.491305 -51.959961)
			(xy 343.280742 -51.959961) (xy 343.280742 -51.875239) (xy 343.288795 -51.790902) (xy 343.304829 -51.707712)
			(xy 343.328697 -51.626422) (xy 343.360185 -51.54777) (xy 343.399007 -51.472467) (xy 343.44481 -51.401195)
			(xy 343.497181 -51.334599) (xy 343.555646 -51.273284) (xy 343.619674 -51.217803) (xy 343.688686 -51.16866)
			(xy 343.762056 -51.1263) (xy 343.839121 -51.091105) (xy 343.919183 -51.063396) (xy 344.001516 -51.043422)
			(xy 344.085375 -51.031365) (xy 344.17 -51.027334) (xy 344.254625 -51.031365) (xy 344.338484 -51.043422)
			(xy 344.420817 -51.063396) (xy 344.500879 -51.091105) (xy 344.577944 -51.1263) (xy 344.651314 -51.16866)
			(xy 344.720326 -51.217803) (xy 344.784354 -51.273284) (xy 344.842819 -51.334599) (xy 344.89519 -51.401195)
			(xy 344.940993 -51.472467) (xy 344.979815 -51.54777) (xy 345.011303 -51.626422) (xy 345.035171 -51.707712)
			(xy 345.051205 -51.790902) (xy 345.059258 -51.875239) (xy 345.059762 -51.9176) (xy 345.059258 -51.959961)
			(xy 345.051205 -52.044298) (xy 345.035171 -52.127488) (xy 345.011303 -52.208778) (xy 344.979815 -52.28743)
			(xy 344.940993 -52.362733) (xy 344.89519 -52.434005) (xy 344.842819 -52.500601) (xy 344.784354 -52.561916)
			(xy 344.720326 -52.617397) (xy 344.651314 -52.66654) (xy 344.577944 -52.7089) (xy 344.500879 -52.744095)
			(xy 344.420817 -52.771804) (xy 344.338484 -52.791778) (xy 344.254625 -52.803835) (xy 344.17 -52.807867)
			(xy 344.085375 -52.803835) (xy 344.001516 -52.791778) (xy 343.919183 -52.771804) (xy 343.839121 -52.744095)
			(xy 343.762056 -52.7089) (xy 343.688686 -52.66654) (xy 343.619674 -52.617397) (xy 343.555646 -52.561916)
			(xy 343.497181 -52.500601) (xy 343.44481 -52.434005) (xy 343.399007 -52.362733) (xy 343.360185 -52.28743)
			(xy 343.328697 -52.208778) (xy 343.304829 -52.127488) (xy 343.288795 -52.044298) (xy 343.280742 -51.959961)
			(xy 335.491305 -51.959961) (xy 335.46557 -51.964037) (xy 335.381885 -51.969303) (xy 335.298076 -51.966669)
			(xy 335.214887 -51.956161) (xy 335.133056 -51.93787) (xy 335.053309 -51.911959) (xy 334.976355 -51.878659)
			(xy 334.902876 -51.838264) (xy 334.833525 -51.791134) (xy 334.768916 -51.737686) (xy 334.709625 -51.678396)
			(xy 334.656176 -51.613788) (xy 334.609044 -51.544438) (xy 334.568648 -51.47096) (xy 334.535346 -51.394006)
			(xy 334.509434 -51.31426) (xy 334.491142 -51.232429) (xy 334.480632 -51.14924) (xy 334.477997 -51.065431)
			(xy 325.12 -51.065431) (xy 325.12 -58.42) (xy 377.061486 -58.42) (xy 377.065468 -58.330072) (xy 377.077382 -58.240848)
			(xy 377.097135 -58.153026) (xy 377.124572 -58.067293) (xy 377.159479 -57.984321) (xy 377.201583 -57.904758)
			(xy 377.250553 -57.829228) (xy 377.306008 -57.758322) (xy 377.367512 -57.692594) (xy 377.434584 -57.632559)
			(xy 377.5067 -57.578687) (xy 377.583295 -57.531399) (xy 377.663769 -57.491066) (xy 377.747493 -57.458003)
			(xy 377.833812 -57.432469) (xy 377.92205 -57.414664) (xy 378.011515 -57.404726) (xy 378.10151 -57.402735)
			(xy 378.191327 -57.408705) (xy 378.280266 -57.42259) (xy 378.36763 -57.444281) (xy 378.452735 -57.473608)
			(xy 378.534914 -57.510342) (xy 378.613526 -57.554196) (xy 378.687954 -57.604825) (xy 378.757616 -57.661835)
			(xy 378.821967 -57.724778) (xy 378.880504 -57.793162) (xy 378.932767 -57.866452) (xy 378.978349 -57.944074)
			(xy 379.016892 -58.025421) (xy 379.048095 -58.109856) (xy 379.071713 -58.196718) (xy 379.087562 -58.285328)
			(xy 379.095518 -58.374992) (xy 379.096016 -58.42) (xy 396.619486 -58.42) (xy 396.623468 -58.330072)
			(xy 396.635382 -58.240848) (xy 396.655135 -58.153026) (xy 396.682572 -58.067293) (xy 396.717479 -57.984321)
			(xy 396.759583 -57.904758) (xy 396.808553 -57.829228) (xy 396.864008 -57.758322) (xy 396.925512 -57.692594)
			(xy 396.992584 -57.632559) (xy 397.0647 -57.578687) (xy 397.141295 -57.531399) (xy 397.221769 -57.491066)
			(xy 397.305493 -57.458003) (xy 397.391812 -57.432469) (xy 397.48005 -57.414664) (xy 397.569515 -57.404726)
			(xy 397.65951 -57.402735) (xy 397.749327 -57.408705) (xy 397.838266 -57.42259) (xy 397.92563 -57.444281)
			(xy 398.010735 -57.473608) (xy 398.092914 -57.510342) (xy 398.171526 -57.554196) (xy 398.245954 -57.604825)
			(xy 398.315616 -57.661835) (xy 398.379967 -57.724778) (xy 398.438504 -57.793162) (xy 398.490767 -57.866452)
			(xy 398.536349 -57.944074) (xy 398.574892 -58.025421) (xy 398.606095 -58.109856) (xy 398.629713 -58.196718)
			(xy 398.645562 -58.285328) (xy 398.653518 -58.374992) (xy 398.654016 -58.42) (xy 398.653518 -58.465008)
			(xy 398.645562 -58.554672) (xy 398.629713 -58.643282) (xy 398.606095 -58.730144) (xy 398.574892 -58.814579)
			(xy 398.536349 -58.895926) (xy 398.490767 -58.973548) (xy 398.438504 -59.046838) (xy 398.379967 -59.115222)
			(xy 398.315616 -59.178165) (xy 398.245954 -59.235175) (xy 398.171526 -59.285804) (xy 398.092914 -59.329658)
			(xy 398.010735 -59.366392) (xy 397.92563 -59.395719) (xy 397.838266 -59.41741) (xy 397.749327 -59.431295)
			(xy 397.65951 -59.437265) (xy 397.569515 -59.435274) (xy 397.48005 -59.425336) (xy 397.391812 -59.407531)
			(xy 397.305493 -59.381997) (xy 397.221769 -59.348934) (xy 397.141295 -59.308601) (xy 397.0647 -59.261313)
			(xy 396.992584 -59.207441) (xy 396.925512 -59.147406) (xy 396.864008 -59.081678) (xy 396.808553 -59.010772)
			(xy 396.759583 -58.935242) (xy 396.717479 -58.855679) (xy 396.682572 -58.772707) (xy 396.655135 -58.686974)
			(xy 396.635382 -58.599152) (xy 396.623468 -58.509928) (xy 396.619486 -58.42) (xy 379.096016 -58.42)
			(xy 379.095518 -58.465008) (xy 379.087562 -58.554672) (xy 379.071713 -58.643282) (xy 379.048095 -58.730144)
			(xy 379.016892 -58.814579) (xy 378.978349 -58.895926) (xy 378.932767 -58.973548) (xy 378.880504 -59.046838)
			(xy 378.821967 -59.115222) (xy 378.757616 -59.178165) (xy 378.687954 -59.235175) (xy 378.613526 -59.285804)
			(xy 378.534914 -59.329658) (xy 378.452735 -59.366392) (xy 378.36763 -59.395719) (xy 378.280266 -59.41741)
			(xy 378.191327 -59.431295) (xy 378.10151 -59.437265) (xy 378.011515 -59.435274) (xy 377.92205 -59.425336)
			(xy 377.833812 -59.407531) (xy 377.747493 -59.381997) (xy 377.663769 -59.348934) (xy 377.583295 -59.308601)
			(xy 377.5067 -59.261313) (xy 377.434584 -59.207441) (xy 377.367512 -59.147406) (xy 377.306008 -59.081678)
			(xy 377.250553 -59.010772) (xy 377.201583 -58.935242) (xy 377.159479 -58.855679) (xy 377.124572 -58.772707)
			(xy 377.097135 -58.686974) (xy 377.077382 -58.599152) (xy 377.065468 -58.509928) (xy 377.061486 -58.42)
			(xy 325.12 -58.42) (xy 325.12 -62.399361) (xy 334.478626 -62.399361) (xy 334.478626 -62.314639) (xy 334.486679 -62.230302)
			(xy 334.502713 -62.147112) (xy 334.526581 -62.065822) (xy 334.558069 -61.98717) (xy 334.596891 -61.911867)
			(xy 334.642694 -61.840595) (xy 334.695065 -61.773999) (xy 334.75353 -61.712684) (xy 334.817558 -61.657203)
			(xy 334.88657 -61.60806) (xy 334.95994 -61.5657) (xy 335.037005 -61.530505) (xy 335.117067 -61.502796)
			(xy 335.1994 -61.482822) (xy 335.283259 -61.470765) (xy 335.367884 -61.466734) (xy 335.452509 -61.470765)
			(xy 335.536368 -61.482822) (xy 335.618701 -61.502796) (xy 335.698763 -61.530505) (xy 335.775828 -61.5657)
			(xy 335.849198 -61.60806) (xy 335.91821 -61.657203) (xy 335.982238 -61.712684) (xy 336.040703 -61.773999)
			(xy 336.093074 -61.840595) (xy 336.138877 -61.911867) (xy 336.177699 -61.98717) (xy 336.209187 -62.065822)
			(xy 336.233055 -62.147112) (xy 336.249089 -62.230302) (xy 336.257142 -62.314639) (xy 336.257646 -62.357)
			(xy 336.257142 -62.399361) (xy 336.249089 -62.483698) (xy 336.233055 -62.566888) (xy 336.209187 -62.648178)
			(xy 336.177699 -62.72683) (xy 336.138877 -62.802133) (xy 336.093074 -62.873405) (xy 336.040703 -62.940001)
			(xy 335.982238 -63.001316) (xy 335.91821 -63.056797) (xy 335.849198 -63.10594) (xy 335.775828 -63.1483)
			(xy 335.698763 -63.183495) (xy 335.618701 -63.211204) (xy 335.536368 -63.231178) (xy 335.452509 -63.243235)
			(xy 335.367884 -63.247267) (xy 335.283259 -63.243235) (xy 335.1994 -63.231178) (xy 335.117067 -63.211204)
			(xy 335.037005 -63.183495) (xy 334.95994 -63.1483) (xy 334.88657 -63.10594) (xy 334.817558 -63.056797)
			(xy 334.75353 -63.001316) (xy 334.695065 -62.940001) (xy 334.642694 -62.873405) (xy 334.596891 -62.802133)
			(xy 334.558069 -62.72683) (xy 334.526581 -62.648178) (xy 334.502713 -62.566888) (xy 334.486679 -62.483698)
			(xy 334.478626 -62.399361) (xy 325.12 -62.399361) (xy 325.12 -71.239888) (xy 376.553741 -71.239888)
			(xy 376.557716 -71.129829) (xy 376.569624 -71.020343) (xy 376.5894 -70.912002) (xy 376.616943 -70.805371)
			(xy 376.652108 -70.701005) (xy 376.694712 -70.599448) (xy 376.744533 -70.501231) (xy 376.801312 -70.406864)
			(xy 376.864751 -70.31684) (xy 376.934522 -70.231629) (xy 377.010259 -70.151674) (xy 377.091568 -70.077393)
			(xy 377.178025 -70.009173) (xy 377.269179 -69.947368) (xy 377.364556 -69.892303) (xy 377.463657 -69.844263)
			(xy 377.565966 -69.803499) (xy 377.67095 -69.770224) (xy 377.778061 -69.744611) (xy 377.886741 -69.726794)
			(xy 377.996424 -69.716865) (xy 378.106537 -69.714877) (xy 378.216507 -69.720839) (xy 378.32576 -69.734721)
			(xy 378.433726 -69.756451) (xy 378.539843 -69.785914) (xy 378.643557 -69.822957) (xy 378.744328 -69.867388)
			(xy 378.84163 -69.918975) (xy 378.934956 -69.977447) (xy 379.023819 -70.042502) (xy 379.107757 -70.1138)
			(xy 379.186332 -70.190968) (xy 379.259133 -70.273605) (xy 379.325781 -70.361279) (xy 379.38593 -70.453535)
			(xy 379.439264 -70.54989) (xy 379.485507 -70.649842) (xy 379.524417 -70.75287) (xy 379.555791 -70.858438)
			(xy 379.579466 -70.965994) (xy 379.595318 -71.074978) (xy 379.603265 -71.184822) (xy 379.603762 -71.239888)
			(xy 396.111741 -71.239888) (xy 396.115716 -71.129829) (xy 396.127624 -71.020343) (xy 396.1474 -70.912002)
			(xy 396.174943 -70.805371) (xy 396.210108 -70.701005) (xy 396.252712 -70.599448) (xy 396.302533 -70.501231)
			(xy 396.359312 -70.406864) (xy 396.422751 -70.31684) (xy 396.492522 -70.231629) (xy 396.568259 -70.151674)
			(xy 396.649568 -70.077393) (xy 396.736025 -70.009173) (xy 396.827179 -69.947368) (xy 396.922556 -69.892303)
			(xy 397.021657 -69.844263) (xy 397.123966 -69.803499) (xy 397.22895 -69.770224) (xy 397.336061 -69.744611)
			(xy 397.444741 -69.726794) (xy 397.554424 -69.716865) (xy 397.664537 -69.714877) (xy 397.774507 -69.720839)
			(xy 397.88376 -69.734721) (xy 397.991726 -69.756451) (xy 398.097843 -69.785914) (xy 398.201557 -69.822957)
			(xy 398.302328 -69.867388) (xy 398.39963 -69.918975) (xy 398.492956 -69.977447) (xy 398.581819 -70.042502)
			(xy 398.665757 -70.1138) (xy 398.744332 -70.190968) (xy 398.817133 -70.273605) (xy 398.883781 -70.361279)
			(xy 398.94393 -70.453535) (xy 398.997264 -70.54989) (xy 399.043507 -70.649842) (xy 399.082417 -70.75287)
			(xy 399.113791 -70.858438) (xy 399.137466 -70.965994) (xy 399.153318 -71.074978) (xy 399.161265 -71.184822)
			(xy 399.161762 -71.239888) (xy 399.161265 -71.294954) (xy 399.153318 -71.404798) (xy 399.137466 -71.513782)
			(xy 399.113791 -71.621338) (xy 399.082417 -71.726906) (xy 399.043507 -71.829934) (xy 398.997264 -71.929886)
			(xy 398.94393 -72.026241) (xy 398.883781 -72.118497) (xy 398.817133 -72.206171) (xy 398.744332 -72.288808)
			(xy 398.665757 -72.365976) (xy 398.581819 -72.437274) (xy 398.492956 -72.502329) (xy 398.39963 -72.560801)
			(xy 398.302328 -72.612388) (xy 398.201557 -72.656819) (xy 398.097843 -72.693862) (xy 397.991726 -72.723325)
			(xy 397.88376 -72.745055) (xy 397.774507 -72.758937) (xy 397.664537 -72.764899) (xy 397.554424 -72.762911)
			(xy 397.444741 -72.752982) (xy 397.336061 -72.735165) (xy 397.22895 -72.709552) (xy 397.123966 -72.676277)
			(xy 397.021657 -72.635513) (xy 396.922556 -72.587473) (xy 396.827179 -72.532408) (xy 396.736025 -72.470603)
			(xy 396.649568 -72.402383) (xy 396.568259 -72.328102) (xy 396.492522 -72.248147) (xy 396.422751 -72.162936)
			(xy 396.359312 -72.072912) (xy 396.302533 -71.978545) (xy 396.252712 -71.880328) (xy 396.210108 -71.778771)
			(xy 396.174943 -71.674405) (xy 396.1474 -71.567774) (xy 396.127624 -71.459433) (xy 396.115716 -71.349947)
			(xy 396.111741 -71.239888) (xy 379.603762 -71.239888) (xy 379.603265 -71.294954) (xy 379.595318 -71.404798)
			(xy 379.579466 -71.513782) (xy 379.555791 -71.621338) (xy 379.524417 -71.726906) (xy 379.485507 -71.829934)
			(xy 379.439264 -71.929886) (xy 379.38593 -72.026241) (xy 379.325781 -72.118497) (xy 379.259133 -72.206171)
			(xy 379.186332 -72.288808) (xy 379.107757 -72.365976) (xy 379.023819 -72.437274) (xy 378.934956 -72.502329)
			(xy 378.84163 -72.560801) (xy 378.744328 -72.612388) (xy 378.643557 -72.656819) (xy 378.539843 -72.693862)
			(xy 378.433726 -72.723325) (xy 378.32576 -72.745055) (xy 378.216507 -72.758937) (xy 378.106537 -72.764899)
			(xy 377.996424 -72.762911) (xy 377.886741 -72.752982) (xy 377.778061 -72.735165) (xy 377.67095 -72.709552)
			(xy 377.565966 -72.676277) (xy 377.463657 -72.635513) (xy 377.364556 -72.587473) (xy 377.269179 -72.532408)
			(xy 377.178025 -72.470603) (xy 377.091568 -72.402383) (xy 377.010259 -72.328102) (xy 376.934522 -72.248147)
			(xy 376.864751 -72.162936) (xy 376.801312 -72.072912) (xy 376.744533 -71.978545) (xy 376.694712 -71.880328)
			(xy 376.652108 -71.778771) (xy 376.616943 -71.674405) (xy 376.5894 -71.567774) (xy 376.569624 -71.459433)
			(xy 376.557716 -71.349947) (xy 376.553741 -71.239888) (xy 325.12 -71.239888) (xy 325.12 -73.676961)
			(xy 334.478626 -73.676961) (xy 334.478626 -73.592239) (xy 334.486679 -73.507902) (xy 334.502713 -73.424712)
			(xy 334.526581 -73.343422) (xy 334.558069 -73.26477) (xy 334.596891 -73.189467) (xy 334.642694 -73.118195)
			(xy 334.695065 -73.051599) (xy 334.75353 -72.990284) (xy 334.817558 -72.934803) (xy 334.88657 -72.88566)
			(xy 334.95994 -72.8433) (xy 335.037005 -72.808105) (xy 335.117067 -72.780396) (xy 335.1994 -72.760422)
			(xy 335.283259 -72.748365) (xy 335.367884 -72.744334) (xy 335.452509 -72.748365) (xy 335.536368 -72.760422)
			(xy 335.618701 -72.780396) (xy 335.698763 -72.808105) (xy 335.775828 -72.8433) (xy 335.849198 -72.88566)
			(xy 335.91821 -72.934803) (xy 335.982238 -72.990284) (xy 336.040703 -73.051599) (xy 336.093074 -73.118195)
			(xy 336.138877 -73.189467) (xy 336.177699 -73.26477) (xy 336.209187 -73.343422) (xy 336.233055 -73.424712)
			(xy 336.249089 -73.507902) (xy 336.257142 -73.592239) (xy 336.257646 -73.6346) (xy 336.257142 -73.676961)
			(xy 336.249089 -73.761298) (xy 336.233055 -73.844488) (xy 336.209187 -73.925778) (xy 336.177699 -74.00443)
			(xy 336.138877 -74.079733) (xy 336.093074 -74.151005) (xy 336.040703 -74.217601) (xy 335.982238 -74.278916)
			(xy 335.91821 -74.334397) (xy 335.849198 -74.38354) (xy 335.775828 -74.4259) (xy 335.698763 -74.461095)
			(xy 335.618701 -74.488804) (xy 335.536368 -74.508778) (xy 335.452509 -74.520835) (xy 335.367884 -74.524867)
			(xy 335.283259 -74.520835) (xy 335.1994 -74.508778) (xy 335.117067 -74.488804) (xy 335.037005 -74.461095)
			(xy 334.95994 -74.4259) (xy 334.88657 -74.38354) (xy 334.817558 -74.334397) (xy 334.75353 -74.278916)
			(xy 334.695065 -74.217601) (xy 334.642694 -74.151005) (xy 334.596891 -74.079733) (xy 334.558069 -74.00443)
			(xy 334.526581 -73.925778) (xy 334.502713 -73.844488) (xy 334.486679 -73.761298) (xy 334.478626 -73.676961)
			(xy 325.12 -73.676961) (xy 325.12 -78.74) (xy 377.061486 -78.74) (xy 377.065468 -78.650072) (xy 377.077382 -78.560848)
			(xy 377.097135 -78.473026) (xy 377.124572 -78.387293) (xy 377.159479 -78.304321) (xy 377.201583 -78.224758)
			(xy 377.250553 -78.149228) (xy 377.306008 -78.078322) (xy 377.367512 -78.012594) (xy 377.434584 -77.952559)
			(xy 377.5067 -77.898687) (xy 377.583295 -77.851399) (xy 377.663769 -77.811066) (xy 377.747493 -77.778003)
			(xy 377.833812 -77.752469) (xy 377.92205 -77.734664) (xy 378.011515 -77.724726) (xy 378.10151 -77.722735)
			(xy 378.191327 -77.728705) (xy 378.280266 -77.74259) (xy 378.36763 -77.764281) (xy 378.452735 -77.793608)
			(xy 378.534914 -77.830342) (xy 378.613526 -77.874196) (xy 378.687954 -77.924825) (xy 378.757616 -77.981835)
			(xy 378.821967 -78.044778) (xy 378.880504 -78.113162) (xy 378.932767 -78.186452) (xy 378.978349 -78.264074)
			(xy 379.016892 -78.345421) (xy 379.048095 -78.429856) (xy 379.071713 -78.516718) (xy 379.087562 -78.605328)
			(xy 379.095518 -78.694992) (xy 379.096016 -78.74) (xy 396.619486 -78.74) (xy 396.623468 -78.650072)
			(xy 396.635382 -78.560848) (xy 396.655135 -78.473026) (xy 396.682572 -78.387293) (xy 396.717479 -78.304321)
			(xy 396.759583 -78.224758) (xy 396.808553 -78.149228) (xy 396.864008 -78.078322) (xy 396.925512 -78.012594)
			(xy 396.992584 -77.952559) (xy 397.0647 -77.898687) (xy 397.141295 -77.851399) (xy 397.221769 -77.811066)
			(xy 397.305493 -77.778003) (xy 397.391812 -77.752469) (xy 397.48005 -77.734664) (xy 397.569515 -77.724726)
			(xy 397.65951 -77.722735) (xy 397.749327 -77.728705) (xy 397.838266 -77.74259) (xy 397.92563 -77.764281)
			(xy 398.010735 -77.793608) (xy 398.092914 -77.830342) (xy 398.171526 -77.874196) (xy 398.245954 -77.924825)
			(xy 398.315616 -77.981835) (xy 398.379967 -78.044778) (xy 398.438504 -78.113162) (xy 398.490767 -78.186452)
			(xy 398.536349 -78.264074) (xy 398.574892 -78.345421) (xy 398.606095 -78.429856) (xy 398.629713 -78.516718)
			(xy 398.645562 -78.605328) (xy 398.653518 -78.694992) (xy 398.654016 -78.74) (xy 398.653518 -78.785008)
			(xy 398.645562 -78.874672) (xy 398.629713 -78.963282) (xy 398.606095 -79.050144) (xy 398.574892 -79.134579)
			(xy 398.536349 -79.215926) (xy 398.490767 -79.293548) (xy 398.438504 -79.366838) (xy 398.379967 -79.435222)
			(xy 398.315616 -79.498165) (xy 398.245954 -79.555175) (xy 398.171526 -79.605804) (xy 398.092914 -79.649658)
			(xy 398.010735 -79.686392) (xy 397.92563 -79.715719) (xy 397.838266 -79.73741) (xy 397.749327 -79.751295)
			(xy 397.65951 -79.757265) (xy 397.569515 -79.755274) (xy 397.48005 -79.745336) (xy 397.391812 -79.727531)
			(xy 397.305493 -79.701997) (xy 397.221769 -79.668934) (xy 397.141295 -79.628601) (xy 397.0647 -79.581313)
			(xy 396.992584 -79.527441) (xy 396.925512 -79.467406) (xy 396.864008 -79.401678) (xy 396.808553 -79.330772)
			(xy 396.759583 -79.255242) (xy 396.717479 -79.175679) (xy 396.682572 -79.092707) (xy 396.655135 -79.006974)
			(xy 396.635382 -78.919152) (xy 396.623468 -78.829928) (xy 396.619486 -78.74) (xy 379.096016 -78.74)
			(xy 379.095518 -78.785008) (xy 379.087562 -78.874672) (xy 379.071713 -78.963282) (xy 379.048095 -79.050144)
			(xy 379.016892 -79.134579) (xy 378.978349 -79.215926) (xy 378.932767 -79.293548) (xy 378.880504 -79.366838)
			(xy 378.821967 -79.435222) (xy 378.757616 -79.498165) (xy 378.687954 -79.555175) (xy 378.613526 -79.605804)
			(xy 378.534914 -79.649658) (xy 378.452735 -79.686392) (xy 378.36763 -79.715719) (xy 378.280266 -79.73741)
			(xy 378.191327 -79.751295) (xy 378.10151 -79.757265) (xy 378.011515 -79.755274) (xy 377.92205 -79.745336)
			(xy 377.833812 -79.727531) (xy 377.747493 -79.701997) (xy 377.663769 -79.668934) (xy 377.583295 -79.628601)
			(xy 377.5067 -79.581313) (xy 377.434584 -79.527441) (xy 377.367512 -79.467406) (xy 377.306008 -79.401678)
			(xy 377.250553 -79.330772) (xy 377.201583 -79.255242) (xy 377.159479 -79.175679) (xy 377.124572 -79.092707)
			(xy 377.097135 -79.006974) (xy 377.077382 -78.919152) (xy 377.065468 -78.829928) (xy 377.061486 -78.74)
			(xy 325.12 -78.74) (xy 325.12 -79.883) (xy 325.119479 -79.91626) (xy 325.110791 -79.98221) (xy 325.093566 -80.046461)
			(xy 325.068097 -80.107912) (xy 325.034821 -80.165511) (xy 324.994308 -80.218271) (xy 324.971156 -80.242156)
			(xy 324.336156 -80.877156) (xy 324.312276 -80.900312) (xy 324.259512 -80.940818) (xy 324.201911 -80.974089)
			(xy 324.14046 -80.999553) (xy 324.076209 -81.016775) (xy 324.010259 -81.025461) (xy 323.977 -81.026)
			(xy 311.395364 -81.026) (xy 311.362105 -81.025476) (xy 311.296157 -81.016785) (xy 311.231909 -80.999556)
			(xy 311.170461 -80.974084) (xy 311.112866 -80.940805) (xy 311.060109 -80.90029) (xy 311.036208 -80.877156)
			(xy 310.362854 -80.203802) (xy 310.339695 -80.179923) (xy 310.299183 -80.127161) (xy 310.265907 -80.069561)
			(xy 310.240437 -80.008109) (xy 310.223208 -79.943858) (xy 310.214516 -79.877907) (xy 310.21401 -79.844646)
			(xy 310.21401 -77.435964) (xy 310.213369 -77.42479) (xy 310.203792 -77.40459) (xy 310.186578 -77.390327)
			(xy 310.17591 -77.386942) (xy 310.08066 -77.362304) (xy 310.069704 -77.360008) (xy 310.047709 -77.364014)
			(xy 310.029491 -77.376974) (xy 310.02351 -77.386434) (xy 310.02351 -77.386942) (xy 309.989346 -77.447396)
			(xy 309.914859 -77.564605) (xy 309.833578 -77.67721) (xy 309.745789 -77.784818) (xy 309.651798 -77.887053)
			(xy 309.551932 -77.983558) (xy 309.446542 -78.073997) (xy 309.335993 -78.158053) (xy 309.220674 -78.235434)
			(xy 309.100985 -78.305868) (xy 308.977346 -78.369111) (xy 308.850187 -78.424941) (xy 308.719952 -78.473163)
			(xy 308.587097 -78.51361) (xy 308.452085 -78.546139) (xy 308.315388 -78.570637) (xy 308.177482 -78.58702)
			(xy 308.03885 -78.595228) (xy 307.969412 -78.595728) (xy 307.901055 -78.595241) (xy 307.764573 -78.587292)
			(xy 307.628785 -78.571421) (xy 307.494148 -78.547682) (xy 307.36112 -78.516154) (xy 307.23015 -78.476944)
			(xy 307.101682 -78.430186) (xy 306.976149 -78.376036) (xy 306.853978 -78.31468) (xy 306.735581 -78.246323)
			(xy 306.621359 -78.171198) (xy 306.511698 -78.089558) (xy 306.40697 -78.00168) (xy 306.307528 -77.907862)
			(xy 306.21371 -77.80842) (xy 306.125833 -77.703691) (xy 306.044194 -77.59403) (xy 305.96907 -77.479807)
			(xy 305.900714 -77.36141) (xy 305.839358 -77.239238) (xy 305.785209 -77.113705) (xy 305.738451 -76.985237)
			(xy 305.699243 -76.854266) (xy 305.667716 -76.721238) (xy 305.643977 -76.586602) (xy 305.628107 -76.450813)
			(xy 305.620159 -76.314331) (xy 305.619658 -76.245974) (xy 305.62023 -76.17225) (xy 305.62947 -76.025091)
			(xy 305.647923 -75.878802) (xy 305.675518 -75.733959) (xy 305.712145 -75.591132) (xy 305.757661 -75.450885)
			(xy 305.78425 -75.38212) (xy 305.790346 -75.36688) (xy 305.782472 -75.335384) (xy 305.69662 -75.262232)
			(xy 305.68821 -75.255846) (xy 305.667978 -75.249875) (xy 305.647047 -75.252502) (xy 305.637692 -75.257406)
			(xy 305.603167 -75.277559) (xy 305.531157 -75.312291) (xy 305.45632 -75.34042) (xy 305.37926 -75.361717)
			(xy 305.3006 -75.376012) (xy 305.220974 -75.383188) (xy 305.181 -75.383644) (xy 305.180746 -75.383644)
			(xy 305.140715 -75.383207) (xy 305.060976 -75.376014) (xy 304.982206 -75.361683) (xy 304.905043 -75.34033)
			(xy 304.830112 -75.312128) (xy 304.758019 -75.277304) (xy 304.689349 -75.236141) (xy 304.624656 -75.188972)
			(xy 304.59426 -75.162918) (xy 304.587106 -75.157136) (xy 304.569921 -75.150609) (xy 304.560732 -75.150218)
			(xy 304.531268 -75.150218) (xy 304.522076 -75.150607) (xy 304.504887 -75.157124) (xy 304.49774 -75.162918)
			(xy 304.467347 -75.188974) (xy 304.402644 -75.236125) (xy 304.333968 -75.277276) (xy 304.261874 -75.312092)
			(xy 304.186945 -75.340294) (xy 304.109785 -75.361654) (xy 304.03102 -75.375997) (xy 303.951284 -75.38321)
			(xy 303.911254 -75.383644) (xy 303.911 -75.383644) (xy 303.870056 -75.383177) (xy 303.788515 -75.375651)
			(xy 303.708011 -75.360662) (xy 303.629225 -75.338337) (xy 303.552825 -75.308867) (xy 303.479457 -75.272498)
			(xy 303.409741 -75.229541) (xy 303.344269 -75.180358) (xy 303.283594 -75.125365) (xy 303.228231 -75.065029)
			(xy 303.178647 -74.99986) (xy 303.135263 -74.93041) (xy 303.098446 -74.857266) (xy 303.068507 -74.781047)
			(xy 303.045699 -74.7024) (xy 303.037494 -74.662284) (xy 303.033938 -74.64425) (xy 303.005998 -74.621136)
			(xy 294.63238 -74.621136) (xy 294.622573 -74.621587) (xy 294.604392 -74.628946) (xy 294.590296 -74.642584)
			(xy 294.585898 -74.651362) (xy 294.580818 -74.662792) (xy 294.576246 -74.683874) (xy 294.579802 -74.70267)
			(xy 294.594802 -74.741852) (xy 294.618218 -74.822424) (xy 294.633938 -74.904843) (xy 294.641822 -74.988377)
			(xy 294.642286 -75.03033) (xy 294.642286 -75.030584) (xy 294.641782 -75.072908) (xy 294.633736 -75.157174)
			(xy 294.617716 -75.240293) (xy 294.593868 -75.321512) (xy 294.562407 -75.400097) (xy 294.523619 -75.475336)
			(xy 294.477855 -75.546547) (xy 294.425528 -75.613085) (xy 294.367114 -75.674348) (xy 294.303141 -75.729781)
			(xy 294.234188 -75.778882) (xy 294.16088 -75.821207) (xy 294.083881 -75.856371) (xy 294.003888 -75.884057)
			(xy 293.921626 -75.904014) (xy 293.837839 -75.91606) (xy 293.753286 -75.920088) (xy 293.668733 -75.91606)
			(xy 293.584946 -75.904014) (xy 293.502684 -75.884057) (xy 293.422691 -75.856371) (xy 293.345692 -75.821207)
			(xy 293.272384 -75.778882) (xy 293.203431 -75.729781) (xy 293.139458 -75.674348) (xy 293.081044 -75.613085)
			(xy 293.028717 -75.546547) (xy 292.982953 -75.475336) (xy 292.944165 -75.400097) (xy 292.912704 -75.321512)
			(xy 292.888856 -75.240293) (xy 292.872836 -75.157174) (xy 292.86479 -75.072908) (xy 292.864286 -75.030584)
			(xy 292.864286 -75.030076) (xy 292.864896 -74.983317) (xy 292.874732 -74.890318) (xy 292.894272 -74.798864)
			(xy 292.908228 -74.754232) (xy 292.910768 -74.73823) (xy 292.910492 -74.730267) (xy 292.905562 -74.715124)
			(xy 292.901116 -74.708512) (xy 292.852856 -74.641964) (xy 292.845285 -74.632658) (xy 292.82394 -74.621783)
			(xy 292.811962 -74.621136) (xy 285.636716 -74.621136) (xy 285.627982 -74.621482) (xy 285.611534 -74.627354)
			(xy 285.598041 -74.638445) (xy 285.593282 -74.645774) (xy 285.548324 -74.720196) (xy 285.544154 -74.727788)
			(xy 285.540694 -74.744748) (xy 285.543114 -74.761887) (xy 285.5468 -74.769726) (xy 285.5468 -74.76998)
			(xy 285.566374 -74.80832) (xy 285.598869 -74.888043) (xy 285.62351 -74.970531) (xy 285.640069 -75.055014)
			(xy 285.64839 -75.140701) (xy 285.648908 -75.183746) (xy 285.648908 -75.184) (xy 285.648433 -75.225506)
			(xy 285.640702 -75.308158) (xy 285.6253 -75.389729) (xy 285.602359 -75.469509) (xy 285.57208 -75.546802)
			(xy 285.534727 -75.620936) (xy 285.490624 -75.691264) (xy 285.465774 -75.724512) (xy 285.459435 -75.733712)
			(xy 285.454609 -75.7555) (xy 285.459435 -75.777288) (xy 285.465774 -75.786488) (xy 285.490604 -75.819727)
			(xy 285.534669 -75.890033) (xy 285.571999 -75.964134) (xy 285.602271 -76.041388) (xy 285.625221 -76.121125)
			(xy 285.64065 -76.202651) (xy 285.648424 -76.28526) (xy 285.648908 -76.326746) (xy 285.648908 -76.327)
			(xy 285.648404 -76.369348) (xy 285.640353 -76.453662) (xy 285.624324 -76.536828) (xy 285.600463 -76.618095)
			(xy 285.568984 -76.696725) (xy 285.530173 -76.772006) (xy 285.484383 -76.843258) (xy 285.432027 -76.909834)
			(xy 285.373579 -76.971132) (xy 285.309569 -77.026597) (xy 285.240577 -77.075726) (xy 285.167227 -77.118075)
			(xy 285.090184 -77.153259) (xy 285.010145 -77.180961) (xy 284.927836 -77.200929) (xy 284.844001 -77.212982)
			(xy 284.7594 -77.217013) (xy 284.674799 -77.212982) (xy 284.590964 -77.200929) (xy 284.508655 -77.180961)
			(xy 284.428616 -77.153259) (xy 284.351573 -77.118075) (xy 284.278223 -77.075726) (xy 284.209231 -77.026597)
			(xy 284.145221 -76.971132) (xy 284.086773 -76.909834) (xy 284.034417 -76.843258) (xy 283.988627 -76.772006)
			(xy 283.949816 -76.696725) (xy 283.918337 -76.618095) (xy 283.894476 -76.536828) (xy 283.878447 -76.453662)
			(xy 283.870396 -76.369348) (xy 283.869892 -76.327) (xy 283.869892 -76.326746) (xy 283.870378 -76.285258)
			(xy 283.878126 -76.202644) (xy 283.893538 -76.121112) (xy 283.916482 -76.041371) (xy 283.946757 -75.964115)
			(xy 283.9841 -75.890017) (xy 284.028186 -75.819721) (xy 284.053026 -75.786488) (xy 284.059365 -75.777288)
			(xy 284.064191 -75.7555) (xy 284.059365 -75.733712) (xy 284.053026 -75.724512) (xy 284.028186 -75.691258)
			(xy 283.984104 -75.62092) (xy 283.946764 -75.546783) (xy 283.916488 -75.469491) (xy 283.893541 -75.389716)
			(xy 283.878122 -75.308151) (xy 283.870365 -75.225505) (xy 283.869892 -75.184) (xy 283.869892 -75.183746)
			(xy 283.870395 -75.1407) (xy 283.87871 -75.05501) (xy 283.895267 -74.970525) (xy 283.919911 -74.888036)
			(xy 283.952411 -74.808314) (xy 283.972 -74.76998) (xy 283.972 -74.769726) (xy 283.975683 -74.761887)
			(xy 283.97809 -74.744747) (xy 283.974649 -74.727784) (xy 283.970476 -74.720196) (xy 283.925518 -74.645774)
			(xy 283.920706 -74.638491) (xy 283.907214 -74.627433) (xy 283.890804 -74.621515) (xy 283.882084 -74.621136)
			(xy 283.325316 -74.621136) (xy 283.316582 -74.621482) (xy 283.300134 -74.627354) (xy 283.286641 -74.638445)
			(xy 283.281882 -74.645774) (xy 283.236924 -74.720196) (xy 283.232754 -74.727788) (xy 283.229294 -74.744748)
			(xy 283.231714 -74.761887) (xy 283.2354 -74.769726) (xy 283.2354 -74.76998) (xy 283.254974 -74.80832)
			(xy 283.287469 -74.888043) (xy 283.31211 -74.970531) (xy 283.328669 -75.055014) (xy 283.33699 -75.140701)
			(xy 283.337508 -75.183746) (xy 283.337508 -75.184254) (xy 283.336997 -75.227041) (xy 283.328776 -75.312218)
			(xy 283.312416 -75.396213) (xy 283.288069 -75.478249) (xy 283.255957 -75.557569) (xy 283.216379 -75.633439)
			(xy 283.169701 -75.70516) (xy 283.116352 -75.772068) (xy 283.056826 -75.833545) (xy 283.02458 -75.861672)
			(xy 283.006546 -75.900534) (xy 283.012134 -75.923394) (xy 283.030696 -75.960904) (xy 283.061496 -76.038728)
			(xy 283.084841 -76.119103) (xy 283.100524 -76.201318) (xy 283.108405 -76.284643) (xy 283.108908 -76.326492)
			(xy 283.108908 -76.327) (xy 283.108404 -76.369348) (xy 283.100353 -76.453662) (xy 283.084324 -76.536828)
			(xy 283.060463 -76.618095) (xy 283.028984 -76.696725) (xy 282.990173 -76.772006) (xy 282.944383 -76.843258)
			(xy 282.892027 -76.909834) (xy 282.833579 -76.971132) (xy 282.769569 -77.026597) (xy 282.700577 -77.075726)
			(xy 282.627227 -77.118075) (xy 282.550184 -77.153259) (xy 282.470145 -77.180961) (xy 282.387836 -77.200929)
			(xy 282.304001 -77.212982) (xy 282.2194 -77.217013) (xy 282.134799 -77.212982) (xy 282.050964 -77.200929)
			(xy 281.968655 -77.180961) (xy 281.888616 -77.153259) (xy 281.811573 -77.118075) (xy 281.738223 -77.075726)
			(xy 281.669231 -77.026597) (xy 281.605221 -76.971132) (xy 281.546773 -76.909834) (xy 281.494417 -76.843258)
			(xy 281.448627 -76.772006) (xy 281.409816 -76.696725) (xy 281.378337 -76.618095) (xy 281.354476 -76.536828)
			(xy 281.338447 -76.453662) (xy 281.330396 -76.369348) (xy 281.329892 -76.327) (xy 281.329892 -76.326746)
			(xy 281.330403 -76.283959) (xy 281.338624 -76.198782) (xy 281.354984 -76.114787) (xy 281.379331 -76.032751)
			(xy 281.411443 -75.953431) (xy 281.451021 -75.877561) (xy 281.497699 -75.80584) (xy 281.551048 -75.738932)
			(xy 281.610574 -75.677455) (xy 281.64282 -75.649328) (xy 281.660854 -75.610466) (xy 281.655266 -75.587606)
			(xy 281.636693 -75.550073) (xy 281.605879 -75.4722) (xy 281.582529 -75.391773) (xy 281.566851 -75.309506)
			(xy 281.558984 -75.226128) (xy 281.558492 -75.184254) (xy 281.558492 -75.183746) (xy 281.558988 -75.141873)
			(xy 281.566884 -75.058501) (xy 281.582572 -74.976238) (xy 281.605914 -74.895811) (xy 281.636704 -74.817931)
			(xy 281.655266 -74.780394) (xy 281.660854 -74.757534) (xy 281.64282 -74.718672) (xy 281.620917 -74.699683)
			(xy 281.579358 -74.659262) (xy 281.559762 -74.6379) (xy 281.52217 -74.621136) (xy 280.937716 -74.621136)
			(xy 280.928982 -74.621482) (xy 280.912534 -74.627354) (xy 280.899041 -74.638445) (xy 280.894282 -74.645774)
			(xy 280.849324 -74.720196) (xy 280.845154 -74.727788) (xy 280.841694 -74.744748) (xy 280.844114 -74.761887)
			(xy 280.8478 -74.769726) (xy 280.8478 -74.76998) (xy 280.867364 -74.808297) (xy 280.899843 -74.887971)
			(xy 280.92448 -74.970408) (xy 280.941043 -75.054838) (xy 280.949379 -75.140472) (xy 280.949908 -75.183492)
			(xy 280.949908 -75.184) (xy 280.949404 -75.226348) (xy 280.941353 -75.310662) (xy 280.925324 -75.393828)
			(xy 280.901463 -75.475095) (xy 280.869984 -75.553725) (xy 280.831173 -75.629006) (xy 280.785383 -75.700258)
			(xy 280.733027 -75.766834) (xy 280.674579 -75.828132) (xy 280.610569 -75.883597) (xy 280.541577 -75.932726)
			(xy 280.468227 -75.975075) (xy 280.391184 -76.010259) (xy 280.311145 -76.037961) (xy 280.228836 -76.057929)
			(xy 280.145001 -76.069982) (xy 280.0604 -76.074013) (xy 279.975799 -76.069982) (xy 279.891964 -76.057929)
			(xy 279.809655 -76.037961) (xy 279.729616 -76.010259) (xy 279.652573 -75.975075) (xy 279.579223 -75.932726)
			(xy 279.510231 -75.883597) (xy 279.446221 -75.828132) (xy 279.387773 -75.766834) (xy 279.335417 -75.700258)
			(xy 279.289627 -75.629006) (xy 279.250816 -75.553725) (xy 279.219337 -75.475095) (xy 279.195476 -75.393828)
			(xy 279.179447 -75.310662) (xy 279.171396 -75.226348) (xy 279.170892 -75.184) (xy 279.170892 -75.183492)
			(xy 279.171406 -75.140471) (xy 279.179736 -75.054834) (xy 279.196298 -74.970402) (xy 279.220936 -74.887964)
			(xy 279.253422 -74.808291) (xy 279.273 -74.76998) (xy 279.273 -74.769726) (xy 279.276683 -74.761887)
			(xy 279.27909 -74.744747) (xy 279.275649 -74.727784) (xy 279.271476 -74.720196) (xy 279.226518 -74.645774)
			(xy 279.221706 -74.638491) (xy 279.208214 -74.627433) (xy 279.191804 -74.621515) (xy 279.183084 -74.621136)
			(xy 275.412708 -74.621136) (xy 275.402688 -74.621555) (xy 275.384175 -74.629225) (xy 275.370009 -74.643398)
			(xy 275.362349 -74.661916) (xy 275.361908 -74.671936) (xy 275.361908 -74.676) (xy 275.361404 -74.718348)
			(xy 275.353353 -74.802662) (xy 275.337324 -74.885828) (xy 275.313463 -74.967095) (xy 275.281984 -75.045725)
			(xy 275.243173 -75.121006) (xy 275.197383 -75.192258) (xy 275.145027 -75.258834) (xy 275.086579 -75.320132)
			(xy 275.022569 -75.375597) (xy 274.953577 -75.424726) (xy 274.880227 -75.467075) (xy 274.803184 -75.502259)
			(xy 274.723145 -75.529961) (xy 274.640836 -75.549929) (xy 274.557001 -75.561982) (xy 274.4724 -75.566013)
			(xy 274.387799 -75.561982) (xy 274.303964 -75.549929) (xy 274.221655 -75.529961) (xy 274.141616 -75.502259)
			(xy 274.064573 -75.467075) (xy 273.991223 -75.424726) (xy 273.922231 -75.375597) (xy 273.858221 -75.320132)
			(xy 273.799773 -75.258834) (xy 273.747417 -75.192258) (xy 273.701627 -75.121006) (xy 273.662816 -75.045725)
			(xy 273.631337 -74.967095) (xy 273.607476 -74.885828) (xy 273.591447 -74.802662) (xy 273.583396 -74.718348)
			(xy 273.582892 -74.676) (xy 273.582892 -74.671936) (xy 273.582479 -74.661911) (xy 273.574815 -74.643383)
			(xy 273.560641 -74.629201) (xy 273.542117 -74.621527) (xy 273.532092 -74.621136) (xy 273.457416 -74.621136)
			(xy 273.412712 -74.64806) (xy 273.391644 -74.686323) (xy 273.343102 -74.758947) (xy 273.287676 -74.826465)
			(xy 273.2259 -74.888225) (xy 273.158368 -74.943634) (xy 273.085732 -74.992159) (xy 273.00869 -75.033331)
			(xy 272.927984 -75.066755) (xy 272.844391 -75.092109) (xy 272.758716 -75.109148) (xy 272.671783 -75.117709)
			(xy 272.628106 -75.118214) (xy 272.58516 -75.117697) (xy 272.499668 -75.109418) (xy 272.415372 -75.092935)
			(xy 272.333058 -75.068403) (xy 272.253492 -75.036049) (xy 272.177416 -74.996176) (xy 272.105537 -74.949155)
			(xy 272.038527 -74.895423) (xy 271.977009 -74.835482) (xy 271.94891 -74.803) (xy 271.910048 -74.784966)
			(xy 271.90446 -74.784966) (xy 271.860037 -74.784426) (xy 271.771632 -74.775565) (xy 271.684552 -74.757936)
			(xy 271.599663 -74.731713) (xy 271.517811 -74.697158) (xy 271.439811 -74.654616) (xy 271.40281 -74.630026)
			(xy 271.374108 -74.621136) (xy 270.59128 -74.621136) (xy 270.55802 -74.620613) (xy 270.492071 -74.611924)
			(xy 270.427821 -74.594698) (xy 270.36637 -74.569228) (xy 270.308772 -74.535953) (xy 270.256012 -74.495441)
			(xy 270.232124 -74.472292) (xy 268.472666 -72.712834) (xy 268.44951 -72.688954) (xy 268.409004 -72.63619)
			(xy 268.375735 -72.578589) (xy 268.350272 -72.517137) (xy 268.333052 -72.452887) (xy 268.324369 -72.386937)
			(xy 268.323822 -72.353678) (xy 268.323822 -72.004428) (xy 268.323221 -71.9938) (xy 268.314569 -71.974377)
			(xy 268.307058 -71.966836) (xy 268.24305 -71.909178) (xy 268.22273 -71.902574) (xy 268.212062 -71.90359)
			(xy 268.189705 -71.905663) (xy 268.144853 -71.907824) (xy 268.1224 -71.907908) (xy 268.080052 -71.907404)
			(xy 267.995738 -71.899353) (xy 267.912572 -71.883324) (xy 267.831305 -71.859463) (xy 267.752675 -71.827984)
			(xy 267.677394 -71.789173) (xy 267.606142 -71.743383) (xy 267.539566 -71.691027) (xy 267.478268 -71.632579)
			(xy 267.422803 -71.568569) (xy 267.373674 -71.499577) (xy 267.331325 -71.426227) (xy 267.296141 -71.349184)
			(xy 267.268439 -71.269145) (xy 267.248471 -71.186836) (xy 267.236418 -71.103001) (xy 267.232388 -71.0184)
			(xy 267.236418 -70.933799) (xy 267.248471 -70.849964) (xy 267.268439 -70.767655) (xy 267.296141 -70.687616)
			(xy 267.331325 -70.610573) (xy 267.373674 -70.537223) (xy 267.422803 -70.468231) (xy 267.478268 -70.404221)
			(xy 267.539566 -70.345773) (xy 267.606142 -70.293417) (xy 267.677394 -70.247627) (xy 267.752675 -70.208816)
			(xy 267.831305 -70.177337) (xy 267.912572 -70.153476) (xy 267.995738 -70.137447) (xy 268.080052 -70.129396)
			(xy 268.1224 -70.128892) (xy 268.144853 -70.128981) (xy 268.189705 -70.131138) (xy 268.212062 -70.13321)
			(xy 268.22273 -70.134226) (xy 268.24305 -70.127622) (xy 268.307058 -70.069964) (xy 268.314674 -70.062497)
			(xy 268.323343 -70.043029) (xy 268.323822 -70.032372) (xy 268.323822 -69.185028) (xy 268.323221 -69.1744)
			(xy 268.314569 -69.154977) (xy 268.307058 -69.147436) (xy 268.24305 -69.089778) (xy 268.22273 -69.083174)
			(xy 268.212062 -69.08419) (xy 268.189705 -69.086263) (xy 268.144853 -69.088424) (xy 268.1224 -69.088508)
			(xy 268.080052 -69.088004) (xy 267.995738 -69.079953) (xy 267.912572 -69.063924) (xy 267.831305 -69.040063)
			(xy 267.752675 -69.008584) (xy 267.677394 -68.969773) (xy 267.606142 -68.923983) (xy 267.539566 -68.871627)
			(xy 267.478268 -68.813179) (xy 267.422803 -68.749169) (xy 267.373674 -68.680177) (xy 267.331325 -68.606827)
			(xy 267.296141 -68.529784) (xy 267.268439 -68.449745) (xy 267.248471 -68.367436) (xy 267.236418 -68.283601)
			(xy 267.232388 -68.199) (xy 267.236418 -68.114399) (xy 267.248471 -68.030564) (xy 267.268439 -67.948255)
			(xy 267.296141 -67.868216) (xy 267.331325 -67.791173) (xy 267.373674 -67.717823) (xy 267.422803 -67.648831)
			(xy 267.478268 -67.584821) (xy 267.539566 -67.526373) (xy 267.606142 -67.474017) (xy 267.677394 -67.428227)
			(xy 267.752675 -67.389416) (xy 267.831305 -67.357937) (xy 267.912572 -67.334076) (xy 267.995738 -67.318047)
			(xy 268.080052 -67.309996) (xy 268.1224 -67.309492) (xy 268.122654 -67.309492) (xy 268.156637 -67.309823)
			(xy 268.224403 -67.315034) (xy 268.258036 -67.319906) (xy 268.258544 -67.319906) (xy 268.267848 -67.320958)
			(xy 268.286116 -67.316916) (xy 268.294104 -67.312032) (xy 268.327378 -67.289934) (xy 268.338046 -67.274694)
			(xy 268.340332 -67.265804) (xy 268.349403 -67.233462) (xy 268.374917 -67.171325) (xy 268.408407 -67.113098)
			(xy 268.449287 -67.059799) (xy 268.472666 -67.03568) (xy 272.899378 -62.608968) (xy 272.906222 -62.601569)
			(xy 272.913948 -62.582971) (xy 272.914364 -62.5729) (xy 272.914364 -57.933082) (xy 272.913937 -57.923014)
			(xy 272.906214 -57.904418) (xy 272.899378 -57.897014) (xy 272.57121 -57.568846) (xy 272.563814 -57.561993)
			(xy 272.545216 -57.554248) (xy 272.535142 -57.55386) (xy 262.008874 -57.55386) (xy 261.998807 -57.554289)
			(xy 261.980215 -57.562017) (xy 261.972806 -57.568846) (xy 261.036816 -58.504836) (xy 261.029973 -58.512236)
			(xy 261.02225 -58.530834) (xy 261.02183 -58.540904) (xy 261.02183 -61.764361) (xy 271.024092 -61.764361)
			(xy 271.024092 -61.679639) (xy 271.032145 -61.595302) (xy 271.048179 -61.512112) (xy 271.072047 -61.430822)
			(xy 271.103535 -61.35217) (xy 271.142357 -61.276867) (xy 271.18816 -61.205595) (xy 271.240531 -61.138999)
			(xy 271.298996 -61.077684) (xy 271.363024 -61.022203) (xy 271.432036 -60.97306) (xy 271.505406 -60.9307)
			(xy 271.582471 -60.895505) (xy 271.662533 -60.867796) (xy 271.744866 -60.847822) (xy 271.828725 -60.835765)
			(xy 271.91335 -60.831734) (xy 271.997975 -60.835765) (xy 272.081834 -60.847822) (xy 272.164167 -60.867796)
			(xy 272.244229 -60.895505) (xy 272.321294 -60.9307) (xy 272.394664 -60.97306) (xy 272.463676 -61.022203)
			(xy 272.527704 -61.077684) (xy 272.586169 -61.138999) (xy 272.63854 -61.205595) (xy 272.684343 -61.276867)
			(xy 272.723165 -61.35217) (xy 272.754653 -61.430822) (xy 272.778521 -61.512112) (xy 272.794555 -61.595302)
			(xy 272.802608 -61.679639) (xy 272.803112 -61.722) (xy 272.802608 -61.764361) (xy 272.794555 -61.848698)
			(xy 272.778521 -61.931888) (xy 272.754653 -62.013178) (xy 272.723165 -62.09183) (xy 272.684343 -62.167133)
			(xy 272.63854 -62.238405) (xy 272.586169 -62.305001) (xy 272.527704 -62.366316) (xy 272.463676 -62.421797)
			(xy 272.394664 -62.47094) (xy 272.321294 -62.5133) (xy 272.244229 -62.548495) (xy 272.164167 -62.576204)
			(xy 272.081834 -62.596178) (xy 271.997975 -62.608235) (xy 271.91335 -62.612267) (xy 271.828725 -62.608235)
			(xy 271.744866 -62.596178) (xy 271.662533 -62.576204) (xy 271.582471 -62.548495) (xy 271.505406 -62.5133)
			(xy 271.432036 -62.47094) (xy 271.363024 -62.421797) (xy 271.298996 -62.366316) (xy 271.240531 -62.305001)
			(xy 271.18816 -62.238405) (xy 271.142357 -62.167133) (xy 271.103535 -62.09183) (xy 271.072047 -62.013178)
			(xy 271.048179 -61.931888) (xy 271.032145 -61.848698) (xy 271.024092 -61.764361) (xy 261.02183 -61.764361)
			(xy 261.02183 -64.558361) (xy 261.838182 -64.558361) (xy 261.838182 -64.473639) (xy 261.846235 -64.389302)
			(xy 261.862269 -64.306112) (xy 261.886137 -64.224822) (xy 261.917625 -64.14617) (xy 261.956447 -64.070867)
			(xy 262.00225 -63.999595) (xy 262.054621 -63.932999) (xy 262.113086 -63.871684) (xy 262.177114 -63.816203)
			(xy 262.246126 -63.76706) (xy 262.319496 -63.7247) (xy 262.396561 -63.689505) (xy 262.476623 -63.661796)
			(xy 262.558956 -63.641822) (xy 262.642815 -63.629765) (xy 262.72744 -63.625734) (xy 262.812065 -63.629765)
			(xy 262.895924 -63.641822) (xy 262.978257 -63.661796) (xy 263.058319 -63.689505) (xy 263.135384 -63.7247)
			(xy 263.208754 -63.76706) (xy 263.277766 -63.816203) (xy 263.341794 -63.871684) (xy 263.400259 -63.932999)
			(xy 263.45263 -63.999595) (xy 263.498433 -64.070867) (xy 263.537255 -64.14617) (xy 263.568743 -64.224822)
			(xy 263.592611 -64.306112) (xy 263.608645 -64.389302) (xy 263.616698 -64.473639) (xy 263.617202 -64.516)
			(xy 263.616698 -64.558361) (xy 263.608645 -64.642698) (xy 263.592611 -64.725888) (xy 263.568743 -64.807178)
			(xy 263.537255 -64.88583) (xy 263.498433 -64.961133) (xy 263.45263 -65.032405) (xy 263.400259 -65.099001)
			(xy 263.341794 -65.160316) (xy 263.277766 -65.215797) (xy 263.208754 -65.26494) (xy 263.135384 -65.3073)
			(xy 263.058319 -65.342495) (xy 262.978257 -65.370204) (xy 262.895924 -65.390178) (xy 262.812065 -65.402235)
			(xy 262.72744 -65.406267) (xy 262.642815 -65.402235) (xy 262.558956 -65.390178) (xy 262.476623 -65.370204)
			(xy 262.396561 -65.342495) (xy 262.319496 -65.3073) (xy 262.246126 -65.26494) (xy 262.177114 -65.215797)
			(xy 262.113086 -65.160316) (xy 262.054621 -65.099001) (xy 262.00225 -65.032405) (xy 261.956447 -64.961133)
			(xy 261.917625 -64.88583) (xy 261.886137 -64.807178) (xy 261.862269 -64.725888) (xy 261.846235 -64.642698)
			(xy 261.838182 -64.558361) (xy 261.02183 -64.558361) (xy 261.02183 -69.34708) (xy 263.981692 -69.34708)
			(xy 263.982196 -69.304732) (xy 263.990247 -69.220418) (xy 264.006276 -69.137252) (xy 264.030137 -69.055985)
			(xy 264.061616 -68.977355) (xy 264.100427 -68.902074) (xy 264.146217 -68.830822) (xy 264.198573 -68.764246)
			(xy 264.257021 -68.702948) (xy 264.321031 -68.647483) (xy 264.390023 -68.598354) (xy 264.463373 -68.556005)
			(xy 264.540416 -68.520821) (xy 264.620455 -68.493119) (xy 264.702764 -68.473151) (xy 264.786599 -68.461098)
			(xy 264.8712 -68.457068) (xy 264.955801 -68.461098) (xy 265.039636 -68.473151) (xy 265.121945 -68.493119)
			(xy 265.201984 -68.520821) (xy 265.279027 -68.556005) (xy 265.352377 -68.598354) (xy 265.421369 -68.647483)
			(xy 265.485379 -68.702948) (xy 265.543827 -68.764246) (xy 265.596183 -68.830822) (xy 265.641973 -68.902074)
			(xy 265.680784 -68.977355) (xy 265.712263 -69.055985) (xy 265.736124 -69.137252) (xy 265.752153 -69.220418)
			(xy 265.760204 -69.304732) (xy 265.760708 -69.34708) (xy 265.760708 -69.347842) (xy 265.760124 -69.39309)
			(xy 265.750905 -69.483115) (xy 265.732585 -69.571738) (xy 265.705356 -69.658041) (xy 265.669499 -69.74113)
			(xy 265.647932 -69.780912) (xy 265.643026 -69.790878) (xy 265.641461 -69.813015) (xy 265.644884 -69.823584)
			(xy 265.676126 -69.906896) (xy 265.691874 -69.92239) (xy 265.702542 -69.9262) (xy 265.741999 -69.940786)
			(xy 265.818247 -69.976332) (xy 265.8908 -70.018917) (xy 265.959008 -70.068161) (xy 266.022264 -70.123623)
			(xy 266.080001 -70.184809) (xy 266.131705 -70.251172) (xy 266.176914 -70.322119) (xy 266.215223 -70.397017)
			(xy 266.246292 -70.475197) (xy 266.269842 -70.55596) (xy 266.285663 -70.638586) (xy 266.293613 -70.722337)
			(xy 266.294108 -70.7644) (xy 266.293604 -70.806748) (xy 266.285553 -70.891062) (xy 266.269524 -70.974228)
			(xy 266.245663 -71.055495) (xy 266.214184 -71.134125) (xy 266.175373 -71.209406) (xy 266.129583 -71.280658)
			(xy 266.077227 -71.347234) (xy 266.018779 -71.408532) (xy 265.954769 -71.463997) (xy 265.885777 -71.513126)
			(xy 265.812427 -71.555475) (xy 265.735384 -71.590659) (xy 265.655345 -71.618361) (xy 265.573036 -71.638329)
			(xy 265.489201 -71.650382) (xy 265.4046 -71.654413) (xy 265.319999 -71.650382) (xy 265.236164 -71.638329)
			(xy 265.153855 -71.618361) (xy 265.073816 -71.590659) (xy 264.996773 -71.555475) (xy 264.923423 -71.513126)
			(xy 264.854431 -71.463997) (xy 264.790421 -71.408532) (xy 264.731973 -71.347234) (xy 264.679617 -71.280658)
			(xy 264.633827 -71.209406) (xy 264.595016 -71.134125) (xy 264.563537 -71.055495) (xy 264.539676 -70.974228)
			(xy 264.523647 -70.891062) (xy 264.515596 -70.806748) (xy 264.515092 -70.7644) (xy 264.515092 -70.763638)
			(xy 264.515667 -70.71839) (xy 264.524889 -70.628364) (xy 264.54321 -70.539741) (xy 264.570441 -70.453439)
			(xy 264.6063 -70.37035) (xy 264.627868 -70.330568) (xy 264.632726 -70.320583) (xy 264.634321 -70.298463)
			(xy 264.630916 -70.287896) (xy 264.599674 -70.204584) (xy 264.583926 -70.18909) (xy 264.573258 -70.18528)
			(xy 264.533794 -70.170712) (xy 264.457545 -70.135164) (xy 264.384993 -70.092578) (xy 264.316784 -70.043333)
			(xy 264.253528 -69.987869) (xy 264.195791 -69.926681) (xy 264.144087 -69.860317) (xy 264.098879 -69.789368)
			(xy 264.06057 -69.714469) (xy 264.029503 -69.636288) (xy 264.005954 -69.555523) (xy 263.990135 -69.472895)
			(xy 263.982186 -69.389144) (xy 263.981692 -69.34708) (xy 261.02183 -69.34708) (xy 261.02183 -74.781607)
			(xy 262.191242 -74.781607) (xy 262.191242 -74.696885) (xy 262.199295 -74.612548) (xy 262.215329 -74.529358)
			(xy 262.239197 -74.448068) (xy 262.270685 -74.369416) (xy 262.309507 -74.294113) (xy 262.35531 -74.222841)
			(xy 262.407681 -74.156245) (xy 262.466146 -74.09493) (xy 262.530174 -74.039449) (xy 262.599186 -73.990306)
			(xy 262.672556 -73.947946) (xy 262.749621 -73.912751) (xy 262.829683 -73.885042) (xy 262.912016 -73.865068)
			(xy 262.995875 -73.853011) (xy 263.0805 -73.84898) (xy 263.165125 -73.853011) (xy 263.248984 -73.865068)
			(xy 263.331317 -73.885042) (xy 263.341597 -73.8886) (xy 266.368788 -73.8886) (xy 266.372818 -73.803999)
			(xy 266.384871 -73.720164) (xy 266.404839 -73.637855) (xy 266.432541 -73.557816) (xy 266.467725 -73.480773)
			(xy 266.510074 -73.407423) (xy 266.559203 -73.338431) (xy 266.614668 -73.274421) (xy 266.675966 -73.215973)
			(xy 266.742542 -73.163617) (xy 266.813794 -73.117827) (xy 266.889075 -73.079016) (xy 266.967705 -73.047537)
			(xy 267.048972 -73.023676) (xy 267.132138 -73.007647) (xy 267.216452 -72.999596) (xy 267.2588 -72.999092)
			(xy 267.259562 -72.999092) (xy 267.297909 -72.999501) (xy 267.374317 -73.006133) (xy 267.449868 -73.019325)
			(xy 267.524002 -73.038978) (xy 267.596166 -73.064947) (xy 267.631164 -73.080626) (xy 267.641437 -73.084766)
			(xy 267.663563 -73.084766) (xy 267.673836 -73.080626) (xy 267.708833 -73.064947) (xy 267.781003 -73.039)
			(xy 267.855138 -73.019357) (xy 267.930687 -73.006163) (xy 268.007092 -72.999518) (xy 268.045438 -72.999092)
			(xy 268.0462 -72.999092) (xy 268.088548 -72.999596) (xy 268.172862 -73.007647) (xy 268.256028 -73.023676)
			(xy 268.337295 -73.047537) (xy 268.415925 -73.079016) (xy 268.491206 -73.117827) (xy 268.562458 -73.163617)
			(xy 268.629034 -73.215973) (xy 268.690332 -73.274421) (xy 268.745797 -73.338431) (xy 268.794926 -73.407423)
			(xy 268.837275 -73.480773) (xy 268.872459 -73.557816) (xy 268.900161 -73.637855) (xy 268.920129 -73.720164)
			(xy 268.932182 -73.803999) (xy 268.936213 -73.8886) (xy 268.932182 -73.973201) (xy 268.920129 -74.057036)
			(xy 268.900161 -74.139345) (xy 268.872459 -74.219384) (xy 268.837275 -74.296427) (xy 268.794926 -74.369777)
			(xy 268.745797 -74.438769) (xy 268.690332 -74.502779) (xy 268.629034 -74.561227) (xy 268.562458 -74.613583)
			(xy 268.491206 -74.659373) (xy 268.415925 -74.698184) (xy 268.337295 -74.729663) (xy 268.256028 -74.753524)
			(xy 268.172862 -74.769553) (xy 268.088548 -74.777604) (xy 268.0462 -74.778108) (xy 268.045438 -74.778108)
			(xy 268.007091 -74.777699) (xy 267.930683 -74.771067) (xy 267.855132 -74.757875) (xy 267.780998 -74.738222)
			(xy 267.708834 -74.712253) (xy 267.673836 -74.696574) (xy 267.663563 -74.692434) (xy 267.641437 -74.692434)
			(xy 267.631164 -74.696574) (xy 267.596167 -74.712253) (xy 267.523997 -74.7382) (xy 267.449862 -74.757843)
			(xy 267.374313 -74.771037) (xy 267.297908 -74.777682) (xy 267.259562 -74.778108) (xy 267.2588 -74.778108)
			(xy 267.216452 -74.777604) (xy 267.132138 -74.769553) (xy 267.048972 -74.753524) (xy 266.967705 -74.729663)
			(xy 266.889075 -74.698184) (xy 266.813794 -74.659373) (xy 266.742542 -74.613583) (xy 266.675966 -74.561227)
			(xy 266.614668 -74.502779) (xy 266.559203 -74.438769) (xy 266.510074 -74.369777) (xy 266.467725 -74.296427)
			(xy 266.432541 -74.219384) (xy 266.404839 -74.139345) (xy 266.384871 -74.057036) (xy 266.372818 -73.973201)
			(xy 266.368788 -73.8886) (xy 263.341597 -73.8886) (xy 263.411379 -73.912751) (xy 263.488444 -73.947946)
			(xy 263.561814 -73.990306) (xy 263.630826 -74.039449) (xy 263.694854 -74.09493) (xy 263.753319 -74.156245)
			(xy 263.80569 -74.222841) (xy 263.851493 -74.294113) (xy 263.890315 -74.369416) (xy 263.921803 -74.448068)
			(xy 263.945671 -74.529358) (xy 263.961705 -74.612548) (xy 263.969758 -74.696885) (xy 263.970262 -74.739246)
			(xy 263.969758 -74.781607) (xy 263.961705 -74.865944) (xy 263.945671 -74.949134) (xy 263.921803 -75.030424)
			(xy 263.890315 -75.109076) (xy 263.851493 -75.184379) (xy 263.80569 -75.255651) (xy 263.753319 -75.322247)
			(xy 263.694854 -75.383562) (xy 263.630826 -75.439043) (xy 263.561814 -75.488186) (xy 263.488444 -75.530546)
			(xy 263.411379 -75.565741) (xy 263.331317 -75.59345) (xy 263.248984 -75.613424) (xy 263.165125 -75.625481)
			(xy 263.0805 -75.629513) (xy 262.995875 -75.625481) (xy 262.912016 -75.613424) (xy 262.829683 -75.59345)
			(xy 262.749621 -75.565741) (xy 262.672556 -75.530546) (xy 262.599186 -75.488186) (xy 262.530174 -75.439043)
			(xy 262.466146 -75.383562) (xy 262.407681 -75.322247) (xy 262.35531 -75.255651) (xy 262.309507 -75.184379)
			(xy 262.270685 -75.109076) (xy 262.239197 -75.030424) (xy 262.215329 -74.949134) (xy 262.199295 -74.865944)
			(xy 262.191242 -74.781607) (xy 261.02183 -74.781607) (xy 261.02183 -76.296266) (xy 261.022237 -76.305887)
			(xy 261.029318 -76.323778) (xy 261.042497 -76.337799) (xy 261.05104 -76.34224) (xy 261.088786 -76.36052)
			(xy 261.160992 -76.403192) (xy 261.228862 -76.452471) (xy 261.291791 -76.507921) (xy 261.34922 -76.569048)
			(xy 261.400641 -76.635309) (xy 261.445595 -76.706117) (xy 261.483684 -76.780843) (xy 261.51457 -76.858822)
			(xy 261.537978 -76.939362) (xy 261.5537 -77.021749) (xy 261.561597 -77.105249) (xy 261.561598 -77.189122)
			(xy 261.553704 -77.272623) (xy 261.537985 -77.355009) (xy 261.514579 -77.435551) (xy 261.500936 -77.47)
			(xy 269.010388 -77.47) (xy 269.014418 -77.385399) (xy 269.026471 -77.301564) (xy 269.046439 -77.219255)
			(xy 269.074141 -77.139216) (xy 269.109325 -77.062173) (xy 269.151674 -76.988823) (xy 269.200803 -76.919831)
			(xy 269.256268 -76.855821) (xy 269.317566 -76.797373) (xy 269.384142 -76.745017) (xy 269.455394 -76.699227)
			(xy 269.530675 -76.660416) (xy 269.609305 -76.628937) (xy 269.690572 -76.605076) (xy 269.773738 -76.589047)
			(xy 269.858052 -76.580996) (xy 269.9004 -76.580492) (xy 269.900908 -76.580492) (xy 269.939418 -76.580899)
			(xy 270.01615 -76.587559) (xy 270.092019 -76.600829) (xy 270.166456 -76.62061) (xy 270.238904 -76.646752)
			(xy 270.274034 -76.662534) (xy 270.284452 -76.666794) (xy 270.306935 -76.666662) (xy 270.327201 -76.656924)
			(xy 270.33474 -76.648564) (xy 270.362818 -76.614935) (xy 270.42463 -76.552841) (xy 270.492244 -76.497121)
			(xy 270.565006 -76.448316) (xy 270.642211 -76.406896) (xy 270.723114 -76.373264) (xy 270.806929 -76.347744)
			(xy 270.892847 -76.330583) (xy 270.980035 -76.321949) (xy 271.023842 -76.321412) (xy 271.02435 -76.321412)
			(xy 271.063451 -76.321826) (xy 271.141349 -76.328699) (xy 271.218343 -76.342386) (xy 271.293838 -76.362783)
			(xy 271.367249 -76.389732) (xy 271.40281 -76.405994) (xy 271.413197 -76.410229) (xy 271.435603 -76.410229)
			(xy 271.44599 -76.405994) (xy 271.481558 -76.38975) (xy 271.554972 -76.362819) (xy 271.630466 -76.342429)
			(xy 271.707456 -76.328737) (xy 271.785351 -76.32185) (xy 271.82445 -76.321412) (xy 271.866802 -76.321858)
			(xy 271.951122 -76.329905) (xy 272.034296 -76.345931) (xy 272.115569 -76.369791) (xy 272.194206 -76.401269)
			(xy 272.269495 -76.440079) (xy 272.340754 -76.485871) (xy 272.407337 -76.538229) (xy 272.468641 -76.596679)
			(xy 272.524112 -76.660692) (xy 272.573246 -76.729688) (xy 272.615599 -76.803043) (xy 272.650788 -76.880091)
			(xy 272.678492 -76.960136) (xy 272.698463 -77.042451) (xy 272.710518 -77.126293) (xy 272.714548 -77.2109)
			(xy 272.710518 -77.295507) (xy 272.698463 -77.379349) (xy 272.678492 -77.461664) (xy 272.660135 -77.514704)
			(xy 286.155892 -77.514704) (xy 286.155892 -77.514196) (xy 286.156396 -77.471848) (xy 286.164447 -77.387534)
			(xy 286.180476 -77.304368) (xy 286.204337 -77.223101) (xy 286.235816 -77.144471) (xy 286.274627 -77.06919)
			(xy 286.320417 -76.997938) (xy 286.372773 -76.931362) (xy 286.431221 -76.870064) (xy 286.495231 -76.814599)
			(xy 286.564223 -76.76547) (xy 286.637573 -76.723121) (xy 286.714616 -76.687937) (xy 286.794655 -76.660235)
			(xy 286.876964 -76.640267) (xy 286.960799 -76.628214) (xy 287.0454 -76.624184) (xy 287.130001 -76.628214)
			(xy 287.213836 -76.640267) (xy 287.296145 -76.660235) (xy 287.376184 -76.687937) (xy 287.453227 -76.723121)
			(xy 287.526577 -76.76547) (xy 287.595569 -76.814599) (xy 287.659579 -76.870064) (xy 287.718027 -76.931362)
			(xy 287.770383 -76.997938) (xy 287.816173 -77.06919) (xy 287.854984 -77.144471) (xy 287.886463 -77.223101)
			(xy 287.910324 -77.304368) (xy 287.926353 -77.387534) (xy 287.934404 -77.471848) (xy 287.934908 -77.514196)
			(xy 287.934908 -77.514958) (xy 287.934417 -77.553255) (xy 289.077142 -77.553255) (xy 289.077142 -77.468533)
			(xy 289.085195 -77.384196) (xy 289.101229 -77.301006) (xy 289.125097 -77.219716) (xy 289.156585 -77.141064)
			(xy 289.195407 -77.065761) (xy 289.24121 -76.994489) (xy 289.293581 -76.927893) (xy 289.352046 -76.866578)
			(xy 289.416074 -76.811097) (xy 289.485086 -76.761954) (xy 289.558456 -76.719594) (xy 289.635521 -76.684399)
			(xy 289.715583 -76.65669) (xy 289.797916 -76.636716) (xy 289.881775 -76.624659) (xy 289.9664 -76.620628)
			(xy 290.051025 -76.624659) (xy 290.134884 -76.636716) (xy 290.217217 -76.65669) (xy 290.297279 -76.684399)
			(xy 290.374344 -76.719594) (xy 290.447714 -76.761954) (xy 290.516726 -76.811097) (xy 290.580754 -76.866578)
			(xy 290.639219 -76.927893) (xy 290.69159 -76.994489) (xy 290.697934 -77.004361) (xy 293.023794 -77.004361)
			(xy 293.023794 -76.919639) (xy 293.031847 -76.835302) (xy 293.047881 -76.752112) (xy 293.071749 -76.670822)
			(xy 293.103237 -76.59217) (xy 293.142059 -76.516867) (xy 293.187862 -76.445595) (xy 293.240233 -76.378999)
			(xy 293.298698 -76.317684) (xy 293.362726 -76.262203) (xy 293.431738 -76.21306) (xy 293.505108 -76.1707)
			(xy 293.582173 -76.135505) (xy 293.662235 -76.107796) (xy 293.744568 -76.087822) (xy 293.828427 -76.075765)
			(xy 293.913052 -76.071734) (xy 293.997677 -76.075765) (xy 294.081536 -76.087822) (xy 294.163869 -76.107796)
			(xy 294.243931 -76.135505) (xy 294.320996 -76.1707) (xy 294.394366 -76.21306) (xy 294.463378 -76.262203)
			(xy 294.527406 -76.317684) (xy 294.585871 -76.378999) (xy 294.638242 -76.445595) (xy 294.684045 -76.516867)
			(xy 294.722867 -76.59217) (xy 294.754355 -76.670822) (xy 294.778223 -76.752112) (xy 294.794257 -76.835302)
			(xy 294.80231 -76.919639) (xy 294.802814 -76.962) (xy 294.80231 -77.004361) (xy 294.794257 -77.088698)
			(xy 294.778223 -77.171888) (xy 294.754355 -77.253178) (xy 294.722867 -77.33183) (xy 294.684045 -77.407133)
			(xy 294.638242 -77.478405) (xy 294.585871 -77.545001) (xy 294.527406 -77.606316) (xy 294.463378 -77.661797)
			(xy 294.394366 -77.71094) (xy 294.320996 -77.7533) (xy 294.243931 -77.788495) (xy 294.163869 -77.816204)
			(xy 294.081536 -77.836178) (xy 293.997677 -77.848235) (xy 293.913052 -77.852267) (xy 293.828427 -77.848235)
			(xy 293.744568 -77.836178) (xy 293.662235 -77.816204) (xy 293.582173 -77.788495) (xy 293.505108 -77.7533)
			(xy 293.431738 -77.71094) (xy 293.362726 -77.661797) (xy 293.298698 -77.606316) (xy 293.240233 -77.545001)
			(xy 293.187862 -77.478405) (xy 293.142059 -77.407133) (xy 293.103237 -77.33183) (xy 293.071749 -77.253178)
			(xy 293.047881 -77.171888) (xy 293.031847 -77.088698) (xy 293.023794 -77.004361) (xy 290.697934 -77.004361)
			(xy 290.737393 -77.065761) (xy 290.776215 -77.141064) (xy 290.807703 -77.219716) (xy 290.831571 -77.301006)
			(xy 290.847605 -77.384196) (xy 290.855658 -77.468533) (xy 290.856162 -77.510894) (xy 290.855658 -77.553255)
			(xy 290.847605 -77.637592) (xy 290.831571 -77.720782) (xy 290.807703 -77.802072) (xy 290.776215 -77.880724)
			(xy 290.737393 -77.956027) (xy 290.69159 -78.027299) (xy 290.639219 -78.093895) (xy 290.580754 -78.15521)
			(xy 290.516726 -78.210691) (xy 290.447714 -78.259834) (xy 290.374344 -78.302194) (xy 290.297279 -78.337389)
			(xy 290.217217 -78.365098) (xy 290.134884 -78.385072) (xy 290.051025 -78.397129) (xy 289.9664 -78.401161)
			(xy 289.881775 -78.397129) (xy 289.797916 -78.385072) (xy 289.715583 -78.365098) (xy 289.635521 -78.337389)
			(xy 289.558456 -78.302194) (xy 289.485086 -78.259834) (xy 289.416074 -78.210691) (xy 289.352046 -78.15521)
			(xy 289.293581 -78.093895) (xy 289.24121 -78.027299) (xy 289.195407 -77.956027) (xy 289.156585 -77.880724)
			(xy 289.125097 -77.802072) (xy 289.101229 -77.720782) (xy 289.085195 -77.637592) (xy 289.077142 -77.553255)
			(xy 287.934417 -77.553255) (xy 287.934351 -77.558361) (xy 287.925829 -77.644749) (xy 287.91789 -77.687424)
			(xy 287.916493 -77.69635) (xy 287.919364 -77.714177) (xy 287.923478 -77.722222) (xy 287.94557 -77.76238)
			(xy 287.982316 -77.846351) (xy 288.010229 -77.933657) (xy 288.029012 -78.023372) (xy 288.038465 -78.114542)
			(xy 288.039048 -78.160372) (xy 288.039048 -78.16088) (xy 288.038544 -78.203228) (xy 288.030493 -78.287542)
			(xy 288.014464 -78.370708) (xy 287.990603 -78.451975) (xy 287.959124 -78.530605) (xy 287.920313 -78.605886)
			(xy 287.874523 -78.677138) (xy 287.822167 -78.743714) (xy 287.763719 -78.805012) (xy 287.699709 -78.860477)
			(xy 287.630717 -78.909606) (xy 287.557367 -78.951955) (xy 287.480324 -78.987139) (xy 287.400285 -79.014841)
			(xy 287.317976 -79.034809) (xy 287.234141 -79.046862) (xy 287.14954 -79.050893) (xy 287.064939 -79.046862)
			(xy 286.981104 -79.034809) (xy 286.898795 -79.014841) (xy 286.818756 -78.987139) (xy 286.741713 -78.951955)
			(xy 286.668363 -78.909606) (xy 286.599371 -78.860477) (xy 286.535361 -78.805012) (xy 286.476913 -78.743714)
			(xy 286.424557 -78.677138) (xy 286.378767 -78.605886) (xy 286.339956 -78.530605) (xy 286.308477 -78.451975)
			(xy 286.284616 -78.370708) (xy 286.268587 -78.287542) (xy 286.260536 -78.203228) (xy 286.260032 -78.16088)
			(xy 286.260032 -78.160118) (xy 286.260584 -78.116715) (xy 286.269109 -78.030326) (xy 286.27705 -77.987652)
			(xy 286.278415 -77.978723) (xy 286.275567 -77.960899) (xy 286.271462 -77.952854) (xy 286.249365 -77.912699)
			(xy 286.212618 -77.828727) (xy 286.184706 -77.74142) (xy 286.165925 -77.651705) (xy 286.156474 -77.560534)
			(xy 286.155892 -77.514704) (xy 272.660135 -77.514704) (xy 272.650788 -77.541709) (xy 272.615599 -77.618757)
			(xy 272.573246 -77.692112) (xy 272.524112 -77.761108) (xy 272.468641 -77.825121) (xy 272.407337 -77.883571)
			(xy 272.340754 -77.935929) (xy 272.269495 -77.981721) (xy 272.194206 -78.020531) (xy 272.115569 -78.052009)
			(xy 272.034296 -78.075869) (xy 271.951122 -78.091895) (xy 271.866802 -78.099942) (xy 271.82445 -78.100428)
			(xy 271.785349 -78.10002) (xy 271.70745 -78.093147) (xy 271.630456 -78.079458) (xy 271.554962 -78.05906)
			(xy 271.481551 -78.032109) (xy 271.44599 -78.015846) (xy 271.435603 -78.011611) (xy 271.413197 -78.011611)
			(xy 271.40281 -78.015846) (xy 271.367243 -78.032093) (xy 271.293828 -78.059023) (xy 271.218335 -78.079412)
			(xy 271.141344 -78.093103) (xy 271.063449 -78.09999) (xy 271.02435 -78.100428) (xy 271.023842 -78.100428)
			(xy 270.985332 -78.1) (xy 270.908601 -78.093344) (xy 270.832733 -78.080079) (xy 270.758295 -78.060303)
			(xy 270.685847 -78.034166) (xy 270.650716 -78.018386) (xy 270.640284 -78.014167) (xy 270.617811 -78.01428)
			(xy 270.597549 -78.024002) (xy 270.59001 -78.032356) (xy 270.561884 -78.065944) (xy 270.500081 -78.128042)
			(xy 270.432474 -78.183766) (xy 270.359719 -78.232576) (xy 270.282519 -78.274001) (xy 270.201622 -78.307638)
			(xy 270.117812 -78.333163) (xy 270.031898 -78.350329) (xy 269.944714 -78.358969) (xy 269.900908 -78.359508)
			(xy 269.9004 -78.359508) (xy 269.858052 -78.359004) (xy 269.773738 -78.350953) (xy 269.690572 -78.334924)
			(xy 269.609305 -78.311063) (xy 269.530675 -78.279584) (xy 269.455394 -78.240773) (xy 269.384142 -78.194983)
			(xy 269.317566 -78.142627) (xy 269.256268 -78.084179) (xy 269.200803 -78.020169) (xy 269.151674 -77.951177)
			(xy 269.109325 -77.877827) (xy 269.074141 -77.800784) (xy 269.046439 -77.720745) (xy 269.026471 -77.638436)
			(xy 269.014418 -77.554601) (xy 269.010388 -77.47) (xy 261.500936 -77.47) (xy 261.483696 -77.513531)
			(xy 261.445609 -77.588257) (xy 261.400657 -77.659067) (xy 261.349239 -77.72533) (xy 261.291811 -77.786459)
			(xy 261.228884 -77.841911) (xy 261.161017 -77.891192) (xy 261.088811 -77.933866) (xy 261.05104 -77.952092)
			(xy 261.042503 -77.956549) (xy 261.029312 -77.970559) (xy 261.02221 -77.988445) (xy 261.02183 -77.998066)
			(xy 261.02183 -79.461106) (xy 289.076892 -79.461106) (xy 289.077396 -79.418758) (xy 289.085447 -79.334444)
			(xy 289.101476 -79.251278) (xy 289.125337 -79.170011) (xy 289.156816 -79.091381) (xy 289.195627 -79.0161)
			(xy 289.241417 -78.944848) (xy 289.293773 -78.878272) (xy 289.352221 -78.816974) (xy 289.416231 -78.761509)
			(xy 289.485223 -78.71238) (xy 289.558573 -78.670031) (xy 289.635616 -78.634847) (xy 289.715655 -78.607145)
			(xy 289.797964 -78.587177) (xy 289.881799 -78.575124) (xy 289.9664 -78.571094) (xy 290.051001 -78.575124)
			(xy 290.134836 -78.587177) (xy 290.217145 -78.607145) (xy 290.297184 -78.634847) (xy 290.374227 -78.670031)
			(xy 290.447577 -78.71238) (xy 290.516569 -78.761509) (xy 290.580579 -78.816974) (xy 290.639027 -78.878272)
			(xy 290.691383 -78.944848) (xy 290.737173 -79.0161) (xy 290.775984 -79.091381) (xy 290.807463 -79.170011)
			(xy 290.831324 -79.251278) (xy 290.841304 -79.303061) (xy 293.191942 -79.303061) (xy 293.191942 -79.218339)
			(xy 293.199995 -79.134002) (xy 293.216029 -79.050812) (xy 293.239897 -78.969522) (xy 293.271385 -78.89087)
			(xy 293.310207 -78.815567) (xy 293.35601 -78.744295) (xy 293.408381 -78.677699) (xy 293.466846 -78.616384)
			(xy 293.530874 -78.560903) (xy 293.599886 -78.51176) (xy 293.673256 -78.4694) (xy 293.750321 -78.434205)
			(xy 293.830383 -78.406496) (xy 293.912716 -78.386522) (xy 293.996575 -78.374465) (xy 294.0812 -78.370434)
			(xy 294.165825 -78.374465) (xy 294.249684 -78.386522) (xy 294.332017 -78.406496) (xy 294.412079 -78.434205)
			(xy 294.489144 -78.4694) (xy 294.562514 -78.51176) (xy 294.631526 -78.560903) (xy 294.695554 -78.616384)
			(xy 294.754019 -78.677699) (xy 294.80639 -78.744295) (xy 294.852193 -78.815567) (xy 294.891015 -78.89087)
			(xy 294.922503 -78.969522) (xy 294.946371 -79.050812) (xy 294.962405 -79.134002) (xy 294.970458 -79.218339)
			(xy 294.970962 -79.2607) (xy 294.970458 -79.303061) (xy 294.962405 -79.387398) (xy 294.946371 -79.470588)
			(xy 294.922503 -79.551878) (xy 294.891015 -79.63053) (xy 294.852193 -79.705833) (xy 294.80639 -79.777105)
			(xy 294.759416 -79.836838) (xy 303.180186 -79.836838) (xy 303.182815 -79.753015) (xy 303.19332 -79.66981)
			(xy 303.211608 -79.587964) (xy 303.237517 -79.508202) (xy 303.270817 -79.431231) (xy 303.311212 -79.357736)
			(xy 303.358343 -79.288368) (xy 303.411794 -79.223743) (xy 303.471088 -79.164435) (xy 303.5357 -79.110969)
			(xy 303.605057 -79.063821) (xy 303.678543 -79.023409) (xy 303.755505 -78.990091) (xy 303.835261 -78.964164)
			(xy 303.917103 -78.945856) (xy 304.000305 -78.935331) (xy 304.084128 -78.932683) (xy 304.167828 -78.937934)
			(xy 304.250663 -78.951038) (xy 304.331897 -78.971879) (xy 304.410809 -79.000271) (xy 304.4867 -79.035964)
			(xy 304.558894 -79.078639) (xy 304.626753 -79.127919) (xy 304.689673 -79.183366) (xy 304.747097 -79.244487)
			(xy 304.798514 -79.310741) (xy 304.843468 -79.38154) (xy 304.881561 -79.456254) (xy 304.912453 -79.534222)
			(xy 304.935872 -79.61475) (xy 304.951609 -79.697125) (xy 304.959525 -79.780616) (xy 304.96002 -79.822548)
			(xy 304.96002 -79.823056) (xy 304.959492 -79.865875) (xy 304.951224 -79.951114) (xy 304.94351 -79.993236)
			(xy 304.941789 -80.004521) (xy 304.94747 -80.026607) (xy 304.954432 -80.035654) (xy 305.012852 -80.104996)
			(xy 305.03368 -80.114394) (xy 305.044856 -80.11414) (xy 305.045872 -80.11414) (xy 305.063398 -80.11414)
			(xy 305.105333 -80.11462) (xy 305.18883 -80.122512) (xy 305.271215 -80.138226) (xy 305.351755 -80.161624)
			(xy 305.429736 -80.192496) (xy 305.504465 -80.23057) (xy 305.57528 -80.275507) (xy 305.641553 -80.326908)
			(xy 305.702694 -80.384318) (xy 305.758161 -80.447227) (xy 305.807463 -80.515076) (xy 305.85016 -80.587263)
			(xy 305.885876 -80.663148) (xy 305.914292 -80.742058) (xy 305.935156 -80.823291) (xy 305.948283 -80.906127)
			(xy 305.953557 -80.98983) (xy 305.950931 -81.073659) (xy 305.940428 -81.156868) (xy 305.922142 -81.23872)
			(xy 305.896234 -81.318488) (xy 305.862935 -81.395464) (xy 305.82254 -81.468965) (xy 305.775407 -81.538338)
			(xy 305.721955 -81.602968) (xy 305.662659 -81.662282) (xy 305.598045 -81.715752) (xy 305.528685 -81.762905)
			(xy 305.455196 -81.803321) (xy 305.37823 -81.836643) (xy 305.298469 -81.862574) (xy 305.216623 -81.880884)
			(xy 305.133416 -81.891411) (xy 305.049589 -81.894061) (xy 304.965883 -81.888812) (xy 304.883044 -81.875708)
			(xy 304.801804 -81.854868) (xy 304.722887 -81.826475) (xy 304.646992 -81.790781) (xy 304.574792 -81.748104)
			(xy 304.506928 -81.698823) (xy 304.444004 -81.643373) (xy 304.386576 -81.582249) (xy 304.335155 -81.515992)
			(xy 304.290198 -81.445189) (xy 304.252102 -81.370471) (xy 304.221207 -81.292499) (xy 304.197787 -81.211966)
			(xy 304.182048 -81.129586) (xy 304.174132 -81.046091) (xy 304.173636 -81.004156) (xy 304.173636 -81.003648)
			(xy 304.174164 -80.960829) (xy 304.182432 -80.87559) (xy 304.190146 -80.833468) (xy 304.191851 -80.822182)
			(xy 304.186179 -80.800099) (xy 304.179224 -80.79105) (xy 304.120804 -80.721708) (xy 304.099976 -80.71231)
			(xy 304.0888 -80.712564) (xy 304.087784 -80.712564) (xy 304.070258 -80.712564) (xy 304.028326 -80.712034)
			(xy 303.944833 -80.704139) (xy 303.862455 -80.688421) (xy 303.78192 -80.665021) (xy 303.703946 -80.634147)
			(xy 303.629222 -80.596072) (xy 303.558413 -80.551135) (xy 303.492147 -80.499733) (xy 303.431012 -80.442324)
			(xy 303.37555 -80.379417) (xy 303.326255 -80.31157) (xy 303.283562 -80.239385) (xy 303.247852 -80.163503)
			(xy 303.219441 -80.084598) (xy 303.198581 -80.003369) (xy 303.185457 -79.920537) (xy 303.180186 -79.836838)
			(xy 294.759416 -79.836838) (xy 294.754019 -79.843701) (xy 294.695554 -79.905016) (xy 294.631526 -79.960497)
			(xy 294.562514 -80.00964) (xy 294.489144 -80.052) (xy 294.412079 -80.087195) (xy 294.332017 -80.114904)
			(xy 294.249684 -80.134878) (xy 294.165825 -80.146935) (xy 294.0812 -80.150967) (xy 293.996575 -80.146935)
			(xy 293.912716 -80.134878) (xy 293.830383 -80.114904) (xy 293.750321 -80.087195) (xy 293.673256 -80.052)
			(xy 293.599886 -80.00964) (xy 293.530874 -79.960497) (xy 293.466846 -79.905016) (xy 293.408381 -79.843701)
			(xy 293.35601 -79.777105) (xy 293.310207 -79.705833) (xy 293.271385 -79.63053) (xy 293.239897 -79.551878)
			(xy 293.216029 -79.470588) (xy 293.199995 -79.387398) (xy 293.191942 -79.303061) (xy 290.841304 -79.303061)
			(xy 290.847353 -79.334444) (xy 290.855404 -79.418758) (xy 290.855908 -79.461106) (xy 290.855458 -79.501892)
			(xy 290.847997 -79.583123) (xy 290.833129 -79.663329) (xy 290.810979 -79.741837) (xy 290.781733 -79.817986)
			(xy 290.745637 -79.891138) (xy 290.702995 -79.960677) (xy 290.654163 -80.026019) (xy 290.599554 -80.086615)
			(xy 290.539625 -80.141956) (xy 290.474881 -80.191577) (xy 290.440618 -80.213708) (xy 290.440364 -80.213962)
			(xy 290.4319 -80.219885) (xy 290.420185 -80.236874) (xy 290.416114 -80.257104) (xy 290.417758 -80.267302)
			(xy 290.440618 -80.376268) (xy 290.463732 -80.397858) (xy 290.479734 -80.400144) (xy 290.521352 -80.406906)
			(xy 290.603168 -80.427307) (xy 290.682687 -80.455356) (xy 290.759196 -80.490802) (xy 290.832009 -80.533328)
			(xy 290.900472 -80.58255) (xy 290.963971 -80.638029) (xy 291.021937 -80.699267) (xy 291.07385 -80.765713)
			(xy 291.119244 -80.836773) (xy 291.157712 -80.911808) (xy 291.188908 -80.990146) (xy 291.212554 -81.071084)
			(xy 291.228437 -81.153896) (xy 291.236414 -81.237839) (xy 291.236908 -81.28) (xy 291.236908 -81.280762)
			(xy 291.2365 -81.318982) (xy 291.229935 -81.395141) (xy 291.216851 -81.470453) (xy 291.197344 -81.544363)
			(xy 291.184838 -81.580482) (xy 291.182252 -81.588798) (xy 291.182252 -81.589061) (xy 292.379142 -81.589061)
			(xy 292.379142 -81.504339) (xy 292.387195 -81.420002) (xy 292.403229 -81.336812) (xy 292.427097 -81.255522)
			(xy 292.458585 -81.17687) (xy 292.497407 -81.101567) (xy 292.54321 -81.030295) (xy 292.595581 -80.963699)
			(xy 292.654046 -80.902384) (xy 292.718074 -80.846903) (xy 292.787086 -80.79776) (xy 292.860456 -80.7554)
			(xy 292.937521 -80.720205) (xy 293.017583 -80.692496) (xy 293.099916 -80.672522) (xy 293.183775 -80.660465)
			(xy 293.2684 -80.656434) (xy 293.353025 -80.660465) (xy 293.436884 -80.672522) (xy 293.519217 -80.692496)
			(xy 293.599279 -80.720205) (xy 293.676344 -80.7554) (xy 293.749714 -80.79776) (xy 293.818726 -80.846903)
			(xy 293.882754 -80.902384) (xy 293.941219 -80.963699) (xy 293.99359 -81.030295) (xy 294.039393 -81.101567)
			(xy 294.078215 -81.17687) (xy 294.109703 -81.255522) (xy 294.133571 -81.336812) (xy 294.149605 -81.420002)
			(xy 294.157658 -81.504339) (xy 294.158162 -81.5467) (xy 294.157658 -81.589061) (xy 294.149605 -81.673398)
			(xy 294.133571 -81.756588) (xy 294.109703 -81.837878) (xy 294.078215 -81.91653) (xy 294.039393 -81.991833)
			(xy 293.99359 -82.063105) (xy 293.941219 -82.129701) (xy 293.882754 -82.191016) (xy 293.818726 -82.246497)
			(xy 293.749714 -82.29564) (xy 293.676344 -82.338) (xy 293.599279 -82.373195) (xy 293.519217 -82.400904)
			(xy 293.436884 -82.420878) (xy 293.353025 -82.432935) (xy 293.2684 -82.436967) (xy 293.183775 -82.432935)
			(xy 293.099916 -82.420878) (xy 293.017583 -82.400904) (xy 292.937521 -82.373195) (xy 292.860456 -82.338)
			(xy 292.787086 -82.29564) (xy 292.718074 -82.246497) (xy 292.654046 -82.191016) (xy 292.595581 -82.129701)
			(xy 292.54321 -82.063105) (xy 292.497407 -81.991833) (xy 292.458585 -81.91653) (xy 292.427097 -81.837878)
			(xy 292.403229 -81.756588) (xy 292.387195 -81.673398) (xy 292.379142 -81.589061) (xy 291.182252 -81.589061)
			(xy 291.182252 -81.606202) (xy 291.184838 -81.614518) (xy 291.197329 -81.650641) (xy 291.216819 -81.724553)
			(xy 291.229903 -81.799864) (xy 291.236485 -81.876019) (xy 291.236908 -81.914238) (xy 291.236908 -81.915)
			(xy 291.236404 -81.957348) (xy 291.228353 -82.041662) (xy 291.212324 -82.124828) (xy 291.188463 -82.206095)
			(xy 291.156984 -82.284725) (xy 291.118173 -82.360006) (xy 291.072383 -82.431258) (xy 291.020027 -82.497834)
			(xy 290.961579 -82.559132) (xy 290.897569 -82.614597) (xy 290.828577 -82.663726) (xy 290.755227 -82.706075)
			(xy 290.678184 -82.741259) (xy 290.598145 -82.768961) (xy 290.515836 -82.788929) (xy 290.432001 -82.800982)
			(xy 290.3474 -82.805013) (xy 290.262799 -82.800982) (xy 290.178964 -82.788929) (xy 290.096655 -82.768961)
			(xy 290.016616 -82.741259) (xy 289.939573 -82.706075) (xy 289.866223 -82.663726) (xy 289.797231 -82.614597)
			(xy 289.733221 -82.559132) (xy 289.674773 -82.497834) (xy 289.622417 -82.431258) (xy 289.576627 -82.360006)
			(xy 289.537816 -82.284725) (xy 289.506337 -82.206095) (xy 289.482476 -82.124828) (xy 289.466447 -82.041662)
			(xy 289.458396 -81.957348) (xy 289.457892 -81.915) (xy 289.457892 -81.914238) (xy 289.4583 -81.876018)
			(xy 289.464865 -81.799859) (xy 289.477949 -81.724547) (xy 289.497456 -81.650637) (xy 289.509962 -81.614518)
			(xy 289.512548 -81.606202) (xy 289.512548 -81.588798) (xy 289.509962 -81.580482) (xy 289.497471 -81.544359)
			(xy 289.477981 -81.470447) (xy 289.464897 -81.395136) (xy 289.458315 -81.318981) (xy 289.457892 -81.280762)
			(xy 289.457892 -81.28) (xy 289.458347 -81.239214) (xy 289.465808 -81.157983) (xy 289.480675 -81.077777)
			(xy 289.502824 -80.99927) (xy 289.53207 -80.92312) (xy 289.568165 -80.849969) (xy 289.610807 -80.78043)
			(xy 289.659638 -80.715087) (xy 289.714247 -80.654491) (xy 289.774175 -80.59915) (xy 289.838919 -80.549529)
			(xy 289.873182 -80.527398) (xy 289.873436 -80.527144) (xy 289.881896 -80.521216) (xy 289.893612 -80.50423)
			(xy 289.897685 -80.484001) (xy 289.896042 -80.473804) (xy 289.873182 -80.364838) (xy 289.850068 -80.343248)
			(xy 289.834066 -80.340962) (xy 289.792449 -80.334194) (xy 289.710634 -80.313794) (xy 289.631115 -80.285745)
			(xy 289.554606 -80.250299) (xy 289.481793 -80.207774) (xy 289.41333 -80.158551) (xy 289.349831 -80.103073)
			(xy 289.291865 -80.041836) (xy 289.239952 -79.97539) (xy 289.194558 -79.904331) (xy 289.15609 -79.829296)
			(xy 289.124893 -79.750958) (xy 289.101247 -79.670021) (xy 289.085364 -79.587209) (xy 289.077387 -79.503266)
			(xy 289.076892 -79.461106) (xy 261.02183 -79.461106) (xy 261.02183 -82.338361) (xy 269.519142 -82.338361)
			(xy 269.519142 -82.253639) (xy 269.527195 -82.169302) (xy 269.543229 -82.086112) (xy 269.567097 -82.004822)
			(xy 269.598585 -81.92617) (xy 269.637407 -81.850867) (xy 269.68321 -81.779595) (xy 269.735581 -81.712999)
			(xy 269.794046 -81.651684) (xy 269.858074 -81.596203) (xy 269.927086 -81.54706) (xy 270.000456 -81.5047)
			(xy 270.077521 -81.469505) (xy 270.157583 -81.441796) (xy 270.239916 -81.421822) (xy 270.323775 -81.409765)
			(xy 270.4084 -81.405734) (xy 270.493025 -81.409765) (xy 270.576884 -81.421822) (xy 270.659217 -81.441796)
			(xy 270.739279 -81.469505) (xy 270.816344 -81.5047) (xy 270.889714 -81.54706) (xy 270.958726 -81.596203)
			(xy 271.022754 -81.651684) (xy 271.081219 -81.712999) (xy 271.13359 -81.779595) (xy 271.179393 -81.850867)
			(xy 271.218215 -81.92617) (xy 271.249703 -82.004822) (xy 271.273571 -82.086112) (xy 271.289605 -82.169302)
			(xy 271.297658 -82.253639) (xy 271.298162 -82.296) (xy 271.297658 -82.338361) (xy 271.551142 -82.338361)
			(xy 271.551142 -82.253639) (xy 271.559195 -82.169302) (xy 271.575229 -82.086112) (xy 271.599097 -82.004822)
			(xy 271.630585 -81.92617) (xy 271.669407 -81.850867) (xy 271.71521 -81.779595) (xy 271.767581 -81.712999)
			(xy 271.826046 -81.651684) (xy 271.890074 -81.596203) (xy 271.959086 -81.54706) (xy 272.032456 -81.5047)
			(xy 272.109521 -81.469505) (xy 272.189583 -81.441796) (xy 272.271916 -81.421822) (xy 272.355775 -81.409765)
			(xy 272.4404 -81.405734) (xy 272.525025 -81.409765) (xy 272.608884 -81.421822) (xy 272.691217 -81.441796)
			(xy 272.771279 -81.469505) (xy 272.848344 -81.5047) (xy 272.921714 -81.54706) (xy 272.990726 -81.596203)
			(xy 273.054754 -81.651684) (xy 273.113219 -81.712999) (xy 273.16559 -81.779595) (xy 273.211393 -81.850867)
			(xy 273.250215 -81.92617) (xy 273.281703 -82.004822) (xy 273.305571 -82.086112) (xy 273.321605 -82.169302)
			(xy 273.329658 -82.253639) (xy 273.330162 -82.296) (xy 273.329658 -82.338361) (xy 273.583142 -82.338361)
			(xy 273.583142 -82.253639) (xy 273.591195 -82.169302) (xy 273.607229 -82.086112) (xy 273.631097 -82.004822)
			(xy 273.662585 -81.92617) (xy 273.701407 -81.850867) (xy 273.74721 -81.779595) (xy 273.799581 -81.712999)
			(xy 273.858046 -81.651684) (xy 273.922074 -81.596203) (xy 273.991086 -81.54706) (xy 274.064456 -81.5047)
			(xy 274.141521 -81.469505) (xy 274.221583 -81.441796) (xy 274.303916 -81.421822) (xy 274.387775 -81.409765)
			(xy 274.4724 -81.405734) (xy 274.557025 -81.409765) (xy 274.640884 -81.421822) (xy 274.723217 -81.441796)
			(xy 274.803279 -81.469505) (xy 274.880344 -81.5047) (xy 274.953714 -81.54706) (xy 275.022726 -81.596203)
			(xy 275.086754 -81.651684) (xy 275.145219 -81.712999) (xy 275.19759 -81.779595) (xy 275.243393 -81.850867)
			(xy 275.276456 -81.915) (xy 284.377892 -81.915) (xy 284.377892 -81.914492) (xy 284.378498 -81.86816)
			(xy 284.388169 -81.776002) (xy 284.407365 -81.685348) (xy 284.435877 -81.597179) (xy 284.454092 -81.554574)
			(xy 284.457898 -81.544632) (xy 284.457898 -81.523368) (xy 284.454092 -81.513426) (xy 284.43587 -81.470823)
			(xy 284.407352 -81.382656) (xy 284.38816 -81.292) (xy 284.3785 -81.19984) (xy 284.377892 -81.153508)
			(xy 284.377892 -81.153) (xy 284.378396 -81.110652) (xy 284.386447 -81.026338) (xy 284.402476 -80.943172)
			(xy 284.426337 -80.861905) (xy 284.457816 -80.783275) (xy 284.496627 -80.707994) (xy 284.542417 -80.636742)
			(xy 284.594773 -80.570166) (xy 284.653221 -80.508868) (xy 284.717231 -80.453403) (xy 284.786223 -80.404274)
			(xy 284.859573 -80.361925) (xy 284.936616 -80.326741) (xy 285.016655 -80.299039) (xy 285.098964 -80.279071)
			(xy 285.182799 -80.267018) (xy 285.2674 -80.262988) (xy 285.352001 -80.267018) (xy 285.435836 -80.279071)
			(xy 285.518145 -80.299039) (xy 285.598184 -80.326741) (xy 285.675227 -80.361925) (xy 285.748577 -80.404274)
			(xy 285.817569 -80.453403) (xy 285.881579 -80.508868) (xy 285.940027 -80.570166) (xy 285.992383 -80.636742)
			(xy 286.038173 -80.707994) (xy 286.076984 -80.783275) (xy 286.108463 -80.861905) (xy 286.132324 -80.943172)
			(xy 286.148353 -81.026338) (xy 286.156404 -81.110652) (xy 286.156908 -81.153) (xy 286.156908 -81.153508)
			(xy 286.156302 -81.19984) (xy 286.146631 -81.291998) (xy 286.127435 -81.382652) (xy 286.098923 -81.470821)
			(xy 286.080708 -81.513426) (xy 286.076902 -81.523368) (xy 286.076902 -81.544632) (xy 286.080708 -81.554574)
			(xy 286.09893 -81.597177) (xy 286.127448 -81.685344) (xy 286.14664 -81.776) (xy 286.1563 -81.86816)
			(xy 286.156908 -81.914492) (xy 286.156908 -81.915) (xy 286.156404 -81.957348) (xy 286.148353 -82.041662)
			(xy 286.132324 -82.124828) (xy 286.108463 -82.206095) (xy 286.076984 -82.284725) (xy 286.038173 -82.360006)
			(xy 285.992383 -82.431258) (xy 285.940027 -82.497834) (xy 285.881579 -82.559132) (xy 285.817569 -82.614597)
			(xy 285.748577 -82.663726) (xy 285.675227 -82.706075) (xy 285.598184 -82.741259) (xy 285.518145 -82.768961)
			(xy 285.435836 -82.788929) (xy 285.352001 -82.800982) (xy 285.2674 -82.805013) (xy 285.182799 -82.800982)
			(xy 285.098964 -82.788929) (xy 285.016655 -82.768961) (xy 284.936616 -82.741259) (xy 284.859573 -82.706075)
			(xy 284.786223 -82.663726) (xy 284.717231 -82.614597) (xy 284.653221 -82.559132) (xy 284.594773 -82.497834)
			(xy 284.542417 -82.431258) (xy 284.496627 -82.360006) (xy 284.457816 -82.284725) (xy 284.426337 -82.206095)
			(xy 284.402476 -82.124828) (xy 284.386447 -82.041662) (xy 284.378396 -81.957348) (xy 284.377892 -81.915)
			(xy 275.276456 -81.915) (xy 275.282215 -81.92617) (xy 275.313703 -82.004822) (xy 275.337571 -82.086112)
			(xy 275.353605 -82.169302) (xy 275.361658 -82.253639) (xy 275.362162 -82.296) (xy 275.361658 -82.338361)
			(xy 275.353605 -82.422698) (xy 275.337571 -82.505888) (xy 275.313703 -82.587178) (xy 275.282215 -82.66583)
			(xy 275.243393 -82.741133) (xy 275.19759 -82.812405) (xy 275.145219 -82.879001) (xy 275.086754 -82.940316)
			(xy 275.022726 -82.995797) (xy 274.953714 -83.04494) (xy 274.880344 -83.0873) (xy 274.803279 -83.122495)
			(xy 274.723217 -83.150204) (xy 274.640884 -83.170178) (xy 274.557025 -83.182235) (xy 274.4724 -83.186267)
			(xy 274.387775 -83.182235) (xy 274.303916 -83.170178) (xy 274.221583 -83.150204) (xy 274.141521 -83.122495)
			(xy 274.064456 -83.0873) (xy 273.991086 -83.04494) (xy 273.922074 -82.995797) (xy 273.858046 -82.940316)
			(xy 273.799581 -82.879001) (xy 273.74721 -82.812405) (xy 273.701407 -82.741133) (xy 273.662585 -82.66583)
			(xy 273.631097 -82.587178) (xy 273.607229 -82.505888) (xy 273.591195 -82.422698) (xy 273.583142 -82.338361)
			(xy 273.329658 -82.338361) (xy 273.321605 -82.422698) (xy 273.305571 -82.505888) (xy 273.281703 -82.587178)
			(xy 273.250215 -82.66583) (xy 273.211393 -82.741133) (xy 273.16559 -82.812405) (xy 273.113219 -82.879001)
			(xy 273.054754 -82.940316) (xy 272.990726 -82.995797) (xy 272.921714 -83.04494) (xy 272.848344 -83.0873)
			(xy 272.771279 -83.122495) (xy 272.691217 -83.150204) (xy 272.608884 -83.170178) (xy 272.525025 -83.182235)
			(xy 272.4404 -83.186267) (xy 272.355775 -83.182235) (xy 272.271916 -83.170178) (xy 272.189583 -83.150204)
			(xy 272.109521 -83.122495) (xy 272.032456 -83.0873) (xy 271.959086 -83.04494) (xy 271.890074 -82.995797)
			(xy 271.826046 -82.940316) (xy 271.767581 -82.879001) (xy 271.71521 -82.812405) (xy 271.669407 -82.741133)
			(xy 271.630585 -82.66583) (xy 271.599097 -82.587178) (xy 271.575229 -82.505888) (xy 271.559195 -82.422698)
			(xy 271.551142 -82.338361) (xy 271.297658 -82.338361) (xy 271.289605 -82.422698) (xy 271.273571 -82.505888)
			(xy 271.249703 -82.587178) (xy 271.218215 -82.66583) (xy 271.179393 -82.741133) (xy 271.13359 -82.812405)
			(xy 271.081219 -82.879001) (xy 271.022754 -82.940316) (xy 270.958726 -82.995797) (xy 270.889714 -83.04494)
			(xy 270.816344 -83.0873) (xy 270.739279 -83.122495) (xy 270.659217 -83.150204) (xy 270.576884 -83.170178)
			(xy 270.493025 -83.182235) (xy 270.4084 -83.186267) (xy 270.323775 -83.182235) (xy 270.239916 -83.170178)
			(xy 270.157583 -83.150204) (xy 270.077521 -83.122495) (xy 270.000456 -83.0873) (xy 269.927086 -83.04494)
			(xy 269.858074 -82.995797) (xy 269.794046 -82.940316) (xy 269.735581 -82.879001) (xy 269.68321 -82.812405)
			(xy 269.637407 -82.741133) (xy 269.598585 -82.66583) (xy 269.567097 -82.587178) (xy 269.543229 -82.505888)
			(xy 269.527195 -82.422698) (xy 269.519142 -82.338361) (xy 261.02183 -82.338361) (xy 261.02183 -83.862361)
			(xy 315.308738 -83.862361) (xy 315.308738 -83.777639) (xy 315.316791 -83.693302) (xy 315.332825 -83.610112)
			(xy 315.356693 -83.528822) (xy 315.388181 -83.45017) (xy 315.427003 -83.374867) (xy 315.472806 -83.303595)
			(xy 315.525177 -83.236999) (xy 315.583642 -83.175684) (xy 315.64767 -83.120203) (xy 315.716682 -83.07106)
			(xy 315.790052 -83.0287) (xy 315.867117 -82.993505) (xy 315.947179 -82.965796) (xy 316.029512 -82.945822)
			(xy 316.113371 -82.933765) (xy 316.197996 -82.929734) (xy 316.282621 -82.933765) (xy 316.36648 -82.945822)
			(xy 316.448813 -82.965796) (xy 316.528875 -82.993505) (xy 316.60594 -83.0287) (xy 316.67931 -83.07106)
			(xy 316.748322 -83.120203) (xy 316.81235 -83.175684) (xy 316.870815 -83.236999) (xy 316.923186 -83.303595)
			(xy 316.968989 -83.374867) (xy 317.007811 -83.45017) (xy 317.039299 -83.528822) (xy 317.063167 -83.610112)
			(xy 317.079201 -83.693302) (xy 317.087254 -83.777639) (xy 317.087758 -83.82) (xy 317.087254 -83.862361)
			(xy 317.079201 -83.946698) (xy 317.063167 -84.029888) (xy 317.039299 -84.111178) (xy 317.007811 -84.18983)
			(xy 316.968989 -84.265133) (xy 316.923186 -84.336405) (xy 316.870815 -84.403001) (xy 316.81235 -84.464316)
			(xy 316.748322 -84.519797) (xy 316.67931 -84.56894) (xy 316.60594 -84.6113) (xy 316.528875 -84.646495)
			(xy 316.448813 -84.674204) (xy 316.36648 -84.694178) (xy 316.282621 -84.706235) (xy 316.197996 -84.710267)
			(xy 316.113371 -84.706235) (xy 316.029512 -84.694178) (xy 315.947179 -84.674204) (xy 315.867117 -84.646495)
			(xy 315.790052 -84.6113) (xy 315.716682 -84.56894) (xy 315.64767 -84.519797) (xy 315.583642 -84.464316)
			(xy 315.525177 -84.403001) (xy 315.472806 -84.336405) (xy 315.427003 -84.265133) (xy 315.388181 -84.18983)
			(xy 315.356693 -84.111178) (xy 315.332825 -84.029888) (xy 315.316791 -83.946698) (xy 315.308738 -83.862361)
			(xy 261.02183 -83.862361) (xy 261.02183 -85.262212) (xy 261.022256 -85.272281) (xy 261.029977 -85.290879)
			(xy 261.036816 -85.29828) (xy 261.971536 -86.233) (xy 269.188188 -86.233) (xy 269.192218 -86.148399)
			(xy 269.204271 -86.064564) (xy 269.224239 -85.982255) (xy 269.251941 -85.902216) (xy 269.287125 -85.825173)
			(xy 269.329474 -85.751823) (xy 269.378603 -85.682831) (xy 269.434068 -85.618821) (xy 269.495366 -85.560373)
			(xy 269.561942 -85.508017) (xy 269.633194 -85.462227) (xy 269.708475 -85.423416) (xy 269.787105 -85.391937)
			(xy 269.868372 -85.368076) (xy 269.951538 -85.352047) (xy 270.035852 -85.343996) (xy 270.0782 -85.343492)
			(xy 270.078962 -85.343492) (xy 270.117182 -85.3439) (xy 270.193341 -85.350465) (xy 270.268653 -85.363549)
			(xy 270.342563 -85.383056) (xy 270.378682 -85.395562) (xy 270.386998 -85.398148) (xy 270.404402 -85.398148)
			(xy 270.412718 -85.395562) (xy 270.448841 -85.383071) (xy 270.522753 -85.363581) (xy 270.598064 -85.350497)
			(xy 270.674219 -85.343915) (xy 270.712438 -85.343492) (xy 270.7132 -85.343492) (xy 270.756684 -85.343995)
			(xy 270.843237 -85.35248) (xy 270.928548 -85.36937) (xy 271.011805 -85.394503) (xy 271.092212 -85.42764)
			(xy 271.169003 -85.468464) (xy 271.241444 -85.516586) (xy 271.308843 -85.571546) (xy 271.340072 -85.60181)
			(xy 271.340326 -85.602064) (xy 271.347704 -85.608646) (xy 271.366008 -85.616084) (xy 271.375886 -85.616542)
			(xy 271.447514 -85.616542) (xy 271.457395 -85.616108) (xy 271.475694 -85.608649) (xy 271.483074 -85.602064)
			(xy 271.483328 -85.60181) (xy 271.514554 -85.571545) (xy 271.581957 -85.51659) (xy 271.6544 -85.468474)
			(xy 271.731191 -85.427654) (xy 271.811598 -85.394521) (xy 271.894855 -85.36939) (xy 271.980165 -85.352502)
			(xy 272.066717 -85.344018) (xy 272.1102 -85.343492) (xy 272.110962 -85.343492) (xy 272.149182 -85.3439)
			(xy 272.225341 -85.350465) (xy 272.300653 -85.363549) (xy 272.374563 -85.383056) (xy 272.410682 -85.395562)
			(xy 272.418998 -85.398148) (xy 272.436402 -85.398148) (xy 272.444718 -85.395562) (xy 272.480841 -85.383071)
			(xy 272.554753 -85.363581) (xy 272.630064 -85.350497) (xy 272.706219 -85.343915) (xy 272.744438 -85.343492)
			(xy 272.7452 -85.343492) (xy 272.788684 -85.343995) (xy 272.875237 -85.35248) (xy 272.960548 -85.36937)
			(xy 273.043805 -85.394503) (xy 273.124212 -85.42764) (xy 273.201003 -85.468464) (xy 273.273444 -85.516586)
			(xy 273.340843 -85.571546) (xy 273.372072 -85.60181) (xy 273.372326 -85.602064) (xy 273.379704 -85.608646)
			(xy 273.398008 -85.616084) (xy 273.407886 -85.616542) (xy 273.479514 -85.616542) (xy 273.489395 -85.616108)
			(xy 273.507694 -85.608649) (xy 273.515074 -85.602064) (xy 273.515328 -85.60181) (xy 273.546554 -85.571545)
			(xy 273.613957 -85.51659) (xy 273.6864 -85.468474) (xy 273.763191 -85.427654) (xy 273.843598 -85.394521)
			(xy 273.926855 -85.36939) (xy 274.012165 -85.352502) (xy 274.098717 -85.344018) (xy 274.1422 -85.343492)
			(xy 274.142962 -85.343492) (xy 274.181182 -85.3439) (xy 274.257341 -85.350465) (xy 274.332653 -85.363549)
			(xy 274.406563 -85.383056) (xy 274.442682 -85.395562) (xy 274.450998 -85.398148) (xy 274.468402 -85.398148)
			(xy 274.476718 -85.395562) (xy 274.512841 -85.383071) (xy 274.586753 -85.363581) (xy 274.662064 -85.350497)
			(xy 274.738219 -85.343915) (xy 274.776438 -85.343492) (xy 274.7772 -85.343492) (xy 274.817247 -85.343907)
			(xy 274.897016 -85.351102) (xy 274.975816 -85.365436) (xy 275.05301 -85.38679) (xy 275.127973 -85.414994)
			(xy 275.2001 -85.449818) (xy 275.268805 -85.490982) (xy 275.333535 -85.538151) (xy 275.36394 -85.564218)
			(xy 275.371029 -85.569983) (xy 275.388086 -85.576495) (xy 275.397214 -85.576918) (xy 275.427186 -85.576918)
			(xy 275.436309 -85.576484) (xy 275.453359 -85.569964) (xy 275.46046 -85.564218) (xy 275.490874 -85.53816)
			(xy 275.555592 -85.490974) (xy 275.624292 -85.449798) (xy 275.696416 -85.414967) (xy 275.77138 -85.386763)
			(xy 275.848577 -85.365414) (xy 275.927381 -85.351094) (xy 276.007153 -85.343919) (xy 276.0472 -85.343492)
			(xy 276.047962 -85.343492) (xy 276.086182 -85.3439) (xy 276.162341 -85.350465) (xy 276.237653 -85.363549)
			(xy 276.311563 -85.383056) (xy 276.347682 -85.395562) (xy 276.355998 -85.398148) (xy 276.373402 -85.398148)
			(xy 276.381718 -85.395562) (xy 276.417841 -85.383071) (xy 276.491753 -85.363581) (xy 276.567064 -85.350497)
			(xy 276.643219 -85.343915) (xy 276.681438 -85.343492) (xy 276.6822 -85.343492) (xy 276.724548 -85.343996)
			(xy 276.808862 -85.352047) (xy 276.892028 -85.368076) (xy 276.973295 -85.391937) (xy 277.051925 -85.423416)
			(xy 277.127206 -85.462227) (xy 277.198458 -85.508017) (xy 277.265034 -85.560373) (xy 277.326332 -85.618821)
			(xy 277.381797 -85.682831) (xy 277.430926 -85.751823) (xy 277.473275 -85.825173) (xy 277.508459 -85.902216)
			(xy 277.536161 -85.982255) (xy 277.556129 -86.064564) (xy 277.568182 -86.148399) (xy 277.572213 -86.233)
			(xy 277.568182 -86.317601) (xy 277.556129 -86.401436) (xy 277.536161 -86.483745) (xy 277.508459 -86.563784)
			(xy 277.473275 -86.640827) (xy 277.430926 -86.714177) (xy 277.381797 -86.783169) (xy 277.326332 -86.847179)
			(xy 277.265034 -86.905627) (xy 277.198458 -86.957983) (xy 277.140857 -86.995) (xy 290.447988 -86.995)
			(xy 290.452018 -86.910399) (xy 290.464071 -86.826564) (xy 290.484039 -86.744255) (xy 290.511741 -86.664216)
			(xy 290.546925 -86.587173) (xy 290.589274 -86.513823) (xy 290.638403 -86.444831) (xy 290.693868 -86.380821)
			(xy 290.755166 -86.322373) (xy 290.821742 -86.270017) (xy 290.892994 -86.224227) (xy 290.968275 -86.185416)
			(xy 291.046905 -86.153937) (xy 291.128172 -86.130076) (xy 291.211338 -86.114047) (xy 291.295652 -86.105996)
			(xy 291.338 -86.105492) (xy 291.338254 -86.105492) (xy 291.382026 -86.105984) (xy 291.469144 -86.114598)
			(xy 291.554996 -86.131727) (xy 291.63875 -86.157206) (xy 291.719596 -86.190788) (xy 291.796753 -86.232149)
			(xy 291.869474 -86.280888) (xy 291.937056 -86.336534) (xy 291.998846 -86.39855) (xy 292.054245 -86.466335)
			(xy 292.078918 -86.502494) (xy 292.08603 -86.512908) (xy 292.108382 -86.5251) (xy 292.218618 -86.5251)
			(xy 292.24097 -86.512908) (xy 292.248082 -86.502494) (xy 292.272755 -86.466334) (xy 292.328147 -86.398543)
			(xy 292.389932 -86.336522) (xy 292.457512 -86.280872) (xy 292.530233 -86.232132) (xy 292.607392 -86.190774)
			(xy 292.688241 -86.157197) (xy 292.771998 -86.131728) (xy 292.857853 -86.114611) (xy 292.944974 -86.106013)
			(xy 292.988746 -86.105492) (xy 292.989 -86.105492) (xy 293.031348 -86.105996) (xy 293.115662 -86.114047)
			(xy 293.198828 -86.130076) (xy 293.280095 -86.153937) (xy 293.358725 -86.185416) (xy 293.434006 -86.224227)
			(xy 293.505258 -86.270017) (xy 293.571834 -86.322373) (xy 293.633132 -86.380821) (xy 293.688597 -86.444831)
			(xy 293.718625 -86.487) (xy 294.365987 -86.487) (xy 294.370017 -86.402402) (xy 294.38207 -86.31857)
			(xy 294.402037 -86.236263) (xy 294.429736 -86.156227) (xy 294.464918 -86.079186) (xy 294.507264 -86.005838)
			(xy 294.55639 -85.936847) (xy 294.611851 -85.872839) (xy 294.673145 -85.814391) (xy 294.739717 -85.762035)
			(xy 294.810965 -85.716243) (xy 294.886242 -85.677431) (xy 294.964868 -85.64595) (xy 295.04613 -85.622086)
			(xy 295.129293 -85.606053) (xy 295.213603 -85.597998) (xy 295.25595 -85.597492) (xy 295.295051 -85.597898)
			(xy 295.37295 -85.604772) (xy 295.449944 -85.618461) (xy 295.525439 -85.638859) (xy 295.598849 -85.665811)
			(xy 295.63441 -85.682074) (xy 295.644797 -85.686309) (xy 295.667203 -85.686309) (xy 295.67759 -85.682074)
			(xy 295.713157 -85.665829) (xy 295.786572 -85.638898) (xy 295.862066 -85.618508) (xy 295.939056 -85.604817)
			(xy 296.016951 -85.59793) (xy 296.05605 -85.597492) (xy 296.098401 -85.597978) (xy 296.098632 -85.598)
			(xy 318.127888 -85.598) (xy 318.12834 -85.556753) (xy 318.13597 -85.474611) (xy 318.151173 -85.393529)
			(xy 318.17382 -85.314204) (xy 318.203714 -85.237316) (xy 318.2406 -85.163527) (xy 318.28416 -85.093471)
			(xy 318.334021 -85.027749) (xy 318.389753 -84.966927) (xy 318.450877 -84.911527) (xy 318.51687 -84.862025)
			(xy 318.587162 -84.818847) (xy 318.62395 -84.800186) (xy 318.632297 -84.795651) (xy 318.645117 -84.781649)
			(xy 318.652006 -84.763958) (xy 318.652398 -84.754466) (xy 318.652398 -84.663534) (xy 318.65204 -84.654032)
			(xy 318.645179 -84.636314) (xy 318.632318 -84.622329) (xy 318.62395 -84.617814) (xy 318.587161 -84.599159)
			(xy 318.516875 -84.555973) (xy 318.45089 -84.506465) (xy 318.389772 -84.451061) (xy 318.334045 -84.390237)
			(xy 318.284188 -84.324514) (xy 318.24063 -84.254459) (xy 318.203745 -84.180672) (xy 318.17385 -84.103786)
			(xy 318.1512 -84.024464) (xy 318.135992 -83.943385) (xy 318.128355 -83.861246) (xy 318.127888 -83.82)
			(xy 318.128392 -83.777639) (xy 318.136445 -83.693302) (xy 318.152479 -83.610112) (xy 318.176347 -83.528822)
			(xy 318.207835 -83.45017) (xy 318.246657 -83.374867) (xy 318.29246 -83.303595) (xy 318.344831 -83.236999)
			(xy 318.403296 -83.175684) (xy 318.467324 -83.120203) (xy 318.536336 -83.07106) (xy 318.609706 -83.0287)
			(xy 318.686771 -82.993505) (xy 318.766833 -82.965796) (xy 318.849166 -82.945822) (xy 318.933025 -82.933765)
			(xy 319.01765 -82.929734) (xy 319.102275 -82.933765) (xy 319.186134 -82.945822) (xy 319.268467 -82.965796)
			(xy 319.348529 -82.993505) (xy 319.425594 -83.0287) (xy 319.498964 -83.07106) (xy 319.567976 -83.120203)
			(xy 319.632004 -83.175684) (xy 319.690469 -83.236999) (xy 319.74284 -83.303595) (xy 319.788643 -83.374867)
			(xy 319.827465 -83.45017) (xy 319.858953 -83.528822) (xy 319.882821 -83.610112) (xy 319.898855 -83.693302)
			(xy 319.906908 -83.777639) (xy 319.907412 -83.82) (xy 319.90696 -83.861247) (xy 319.89933 -83.943389)
			(xy 319.884127 -84.024471) (xy 319.86148 -84.103796) (xy 319.831586 -84.180684) (xy 319.7947 -84.254473)
			(xy 319.75114 -84.324529) (xy 319.701279 -84.390251) (xy 319.645547 -84.451073) (xy 319.584423 -84.506473)
			(xy 319.51843 -84.555975) (xy 319.448138 -84.599153) (xy 319.41135 -84.617814) (xy 319.403003 -84.622349)
			(xy 319.390183 -84.636351) (xy 319.383294 -84.654042) (xy 319.382902 -84.663534) (xy 319.382902 -84.754466)
			(xy 319.38326 -84.763968) (xy 319.390121 -84.781686) (xy 319.402982 -84.795671) (xy 319.41135 -84.800186)
			(xy 319.448139 -84.818841) (xy 319.518425 -84.862027) (xy 319.58441 -84.911535) (xy 319.645528 -84.966939)
			(xy 319.701255 -85.027763) (xy 319.751112 -85.093486) (xy 319.79467 -85.163541) (xy 319.831555 -85.237328)
			(xy 319.86145 -85.314214) (xy 319.8841 -85.393536) (xy 319.899308 -85.474615) (xy 319.906945 -85.556754)
			(xy 319.907412 -85.598) (xy 319.906908 -85.640361) (xy 319.898855 -85.724698) (xy 319.882821 -85.807888)
			(xy 319.858953 -85.889178) (xy 319.827465 -85.96783) (xy 319.788643 -86.043133) (xy 319.74284 -86.114405)
			(xy 319.690469 -86.181001) (xy 319.632004 -86.242316) (xy 319.567976 -86.297797) (xy 319.498964 -86.34694)
			(xy 319.425594 -86.3893) (xy 319.348529 -86.424495) (xy 319.268467 -86.452204) (xy 319.186134 -86.472178)
			(xy 319.102275 -86.484235) (xy 319.01765 -86.488267) (xy 318.933025 -86.484235) (xy 318.849166 -86.472178)
			(xy 318.766833 -86.452204) (xy 318.686771 -86.424495) (xy 318.609706 -86.3893) (xy 318.536336 -86.34694)
			(xy 318.467324 -86.297797) (xy 318.403296 -86.242316) (xy 318.344831 -86.181001) (xy 318.29246 -86.114405)
			(xy 318.246657 -86.043133) (xy 318.207835 -85.96783) (xy 318.176347 -85.889178) (xy 318.152479 -85.807888)
			(xy 318.136445 -85.724698) (xy 318.128392 -85.640361) (xy 318.127888 -85.598) (xy 296.098632 -85.598)
			(xy 296.182719 -85.606025) (xy 296.265891 -85.62205) (xy 296.347162 -85.64591) (xy 296.425798 -85.677387)
			(xy 296.501085 -85.716196) (xy 296.572342 -85.761987) (xy 296.638924 -85.814344) (xy 296.700227 -85.872793)
			(xy 296.755696 -85.936805) (xy 296.804829 -86.005799) (xy 296.847181 -86.079152) (xy 296.882369 -86.156199)
			(xy 296.910073 -86.236241) (xy 296.930043 -86.318555) (xy 296.942098 -86.402394) (xy 296.946128 -86.487)
			(xy 296.942098 -86.571606) (xy 296.930043 -86.655445) (xy 296.910073 -86.737759) (xy 296.882369 -86.817801)
			(xy 296.847181 -86.894848) (xy 296.804829 -86.968201) (xy 296.755696 -87.037195) (xy 296.700227 -87.101207)
			(xy 296.638924 -87.159656) (xy 296.572342 -87.212013) (xy 296.501085 -87.257804) (xy 296.425798 -87.296613)
			(xy 296.347162 -87.32809) (xy 296.265891 -87.35195) (xy 296.182719 -87.367975) (xy 296.098401 -87.376022)
			(xy 296.05605 -87.376508) (xy 296.016949 -87.376102) (xy 295.93905 -87.369228) (xy 295.862056 -87.355539)
			(xy 295.786561 -87.335141) (xy 295.713151 -87.308189) (xy 295.67759 -87.291926) (xy 295.667203 -87.287691)
			(xy 295.644797 -87.287691) (xy 295.63441 -87.291926) (xy 295.598843 -87.308171) (xy 295.525428 -87.335102)
			(xy 295.449934 -87.355492) (xy 295.372944 -87.369183) (xy 295.295049 -87.37607) (xy 295.25595 -87.376508)
			(xy 295.213603 -87.376002) (xy 295.129293 -87.367947) (xy 295.04613 -87.351914) (xy 294.964868 -87.32805)
			(xy 294.886242 -87.296569) (xy 294.810965 -87.257757) (xy 294.739717 -87.211965) (xy 294.673145 -87.159609)
			(xy 294.611851 -87.101161) (xy 294.55639 -87.037153) (xy 294.507264 -86.968162) (xy 294.464918 -86.894814)
			(xy 294.429736 -86.817773) (xy 294.402037 -86.737737) (xy 294.38207 -86.65543) (xy 294.370017 -86.571598)
			(xy 294.365987 -86.487) (xy 293.718625 -86.487) (xy 293.737726 -86.513823) (xy 293.780075 -86.587173)
			(xy 293.815259 -86.664216) (xy 293.842961 -86.744255) (xy 293.862929 -86.826564) (xy 293.874982 -86.910399)
			(xy 293.879013 -86.995) (xy 293.874982 -87.079601) (xy 293.862929 -87.163436) (xy 293.842961 -87.245745)
			(xy 293.815259 -87.325784) (xy 293.780075 -87.402827) (xy 293.737726 -87.476177) (xy 293.688597 -87.545169)
			(xy 293.633132 -87.609179) (xy 293.571834 -87.667627) (xy 293.505258 -87.719983) (xy 293.434006 -87.765773)
			(xy 293.358725 -87.804584) (xy 293.280095 -87.836063) (xy 293.198828 -87.859924) (xy 293.115662 -87.875953)
			(xy 293.031348 -87.884004) (xy 292.989 -87.884508) (xy 292.988746 -87.884508) (xy 292.944974 -87.884016)
			(xy 292.857856 -87.875402) (xy 292.772004 -87.858273) (xy 292.68825 -87.832794) (xy 292.607404 -87.799212)
			(xy 292.530247 -87.757851) (xy 292.457526 -87.709112) (xy 292.389944 -87.653466) (xy 292.328154 -87.59145)
			(xy 292.272755 -87.523665) (xy 292.248082 -87.487506) (xy 292.24097 -87.477092) (xy 292.218618 -87.4649)
			(xy 292.108382 -87.4649) (xy 292.08603 -87.477092) (xy 292.078918 -87.487506) (xy 292.054245 -87.523666)
			(xy 291.998853 -87.591457) (xy 291.937068 -87.653478) (xy 291.869488 -87.709128) (xy 291.796767 -87.757868)
			(xy 291.719608 -87.799226) (xy 291.638759 -87.832803) (xy 291.555002 -87.858272) (xy 291.469147 -87.875389)
			(xy 291.382026 -87.883987) (xy 291.338254 -87.884508) (xy 291.338 -87.884508) (xy 291.295652 -87.884004)
			(xy 291.211338 -87.875953) (xy 291.128172 -87.859924) (xy 291.046905 -87.836063) (xy 290.968275 -87.804584)
			(xy 290.892994 -87.765773) (xy 290.821742 -87.719983) (xy 290.755166 -87.667627) (xy 290.693868 -87.609179)
			(xy 290.638403 -87.545169) (xy 290.589274 -87.476177) (xy 290.546925 -87.402827) (xy 290.511741 -87.325784)
			(xy 290.484039 -87.245745) (xy 290.464071 -87.163436) (xy 290.452018 -87.079601) (xy 290.447988 -86.995)
			(xy 277.140857 -86.995) (xy 277.127206 -87.003773) (xy 277.051925 -87.042584) (xy 276.973295 -87.074063)
			(xy 276.892028 -87.097924) (xy 276.808862 -87.113953) (xy 276.724548 -87.122004) (xy 276.6822 -87.122508)
			(xy 276.681438 -87.122508) (xy 276.643218 -87.1221) (xy 276.567059 -87.115535) (xy 276.491747 -87.102451)
			(xy 276.417837 -87.082944) (xy 276.381718 -87.070438) (xy 276.373402 -87.067852) (xy 276.355998 -87.067852)
			(xy 276.347682 -87.070438) (xy 276.311559 -87.082929) (xy 276.237647 -87.102419) (xy 276.162336 -87.115503)
			(xy 276.086181 -87.122085) (xy 276.047962 -87.122508) (xy 276.0472 -87.122508) (xy 276.007153 -87.122093)
			(xy 275.927384 -87.114898) (xy 275.848584 -87.100564) (xy 275.77139 -87.07921) (xy 275.696427 -87.051006)
			(xy 275.6243 -87.016182) (xy 275.555595 -86.975018) (xy 275.490865 -86.927849) (xy 275.46046 -86.901782)
			(xy 275.453371 -86.896017) (xy 275.436314 -86.889505) (xy 275.427186 -86.889082) (xy 275.397214 -86.889082)
			(xy 275.388091 -86.889516) (xy 275.371041 -86.896036) (xy 275.36394 -86.901782) (xy 275.333526 -86.92784)
			(xy 275.268808 -86.975026) (xy 275.200108 -87.016202) (xy 275.127984 -87.051033) (xy 275.05302 -87.079237)
			(xy 274.975823 -87.100586) (xy 274.897019 -87.114906) (xy 274.817247 -87.122081) (xy 274.7772 -87.122508)
			(xy 274.776438 -87.122508) (xy 274.738218 -87.1221) (xy 274.662059 -87.115535) (xy 274.586747 -87.102451)
			(xy 274.512837 -87.082944) (xy 274.476718 -87.070438) (xy 274.468402 -87.067852) (xy 274.450998 -87.067852)
			(xy 274.442682 -87.070438) (xy 274.406559 -87.082929) (xy 274.332647 -87.102419) (xy 274.257336 -87.115503)
			(xy 274.181181 -87.122085) (xy 274.142962 -87.122508) (xy 274.1422 -87.122508) (xy 274.098716 -87.122005)
			(xy 274.012163 -87.11352) (xy 273.926852 -87.09663) (xy 273.843595 -87.071497) (xy 273.763188 -87.03836)
			(xy 273.686397 -86.997536) (xy 273.613956 -86.949414) (xy 273.546557 -86.894454) (xy 273.515328 -86.86419)
			(xy 273.515074 -86.863936) (xy 273.507696 -86.857354) (xy 273.489392 -86.849916) (xy 273.479514 -86.849458)
			(xy 273.407886 -86.849458) (xy 273.398005 -86.849892) (xy 273.379706 -86.857351) (xy 273.372326 -86.863936)
			(xy 273.372072 -86.86419) (xy 273.340846 -86.894455) (xy 273.273443 -86.94941) (xy 273.201 -86.997526)
			(xy 273.124209 -87.038346) (xy 273.043802 -87.071479) (xy 272.960545 -87.09661) (xy 272.875235 -87.113498)
			(xy 272.788683 -87.121982) (xy 272.7452 -87.122508) (xy 272.744438 -87.122508) (xy 272.706218 -87.1221)
			(xy 272.630059 -87.115535) (xy 272.554747 -87.102451) (xy 272.480837 -87.082944) (xy 272.444718 -87.070438)
			(xy 272.436402 -87.067852) (xy 272.418998 -87.067852) (xy 272.410682 -87.070438) (xy 272.374559 -87.082929)
			(xy 272.300647 -87.102419) (xy 272.225336 -87.115503) (xy 272.149181 -87.122085) (xy 272.110962 -87.122508)
			(xy 272.1102 -87.122508) (xy 272.066716 -87.122005) (xy 271.980163 -87.11352) (xy 271.894852 -87.09663)
			(xy 271.811595 -87.071497) (xy 271.731188 -87.03836) (xy 271.654397 -86.997536) (xy 271.581956 -86.949414)
			(xy 271.514557 -86.894454) (xy 271.483328 -86.86419) (xy 271.483074 -86.863936) (xy 271.475696 -86.857354)
			(xy 271.457392 -86.849916) (xy 271.447514 -86.849458) (xy 271.375886 -86.849458) (xy 271.366005 -86.849892)
			(xy 271.347706 -86.857351) (xy 271.340326 -86.863936) (xy 271.340072 -86.86419) (xy 271.308846 -86.894455)
			(xy 271.241443 -86.94941) (xy 271.169 -86.997526) (xy 271.092209 -87.038346) (xy 271.011802 -87.071479)
			(xy 270.928545 -87.09661) (xy 270.843235 -87.113498) (xy 270.756683 -87.121982) (xy 270.7132 -87.122508)
			(xy 270.712438 -87.122508) (xy 270.674218 -87.1221) (xy 270.598059 -87.115535) (xy 270.522747 -87.102451)
			(xy 270.448837 -87.082944) (xy 270.412718 -87.070438) (xy 270.404402 -87.067852) (xy 270.386998 -87.067852)
			(xy 270.378682 -87.070438) (xy 270.342559 -87.082929) (xy 270.268647 -87.102419) (xy 270.193336 -87.115503)
			(xy 270.117181 -87.122085) (xy 270.078962 -87.122508) (xy 270.0782 -87.122508) (xy 270.035852 -87.122004)
			(xy 269.951538 -87.113953) (xy 269.868372 -87.097924) (xy 269.787105 -87.074063) (xy 269.708475 -87.042584)
			(xy 269.633194 -87.003773) (xy 269.561942 -86.957983) (xy 269.495366 -86.905627) (xy 269.434068 -86.847179)
			(xy 269.378603 -86.783169) (xy 269.329474 -86.714177) (xy 269.287125 -86.640827) (xy 269.251941 -86.563784)
			(xy 269.224239 -86.483745) (xy 269.204271 -86.401436) (xy 269.192218 -86.317601) (xy 269.188188 -86.233)
			(xy 261.971536 -86.233) (xy 263.858756 -88.12022) (xy 263.866154 -88.127067) (xy 263.884753 -88.134793)
			(xy 263.894824 -88.135206) (xy 288.256218 -88.135206) (xy 288.267917 -88.134614) (xy 288.288892 -88.124247)
			(xy 288.303111 -88.105666) (xy 288.306002 -88.094312) (xy 288.306002 -88.094058) (xy 288.314303 -88.054055)
			(xy 288.337284 -87.975649) (xy 288.36736 -87.899681) (xy 288.404275 -87.826791) (xy 288.44772 -87.757594)
			(xy 288.497328 -87.692673) (xy 288.552682 -87.632576) (xy 288.613313 -87.577808) (xy 288.678712 -87.528832)
			(xy 288.748328 -87.486061) (xy 288.821572 -87.449854) (xy 288.897829 -87.420517) (xy 288.976454 -87.398298)
			(xy 289.056786 -87.383384) (xy 289.138148 -87.375899) (xy 289.179 -87.375492) (xy 289.225403 -87.376099)
			(xy 289.317704 -87.385784) (xy 289.408492 -87.405037) (xy 289.496778 -87.433649) (xy 289.539426 -87.451946)
			(xy 289.549368 -87.455752) (xy 289.570632 -87.455752) (xy 289.580574 -87.451946) (xy 289.623234 -87.433681)
			(xy 289.711522 -87.405084) (xy 289.802305 -87.385824) (xy 289.894599 -87.376111) (xy 289.941 -87.375492)
			(xy 289.981847 -87.375959) (xy 290.063197 -87.383459) (xy 290.143516 -87.398385) (xy 290.222129 -87.420613)
			(xy 290.298372 -87.449955) (xy 290.371605 -87.486164) (xy 290.441208 -87.528935) (xy 290.506597 -87.577907)
			(xy 290.567221 -87.632668) (xy 290.622568 -87.692757) (xy 290.672173 -87.757668) (xy 290.715618 -87.826853)
			(xy 290.752536 -87.89973) (xy 290.782617 -87.975685) (xy 290.805607 -88.054078) (xy 290.813998 -88.094058)
			(xy 290.813998 -88.094312) (xy 290.816851 -88.105683) (xy 290.831089 -88.124274) (xy 290.852075 -88.134666)
			(xy 290.863782 -88.135206) (xy 296.141902 -88.135206) (xy 296.173144 -88.124284) (xy 296.206733 -88.098559)
			(xy 296.27795 -88.052872) (xy 296.353179 -88.014146) (xy 296.431742 -87.98273) (xy 296.512931 -87.958909)
			(xy 296.596014 -87.942896) (xy 296.68024 -87.934837) (xy 296.722546 -87.934292) (xy 296.7228 -87.934292)
			(xy 296.763591 -87.934765) (xy 296.844828 -87.942255) (xy 296.925039 -87.957145) (xy 297.003552 -87.979311)
			(xy 297.079708 -88.008565) (xy 297.152869 -88.044664) (xy 297.187874 -88.06561) (xy 297.199027 -88.071693)
			(xy 297.224356 -88.073163) (xy 297.236134 -88.068404) (xy 297.271472 -88.052396) (xy 297.344378 -88.025862)
			(xy 297.419317 -88.005776) (xy 297.495721 -87.992292) (xy 297.573008 -87.985511) (xy 297.6118 -87.985092)
			(xy 297.654267 -87.985586) (xy 297.738814 -87.993684) (xy 297.822204 -88.009805) (xy 297.903677 -88.033804)
			(xy 297.982491 -88.065461) (xy 298.057928 -88.104488) (xy 298.093892 -88.127078) (xy 298.094146 -88.127078)
			(xy 298.100394 -88.130789) (xy 298.114317 -88.134929) (xy 298.121578 -88.135206) (xy 298.240196 -88.135206)
			(xy 298.252896 -88.13165) (xy 298.258738 -88.128348) (xy 298.29924 -88.10581) (xy 298.384011 -88.068311)
			(xy 298.472222 -88.039835) (xy 298.562918 -88.02069) (xy 298.655113 -88.011084) (xy 298.70146 -88.010492)
			(xy 298.704 -88.010492) (xy 298.747796 -88.011013) (xy 298.834963 -88.019623) (xy 298.920859 -88.036768)
			(xy 299.004652 -88.062281) (xy 299.085528 -88.095917) (xy 299.12437 -88.116156) (xy 299.1485 -88.122252)
			(xy 299.17263 -88.116156) (xy 299.211475 -88.095926) (xy 299.29236 -88.062325) (xy 299.376154 -88.036828)
			(xy 299.462046 -88.019682) (xy 299.549207 -88.011052) (xy 299.593 -88.010492) (xy 299.593508 -88.010492)
			(xy 299.639804 -88.011102) (xy 299.731892 -88.02075) (xy 299.82248 -88.039911) (xy 299.910588 -88.068375)
			(xy 299.995263 -88.105837) (xy 300.035722 -88.128348) (xy 300.060868 -88.135206) (xy 328.9808 -88.135206)
			(xy 329.011501 -88.135651) (xy 329.072456 -88.143053) (xy 329.132074 -88.157747) (xy 329.189487 -88.179521)
			(xy 329.243856 -88.208056) (xy 329.294389 -88.242937) (xy 329.340349 -88.283655) (xy 329.381066 -88.329616)
			(xy 329.415947 -88.380149) (xy 329.444481 -88.434519) (xy 329.466255 -88.491931) (xy 329.480949 -88.55155)
			(xy 329.488349 -88.612505) (xy 329.4888 -88.643206) (xy 329.4888 -92.500196) (xy 334.864964 -92.500196)
			(xy 334.864964 -87.500206) (xy 334.865459 -87.399365) (xy 334.873377 -87.197838) (xy 334.889201 -86.996778)
			(xy 334.912906 -86.796494) (xy 334.944456 -86.597295) (xy 334.983802 -86.399488) (xy 335.030884 -86.203379)
			(xy 335.085629 -86.009269) (xy 335.147952 -85.817458) (xy 335.217757 -85.628241) (xy 335.294938 -85.441912)
			(xy 335.379374 -85.258755) (xy 335.470936 -85.079055) (xy 335.569482 -84.903089) (xy 335.67486 -84.731126)
			(xy 335.786909 -84.563434) (xy 335.905455 -84.40027) (xy 336.030315 -84.241885) (xy 336.161297 -84.088525)
			(xy 336.298199 -83.940425) (xy 336.440809 -83.797815) (xy 336.588909 -83.660913) (xy 336.742269 -83.529931)
			(xy 336.900654 -83.405071) (xy 337.063818 -83.286525) (xy 337.23151 -83.174476) (xy 337.403473 -83.069098)
			(xy 337.579439 -82.970552) (xy 337.759139 -82.87899) (xy 337.942296 -82.794554) (xy 338.128625 -82.717373)
			(xy 338.317842 -82.647568) (xy 338.509653 -82.585245) (xy 338.703763 -82.5305) (xy 338.899872 -82.483418)
			(xy 339.097679 -82.444072) (xy 339.296878 -82.412522) (xy 339.497162 -82.388817) (xy 339.698222 -82.372993)
			(xy 339.899749 -82.365075) (xy 340.101431 -82.365075) (xy 340.302958 -82.372993) (xy 340.504018 -82.388817)
			(xy 340.704302 -82.412522) (xy 340.903501 -82.444072) (xy 341.101308 -82.483418) (xy 341.297417 -82.5305)
			(xy 341.491527 -82.585245) (xy 341.683338 -82.647568) (xy 341.872555 -82.717373) (xy 342.058884 -82.794554)
			(xy 342.242041 -82.87899) (xy 342.421741 -82.970552) (xy 342.597707 -83.069098) (xy 342.76967 -83.174476)
			(xy 342.937362 -83.286525) (xy 343.100526 -83.405071) (xy 343.258911 -83.529931) (xy 343.412271 -83.660913)
			(xy 343.560371 -83.797815) (xy 343.702981 -83.940425) (xy 343.839883 -84.088525) (xy 343.970865 -84.241885)
			(xy 344.095725 -84.40027) (xy 344.214271 -84.563434) (xy 344.32632 -84.731126) (xy 344.431698 -84.903089)
			(xy 344.530244 -85.079055) (xy 344.621806 -85.258755) (xy 344.706242 -85.441912) (xy 344.783423 -85.628241)
			(xy 344.853228 -85.817458) (xy 344.915551 -86.009269) (xy 344.970296 -86.203379) (xy 345.017378 -86.399488)
			(xy 345.056724 -86.597295) (xy 345.088274 -86.796494) (xy 345.111979 -86.996778) (xy 345.127803 -87.197838)
			(xy 345.135721 -87.399365) (xy 345.136216 -87.500206) (xy 345.136216 -91.559888) (xy 376.553741 -91.559888)
			(xy 376.557716 -91.449829) (xy 376.569624 -91.340343) (xy 376.5894 -91.232002) (xy 376.616943 -91.125371)
			(xy 376.652108 -91.021005) (xy 376.694712 -90.919448) (xy 376.744533 -90.821231) (xy 376.801312 -90.726864)
			(xy 376.864751 -90.63684) (xy 376.934522 -90.551629) (xy 377.010259 -90.471674) (xy 377.091568 -90.397393)
			(xy 377.178025 -90.329173) (xy 377.269179 -90.267368) (xy 377.364556 -90.212303) (xy 377.463657 -90.164263)
			(xy 377.565966 -90.123499) (xy 377.67095 -90.090224) (xy 377.778061 -90.064611) (xy 377.886741 -90.046794)
			(xy 377.996424 -90.036865) (xy 378.106537 -90.034877) (xy 378.216507 -90.040839) (xy 378.32576 -90.054721)
			(xy 378.433726 -90.076451) (xy 378.539843 -90.105914) (xy 378.643557 -90.142957) (xy 378.744328 -90.187388)
			(xy 378.84163 -90.238975) (xy 378.934956 -90.297447) (xy 379.023819 -90.362502) (xy 379.107757 -90.4338)
			(xy 379.186332 -90.510968) (xy 379.259133 -90.593605) (xy 379.325781 -90.681279) (xy 379.38593 -90.773535)
			(xy 379.439264 -90.86989) (xy 379.485507 -90.969842) (xy 379.524417 -91.07287) (xy 379.555791 -91.178438)
			(xy 379.579466 -91.285994) (xy 379.595318 -91.394978) (xy 379.603265 -91.504822) (xy 379.603762 -91.559888)
			(xy 396.111741 -91.559888) (xy 396.115716 -91.449829) (xy 396.127624 -91.340343) (xy 396.1474 -91.232002)
			(xy 396.174943 -91.125371) (xy 396.210108 -91.021005) (xy 396.252712 -90.919448) (xy 396.302533 -90.821231)
			(xy 396.359312 -90.726864) (xy 396.422751 -90.63684) (xy 396.492522 -90.551629) (xy 396.568259 -90.471674)
			(xy 396.649568 -90.397393) (xy 396.736025 -90.329173) (xy 396.827179 -90.267368) (xy 396.922556 -90.212303)
			(xy 397.021657 -90.164263) (xy 397.123966 -90.123499) (xy 397.22895 -90.090224) (xy 397.336061 -90.064611)
			(xy 397.444741 -90.046794) (xy 397.554424 -90.036865) (xy 397.664537 -90.034877) (xy 397.774507 -90.040839)
			(xy 397.88376 -90.054721) (xy 397.991726 -90.076451) (xy 398.097843 -90.105914) (xy 398.201557 -90.142957)
			(xy 398.302328 -90.187388) (xy 398.39963 -90.238975) (xy 398.492956 -90.297447) (xy 398.581819 -90.362502)
			(xy 398.665757 -90.4338) (xy 398.744332 -90.510968) (xy 398.817133 -90.593605) (xy 398.883781 -90.681279)
			(xy 398.94393 -90.773535) (xy 398.997264 -90.86989) (xy 399.043507 -90.969842) (xy 399.082417 -91.07287)
			(xy 399.113791 -91.178438) (xy 399.137466 -91.285994) (xy 399.153318 -91.394978) (xy 399.161265 -91.504822)
			(xy 399.161762 -91.559888) (xy 399.161265 -91.614954) (xy 399.153318 -91.724798) (xy 399.137466 -91.833782)
			(xy 399.113791 -91.941338) (xy 399.082417 -92.046906) (xy 399.043507 -92.149934) (xy 398.997264 -92.249886)
			(xy 398.94393 -92.346241) (xy 398.883781 -92.438497) (xy 398.817133 -92.526171) (xy 398.744332 -92.608808)
			(xy 398.665757 -92.685976) (xy 398.581819 -92.757274) (xy 398.492956 -92.822329) (xy 398.39963 -92.880801)
			(xy 398.302328 -92.932388) (xy 398.201557 -92.976819) (xy 398.097843 -93.013862) (xy 397.991726 -93.043325)
			(xy 397.88376 -93.065055) (xy 397.774507 -93.078937) (xy 397.664537 -93.084899) (xy 397.554424 -93.082911)
			(xy 397.444741 -93.072982) (xy 397.336061 -93.055165) (xy 397.22895 -93.029552) (xy 397.123966 -92.996277)
			(xy 397.021657 -92.955513) (xy 396.922556 -92.907473) (xy 396.827179 -92.852408) (xy 396.736025 -92.790603)
			(xy 396.649568 -92.722383) (xy 396.568259 -92.648102) (xy 396.492522 -92.568147) (xy 396.422751 -92.482936)
			(xy 396.359312 -92.392912) (xy 396.302533 -92.298545) (xy 396.252712 -92.200328) (xy 396.210108 -92.098771)
			(xy 396.174943 -91.994405) (xy 396.1474 -91.887774) (xy 396.127624 -91.779433) (xy 396.115716 -91.669947)
			(xy 396.111741 -91.559888) (xy 379.603762 -91.559888) (xy 379.603265 -91.614954) (xy 379.595318 -91.724798)
			(xy 379.579466 -91.833782) (xy 379.555791 -91.941338) (xy 379.524417 -92.046906) (xy 379.485507 -92.149934)
			(xy 379.439264 -92.249886) (xy 379.38593 -92.346241) (xy 379.325781 -92.438497) (xy 379.259133 -92.526171)
			(xy 379.186332 -92.608808) (xy 379.107757 -92.685976) (xy 379.023819 -92.757274) (xy 378.934956 -92.822329)
			(xy 378.84163 -92.880801) (xy 378.744328 -92.932388) (xy 378.643557 -92.976819) (xy 378.539843 -93.013862)
			(xy 378.433726 -93.043325) (xy 378.32576 -93.065055) (xy 378.216507 -93.078937) (xy 378.106537 -93.084899)
			(xy 377.996424 -93.082911) (xy 377.886741 -93.072982) (xy 377.778061 -93.055165) (xy 377.67095 -93.029552)
			(xy 377.565966 -92.996277) (xy 377.463657 -92.955513) (xy 377.364556 -92.907473) (xy 377.269179 -92.852408)
			(xy 377.178025 -92.790603) (xy 377.091568 -92.722383) (xy 377.010259 -92.648102) (xy 376.934522 -92.568147)
			(xy 376.864751 -92.482936) (xy 376.801312 -92.392912) (xy 376.744533 -92.298545) (xy 376.694712 -92.200328)
			(xy 376.652108 -92.098771) (xy 376.616943 -91.994405) (xy 376.5894 -91.887774) (xy 376.569624 -91.779433)
			(xy 376.557716 -91.669947) (xy 376.553741 -91.559888) (xy 345.136216 -91.559888) (xy 345.136216 -92.500196)
			(xy 345.135721 -92.601037) (xy 345.127803 -92.802564) (xy 345.111979 -93.003624) (xy 345.088274 -93.203908)
			(xy 345.056724 -93.403107) (xy 345.017378 -93.600914) (xy 344.970296 -93.797023) (xy 344.915551 -93.991133)
			(xy 344.853228 -94.182944) (xy 344.783423 -94.372161) (xy 344.706242 -94.55849) (xy 344.621806 -94.741647)
			(xy 344.530244 -94.921347) (xy 344.431698 -95.097313) (xy 344.32632 -95.269276) (xy 344.214271 -95.436968)
			(xy 344.095725 -95.600132) (xy 343.970865 -95.758517) (xy 343.839883 -95.911877) (xy 343.702981 -96.059977)
			(xy 343.560371 -96.202587) (xy 343.412271 -96.339489) (xy 343.258911 -96.470471) (xy 343.100526 -96.595331)
			(xy 342.937362 -96.713877) (xy 342.76967 -96.825926) (xy 342.597707 -96.931304) (xy 342.421741 -97.02985)
			(xy 342.242041 -97.121412) (xy 342.058884 -97.205848) (xy 341.872555 -97.283029) (xy 341.683338 -97.352834)
			(xy 341.491527 -97.415157) (xy 341.297417 -97.469902) (xy 341.101308 -97.516984) (xy 340.903501 -97.55633)
			(xy 340.704302 -97.58788) (xy 340.504018 -97.611585) (xy 340.302958 -97.627409) (xy 340.101431 -97.635327)
			(xy 339.899749 -97.635327) (xy 339.698222 -97.627409) (xy 339.497162 -97.611585) (xy 339.296878 -97.58788)
			(xy 339.097679 -97.55633) (xy 338.899872 -97.516984) (xy 338.703763 -97.469902) (xy 338.509653 -97.415157)
			(xy 338.317842 -97.352834) (xy 338.128625 -97.283029) (xy 337.942296 -97.205848) (xy 337.759139 -97.121412)
			(xy 337.579439 -97.02985) (xy 337.403473 -96.931304) (xy 337.23151 -96.825926) (xy 337.063818 -96.713877)
			(xy 336.900654 -96.595331) (xy 336.742269 -96.470471) (xy 336.588909 -96.339489) (xy 336.440809 -96.202587)
			(xy 336.298199 -96.059977) (xy 336.161297 -95.911877) (xy 336.030315 -95.758517) (xy 335.905455 -95.600132)
			(xy 335.786909 -95.436968) (xy 335.67486 -95.269276) (xy 335.569482 -95.097313) (xy 335.470936 -94.921347)
			(xy 335.379374 -94.741647) (xy 335.294938 -94.55849) (xy 335.217757 -94.372161) (xy 335.147952 -94.182944)
			(xy 335.085629 -93.991133) (xy 335.030884 -93.797023) (xy 334.983802 -93.600914) (xy 334.944456 -93.403107)
			(xy 334.912906 -93.203908) (xy 334.889201 -93.003624) (xy 334.873377 -92.802564) (xy 334.865459 -92.601037)
			(xy 334.864964 -92.500196) (xy 329.4888 -92.500196) (xy 329.4888 -99.06) (xy 377.061486 -99.06) (xy 377.065468 -98.970072)
			(xy 377.077382 -98.880848) (xy 377.097135 -98.793026) (xy 377.124572 -98.707293) (xy 377.159479 -98.624321)
			(xy 377.201583 -98.544758) (xy 377.250553 -98.469228) (xy 377.306008 -98.398322) (xy 377.367512 -98.332594)
			(xy 377.434584 -98.272559) (xy 377.5067 -98.218687) (xy 377.583295 -98.171399) (xy 377.663769 -98.131066)
			(xy 377.747493 -98.098003) (xy 377.833812 -98.072469) (xy 377.92205 -98.054664) (xy 378.011515 -98.044726)
			(xy 378.10151 -98.042735) (xy 378.191327 -98.048705) (xy 378.280266 -98.06259) (xy 378.36763 -98.084281)
			(xy 378.452735 -98.113608) (xy 378.534914 -98.150342) (xy 378.613526 -98.194196) (xy 378.687954 -98.244825)
			(xy 378.757616 -98.301835) (xy 378.821967 -98.364778) (xy 378.880504 -98.433162) (xy 378.932767 -98.506452)
			(xy 378.978349 -98.584074) (xy 379.016892 -98.665421) (xy 379.048095 -98.749856) (xy 379.071713 -98.836718)
			(xy 379.087562 -98.925328) (xy 379.095518 -99.014992) (xy 379.096016 -99.06) (xy 396.619486 -99.06)
			(xy 396.623468 -98.970072) (xy 396.635382 -98.880848) (xy 396.655135 -98.793026) (xy 396.682572 -98.707293)
			(xy 396.717479 -98.624321) (xy 396.759583 -98.544758) (xy 396.808553 -98.469228) (xy 396.864008 -98.398322)
			(xy 396.925512 -98.332594) (xy 396.992584 -98.272559) (xy 397.0647 -98.218687) (xy 397.141295 -98.171399)
			(xy 397.221769 -98.131066) (xy 397.305493 -98.098003) (xy 397.391812 -98.072469) (xy 397.48005 -98.054664)
			(xy 397.569515 -98.044726) (xy 397.65951 -98.042735) (xy 397.749327 -98.048705) (xy 397.838266 -98.06259)
			(xy 397.92563 -98.084281) (xy 398.010735 -98.113608) (xy 398.092914 -98.150342) (xy 398.171526 -98.194196)
			(xy 398.245954 -98.244825) (xy 398.315616 -98.301835) (xy 398.379967 -98.364778) (xy 398.438504 -98.433162)
			(xy 398.490767 -98.506452) (xy 398.536349 -98.584074) (xy 398.574892 -98.665421) (xy 398.606095 -98.749856)
			(xy 398.629713 -98.836718) (xy 398.645562 -98.925328) (xy 398.653518 -99.014992) (xy 398.654016 -99.06)
			(xy 398.653518 -99.105008) (xy 398.645562 -99.194672) (xy 398.629713 -99.283282) (xy 398.606095 -99.370144)
			(xy 398.574892 -99.454579) (xy 398.536349 -99.535926) (xy 398.490767 -99.613548) (xy 398.438504 -99.686838)
			(xy 398.379967 -99.755222) (xy 398.315616 -99.818165) (xy 398.245954 -99.875175) (xy 398.171526 -99.925804)
			(xy 398.092914 -99.969658) (xy 398.010735 -100.006392) (xy 397.92563 -100.035719) (xy 397.838266 -100.05741)
			(xy 397.749327 -100.071295) (xy 397.65951 -100.077265) (xy 397.569515 -100.075274) (xy 397.48005 -100.065336)
			(xy 397.391812 -100.047531) (xy 397.305493 -100.021997) (xy 397.221769 -99.988934) (xy 397.141295 -99.948601)
			(xy 397.0647 -99.901313) (xy 396.992584 -99.847441) (xy 396.925512 -99.787406) (xy 396.864008 -99.721678)
			(xy 396.808553 -99.650772) (xy 396.759583 -99.575242) (xy 396.717479 -99.495679) (xy 396.682572 -99.412707)
			(xy 396.655135 -99.326974) (xy 396.635382 -99.239152) (xy 396.623468 -99.149928) (xy 396.619486 -99.06)
			(xy 379.096016 -99.06) (xy 379.095518 -99.105008) (xy 379.087562 -99.194672) (xy 379.071713 -99.283282)
			(xy 379.048095 -99.370144) (xy 379.016892 -99.454579) (xy 378.978349 -99.535926) (xy 378.932767 -99.613548)
			(xy 378.880504 -99.686838) (xy 378.821967 -99.755222) (xy 378.757616 -99.818165) (xy 378.687954 -99.875175)
			(xy 378.613526 -99.925804) (xy 378.534914 -99.969658) (xy 378.452735 -100.006392) (xy 378.36763 -100.035719)
			(xy 378.280266 -100.05741) (xy 378.191327 -100.071295) (xy 378.10151 -100.077265) (xy 378.011515 -100.075274)
			(xy 377.92205 -100.065336) (xy 377.833812 -100.047531) (xy 377.747493 -100.021997) (xy 377.663769 -99.988934)
			(xy 377.583295 -99.948601) (xy 377.5067 -99.901313) (xy 377.434584 -99.847441) (xy 377.367512 -99.787406)
			(xy 377.306008 -99.721678) (xy 377.250553 -99.650772) (xy 377.201583 -99.575242) (xy 377.159479 -99.495679)
			(xy 377.124572 -99.412707) (xy 377.097135 -99.326974) (xy 377.077382 -99.239152) (xy 377.065468 -99.149928)
			(xy 377.061486 -99.06) (xy 329.4888 -99.06) (xy 329.4888 -101.399086) (xy 329.48916 -101.408135)
			(xy 329.495436 -101.425111) (xy 329.507211 -101.438854) (xy 329.514962 -101.443536) (xy 329.59294 -101.486462)
			(xy 329.598604 -101.489401) (xy 329.610946 -101.492625) (xy 329.617324 -101.492812) (xy 329.644502 -101.484938)
			(xy 329.680034 -101.463133) (xy 329.754426 -101.425494) (xy 329.832013 -101.394979) (xy 329.912114 -101.371856)
			(xy 329.994027 -101.356328) (xy 330.077034 -101.348531) (xy 330.11872 -101.348032) (xy 330.161198 -101.348532)
			(xy 330.245766 -101.356641) (xy 330.329177 -101.372774) (xy 330.41067 -101.396784) (xy 330.489503 -101.428452)
			(xy 330.564959 -101.46749) (xy 330.63635 -101.513543) (xy 330.703026 -101.566191) (xy 330.764381 -101.624955)
			(xy 330.819855 -101.689299) (xy 330.868944 -101.758637) (xy 330.9112 -101.83234) (xy 330.946238 -101.909734)
			(xy 330.960476 -101.949758) (xy 330.96581 -101.965252) (xy 330.991972 -101.984048) (xy 334.325468 -101.984048)
			(xy 334.35163 -101.965252) (xy 334.356964 -101.949758) (xy 334.371175 -101.90972) (xy 334.406201 -101.832311)
			(xy 334.448448 -101.758595) (xy 334.497531 -101.689242) (xy 334.553003 -101.624885) (xy 334.614358 -101.56611)
			(xy 334.681038 -101.513453) (xy 334.752434 -101.467393) (xy 334.827897 -101.428351) (xy 334.906739 -101.396681)
			(xy 334.988241 -101.372673) (xy 335.07166 -101.356545) (xy 335.156238 -101.348444) (xy 335.241202 -101.348444)
			(xy 335.32578 -101.356545) (xy 335.409199 -101.372673) (xy 335.490701 -101.396681) (xy 335.569543 -101.428351)
			(xy 335.645006 -101.467393) (xy 335.716402 -101.513453) (xy 335.783082 -101.56611) (xy 335.844437 -101.624885)
			(xy 335.899909 -101.689242) (xy 335.948992 -101.758595) (xy 335.991239 -101.832311) (xy 336.026265 -101.90972)
			(xy 336.040476 -101.949758) (xy 336.04581 -101.965252) (xy 336.071972 -101.984048) (xy 339.405468 -101.984048)
			(xy 339.43163 -101.965252) (xy 339.436964 -101.949758) (xy 339.451175 -101.90972) (xy 339.486201 -101.832311)
			(xy 339.528448 -101.758595) (xy 339.577531 -101.689242) (xy 339.633003 -101.624885) (xy 339.694358 -101.56611)
			(xy 339.761038 -101.513453) (xy 339.832434 -101.467393) (xy 339.907897 -101.428351) (xy 339.986739 -101.396681)
			(xy 340.068241 -101.372673) (xy 340.15166 -101.356545) (xy 340.236238 -101.348444) (xy 340.321202 -101.348444)
			(xy 340.40578 -101.356545) (xy 340.489199 -101.372673) (xy 340.570701 -101.396681) (xy 340.649543 -101.428351)
			(xy 340.725006 -101.467393) (xy 340.796402 -101.513453) (xy 340.863082 -101.56611) (xy 340.924437 -101.624885)
			(xy 340.979909 -101.689242) (xy 341.028992 -101.758595) (xy 341.071239 -101.832311) (xy 341.106265 -101.90972)
			(xy 341.120476 -101.949758) (xy 341.12581 -101.965252) (xy 341.151972 -101.984048) (xy 344.000074 -101.984048)
			(xy 344.122446 -101.984525) (xy 344.367086 -101.991637) (xy 344.489278 -101.998272) (xy 344.499435 -101.998447)
			(xy 344.518585 -101.99172) (xy 344.533609 -101.978073) (xy 344.5383 -101.969062) (xy 344.556553 -101.931268)
			(xy 344.599182 -101.858962) (xy 344.648434 -101.790994) (xy 344.703872 -101.72797) (xy 344.765002 -101.67045)
			(xy 344.83128 -101.618946) (xy 344.902117 -101.573917) (xy 344.976881 -101.535764) (xy 345.054908 -101.504825)
			(xy 345.135502 -101.481376) (xy 345.217948 -101.465625) (xy 345.301512 -101.457714) (xy 345.34348 -101.457252)
			(xy 345.386739 -101.457766) (xy 345.472848 -101.466164) (xy 345.557735 -101.482882) (xy 345.640598 -101.507763)
			(xy 345.720654 -101.540571) (xy 345.797147 -101.580996) (xy 345.869353 -101.628657) (xy 345.936591 -101.683103)
			(xy 345.998226 -101.74382) (xy 346.053674 -101.810234) (xy 346.102413 -101.881717) (xy 346.143981 -101.957595)
			(xy 346.177986 -102.03715) (xy 346.204107 -102.11963) (xy 346.222097 -102.204257) (xy 346.2274 -102.247192)
			(xy 346.228993 -102.257191) (xy 346.238893 -102.274833) (xy 346.254844 -102.287275) (xy 346.264484 -102.290372)
			(xy 346.388577 -102.325108) (xy 346.634834 -102.401133) (xy 346.878677 -102.484575) (xy 347.119884 -102.575356)
			(xy 347.358234 -102.673394) (xy 347.593508 -102.778599) (xy 347.825491 -102.890874) (xy 348.053971 -103.010118)
			(xy 348.278738 -103.13622) (xy 348.499587 -103.269065) (xy 348.716315 -103.408532) (xy 348.928723 -103.554493)
			(xy 349.136618 -103.706814) (xy 349.339809 -103.865355) (xy 349.53811 -104.029972) (xy 349.731339 -104.200514)
			(xy 349.91932 -104.376825) (xy 350.10188 -104.558742) (xy 350.278851 -104.7461) (xy 350.450073 -104.938727)
			(xy 350.615388 -105.136447) (xy 350.774644 -105.339078) (xy 350.927697 -105.546435) (xy 351.074405 -105.758328)
			(xy 351.214635 -105.974563) (xy 351.348257 -106.194943) (xy 351.475151 -106.419264) (xy 351.595198 -106.647322)
			(xy 351.708291 -106.878908) (xy 351.814324 -107.11381) (xy 351.913201 -107.351813) (xy 352.004832 -107.592699)
			(xy 352.089132 -107.836247) (xy 352.166024 -108.082234) (xy 352.235437 -108.330435) (xy 352.29731 -108.580622)
			(xy 352.351583 -108.832568) (xy 352.398209 -109.08604) (xy 352.437144 -109.340806) (xy 352.453194 -109.468666)
			(xy 352.49104 -109.511592) (xy 352.531446 -109.522561) (xy 352.610166 -109.55109) (xy 352.685858 -109.586889)
			(xy 352.757853 -109.629641) (xy 352.825512 -109.678967) (xy 352.888238 -109.734431) (xy 352.945476 -109.795543)
			(xy 352.99672 -109.861762) (xy 353.041515 -109.932502) (xy 353.079467 -110.007138) (xy 353.11024 -110.085009)
			(xy 353.13356 -110.165427) (xy 353.149222 -110.24768) (xy 353.157088 -110.331041) (xy 353.157536 -110.372906)
			(xy 353.157031 -110.415602) (xy 353.148849 -110.5006) (xy 353.132559 -110.584423) (xy 353.108313 -110.6663)
			(xy 353.076333 -110.745477) (xy 353.036914 -110.821225) (xy 352.990418 -110.892848) (xy 352.937273 -110.959686)
			(xy 352.877968 -111.021124) (xy 352.813049 -111.076597) (xy 352.743114 -111.125595) (xy 352.668806 -111.167666)
			(xy 352.590808 -111.202423) (xy 352.550476 -111.21644) (xy 352.534982 -111.221774) (xy 352.515932 -111.24819)
			(xy 352.515932 -111.879888) (xy 376.553741 -111.879888) (xy 376.557716 -111.769829) (xy 376.569624 -111.660343)
			(xy 376.5894 -111.552002) (xy 376.616943 -111.445371) (xy 376.652108 -111.341005) (xy 376.694712 -111.239448)
			(xy 376.744533 -111.141231) (xy 376.801312 -111.046864) (xy 376.864751 -110.95684) (xy 376.934522 -110.871629)
			(xy 377.010259 -110.791674) (xy 377.091568 -110.717393) (xy 377.178025 -110.649173) (xy 377.269179 -110.587368)
			(xy 377.364556 -110.532303) (xy 377.463657 -110.484263) (xy 377.565966 -110.443499) (xy 377.67095 -110.410224)
			(xy 377.778061 -110.384611) (xy 377.886741 -110.366794) (xy 377.996424 -110.356865) (xy 378.106537 -110.354877)
			(xy 378.216507 -110.360839) (xy 378.32576 -110.374721) (xy 378.433726 -110.396451) (xy 378.539843 -110.425914)
			(xy 378.643557 -110.462957) (xy 378.744328 -110.507388) (xy 378.84163 -110.558975) (xy 378.934956 -110.617447)
			(xy 379.023819 -110.682502) (xy 379.107757 -110.7538) (xy 379.186332 -110.830968) (xy 379.259133 -110.913605)
			(xy 379.325781 -111.001279) (xy 379.38593 -111.093535) (xy 379.439264 -111.18989) (xy 379.485507 -111.289842)
			(xy 379.524417 -111.39287) (xy 379.555791 -111.498438) (xy 379.579466 -111.605994) (xy 379.595318 -111.714978)
			(xy 379.603265 -111.824822) (xy 379.603762 -111.879888) (xy 396.111741 -111.879888) (xy 396.115716 -111.769829)
			(xy 396.127624 -111.660343) (xy 396.1474 -111.552002) (xy 396.174943 -111.445371) (xy 396.210108 -111.341005)
			(xy 396.252712 -111.239448) (xy 396.302533 -111.141231) (xy 396.359312 -111.046864) (xy 396.422751 -110.95684)
			(xy 396.492522 -110.871629) (xy 396.568259 -110.791674) (xy 396.649568 -110.717393) (xy 396.736025 -110.649173)
			(xy 396.827179 -110.587368) (xy 396.922556 -110.532303) (xy 397.021657 -110.484263) (xy 397.123966 -110.443499)
			(xy 397.22895 -110.410224) (xy 397.336061 -110.384611) (xy 397.444741 -110.366794) (xy 397.554424 -110.356865)
			(xy 397.664537 -110.354877) (xy 397.774507 -110.360839) (xy 397.88376 -110.374721) (xy 397.991726 -110.396451)
			(xy 398.097843 -110.425914) (xy 398.201557 -110.462957) (xy 398.302328 -110.507388) (xy 398.39963 -110.558975)
			(xy 398.492956 -110.617447) (xy 398.581819 -110.682502) (xy 398.665757 -110.7538) (xy 398.744332 -110.830968)
			(xy 398.817133 -110.913605) (xy 398.883781 -111.001279) (xy 398.94393 -111.093535) (xy 398.997264 -111.18989)
			(xy 399.043507 -111.289842) (xy 399.082417 -111.39287) (xy 399.113791 -111.498438) (xy 399.137466 -111.605994)
			(xy 399.153318 -111.714978) (xy 399.161265 -111.824822) (xy 399.161762 -111.879888) (xy 399.161265 -111.934954)
			(xy 399.153318 -112.044798) (xy 399.137466 -112.153782) (xy 399.113791 -112.261338) (xy 399.082417 -112.366906)
			(xy 399.043507 -112.469934) (xy 398.997264 -112.569886) (xy 398.94393 -112.666241) (xy 398.883781 -112.758497)
			(xy 398.817133 -112.846171) (xy 398.744332 -112.928808) (xy 398.665757 -113.005976) (xy 398.581819 -113.077274)
			(xy 398.492956 -113.142329) (xy 398.39963 -113.200801) (xy 398.302328 -113.252388) (xy 398.201557 -113.296819)
			(xy 398.097843 -113.333862) (xy 397.991726 -113.363325) (xy 397.88376 -113.385055) (xy 397.774507 -113.398937)
			(xy 397.664537 -113.404899) (xy 397.554424 -113.402911) (xy 397.444741 -113.392982) (xy 397.336061 -113.375165)
			(xy 397.22895 -113.349552) (xy 397.123966 -113.316277) (xy 397.021657 -113.275513) (xy 396.922556 -113.227473)
			(xy 396.827179 -113.172408) (xy 396.736025 -113.110603) (xy 396.649568 -113.042383) (xy 396.568259 -112.968102)
			(xy 396.492522 -112.888147) (xy 396.422751 -112.802936) (xy 396.359312 -112.712912) (xy 396.302533 -112.618545)
			(xy 396.252712 -112.520328) (xy 396.210108 -112.418771) (xy 396.174943 -112.314405) (xy 396.1474 -112.207774)
			(xy 396.127624 -112.099433) (xy 396.115716 -111.989947) (xy 396.111741 -111.879888) (xy 379.603762 -111.879888)
			(xy 379.603265 -111.934954) (xy 379.595318 -112.044798) (xy 379.579466 -112.153782) (xy 379.555791 -112.261338)
			(xy 379.524417 -112.366906) (xy 379.485507 -112.469934) (xy 379.439264 -112.569886) (xy 379.38593 -112.666241)
			(xy 379.325781 -112.758497) (xy 379.259133 -112.846171) (xy 379.186332 -112.928808) (xy 379.107757 -113.005976)
			(xy 379.023819 -113.077274) (xy 378.934956 -113.142329) (xy 378.84163 -113.200801) (xy 378.744328 -113.252388)
			(xy 378.643557 -113.296819) (xy 378.539843 -113.333862) (xy 378.433726 -113.363325) (xy 378.32576 -113.385055)
			(xy 378.216507 -113.398937) (xy 378.106537 -113.404899) (xy 377.996424 -113.402911) (xy 377.886741 -113.392982)
			(xy 377.778061 -113.375165) (xy 377.67095 -113.349552) (xy 377.565966 -113.316277) (xy 377.463657 -113.275513)
			(xy 377.364556 -113.227473) (xy 377.269179 -113.172408) (xy 377.178025 -113.110603) (xy 377.091568 -113.042383)
			(xy 377.010259 -112.968102) (xy 376.934522 -112.888147) (xy 376.864751 -112.802936) (xy 376.801312 -112.712912)
			(xy 376.744533 -112.618545) (xy 376.694712 -112.520328) (xy 376.652108 -112.418771) (xy 376.616943 -112.314405)
			(xy 376.5894 -112.207774) (xy 376.569624 -112.099433) (xy 376.557716 -111.989947) (xy 376.553741 -111.879888)
			(xy 352.515932 -111.879888) (xy 352.515932 -114.561366) (xy 352.516448 -114.571942) (xy 352.524971 -114.591297)
			(xy 352.540609 -114.605534) (xy 352.550476 -114.609372) (xy 352.590802 -114.623408) (xy 352.668804 -114.658159)
			(xy 352.743117 -114.700224) (xy 352.813057 -114.749217) (xy 352.87798 -114.804686) (xy 352.93729 -114.866121)
			(xy 352.990439 -114.932958) (xy 353.036938 -115.004579) (xy 353.076361 -115.080327) (xy 353.108343 -115.159504)
			(xy 353.132591 -115.241382) (xy 353.148881 -115.325206) (xy 353.157064 -115.410206) (xy 353.157064 -115.495598)
			(xy 353.148881 -115.580598) (xy 353.13259 -115.664422) (xy 353.108342 -115.746299) (xy 353.076359 -115.825476)
			(xy 353.036936 -115.901224) (xy 352.990436 -115.972846) (xy 352.937287 -116.039681) (xy 352.877978 -116.101117)
			(xy 352.813054 -116.156586) (xy 352.743114 -116.205578) (xy 352.668801 -116.247643) (xy 352.590799 -116.282393)
			(xy 352.550476 -116.29644) (xy 352.534982 -116.301774) (xy 352.515932 -116.32819) (xy 352.515932 -119.38)
			(xy 377.061486 -119.38) (xy 377.065468 -119.290072) (xy 377.077382 -119.200848) (xy 377.097135 -119.113026)
			(xy 377.124572 -119.027293) (xy 377.159479 -118.944321) (xy 377.201583 -118.864758) (xy 377.250553 -118.789228)
			(xy 377.306008 -118.718322) (xy 377.367512 -118.652594) (xy 377.434584 -118.592559) (xy 377.5067 -118.538687)
			(xy 377.583295 -118.491399) (xy 377.663769 -118.451066) (xy 377.747493 -118.418003) (xy 377.833812 -118.392469)
			(xy 377.92205 -118.374664) (xy 378.011515 -118.364726) (xy 378.10151 -118.362735) (xy 378.191327 -118.368705)
			(xy 378.280266 -118.38259) (xy 378.36763 -118.404281) (xy 378.452735 -118.433608) (xy 378.534914 -118.470342)
			(xy 378.613526 -118.514196) (xy 378.687954 -118.564825) (xy 378.757616 -118.621835) (xy 378.821967 -118.684778)
			(xy 378.880504 -118.753162) (xy 378.932767 -118.826452) (xy 378.978349 -118.904074) (xy 379.016892 -118.985421)
			(xy 379.048095 -119.069856) (xy 379.071713 -119.156718) (xy 379.087562 -119.245328) (xy 379.095518 -119.334992)
			(xy 379.096016 -119.38) (xy 396.619486 -119.38) (xy 396.623468 -119.290072) (xy 396.635382 -119.200848)
			(xy 396.655135 -119.113026) (xy 396.682572 -119.027293) (xy 396.717479 -118.944321) (xy 396.759583 -118.864758)
			(xy 396.808553 -118.789228) (xy 396.864008 -118.718322) (xy 396.925512 -118.652594) (xy 396.992584 -118.592559)
			(xy 397.0647 -118.538687) (xy 397.141295 -118.491399) (xy 397.221769 -118.451066) (xy 397.305493 -118.418003)
			(xy 397.391812 -118.392469) (xy 397.48005 -118.374664) (xy 397.569515 -118.364726) (xy 397.65951 -118.362735)
			(xy 397.749327 -118.368705) (xy 397.838266 -118.38259) (xy 397.92563 -118.404281) (xy 398.010735 -118.433608)
			(xy 398.092914 -118.470342) (xy 398.171526 -118.514196) (xy 398.245954 -118.564825) (xy 398.315616 -118.621835)
			(xy 398.379967 -118.684778) (xy 398.438504 -118.753162) (xy 398.490767 -118.826452) (xy 398.536349 -118.904074)
			(xy 398.574892 -118.985421) (xy 398.606095 -119.069856) (xy 398.629713 -119.156718) (xy 398.645562 -119.245328)
			(xy 398.653518 -119.334992) (xy 398.654016 -119.38) (xy 398.653518 -119.425008) (xy 398.645562 -119.514672)
			(xy 398.629713 -119.603282) (xy 398.606095 -119.690144) (xy 398.574892 -119.774579) (xy 398.536349 -119.855926)
			(xy 398.490767 -119.933548) (xy 398.438504 -120.006838) (xy 398.379967 -120.075222) (xy 398.315616 -120.138165)
			(xy 398.245954 -120.195175) (xy 398.171526 -120.245804) (xy 398.092914 -120.289658) (xy 398.010735 -120.326392)
			(xy 397.92563 -120.355719) (xy 397.838266 -120.37741) (xy 397.749327 -120.391295) (xy 397.65951 -120.397265)
			(xy 397.569515 -120.395274) (xy 397.48005 -120.385336) (xy 397.391812 -120.367531) (xy 397.305493 -120.341997)
			(xy 397.221769 -120.308934) (xy 397.141295 -120.268601) (xy 397.0647 -120.221313) (xy 396.992584 -120.167441)
			(xy 396.925512 -120.107406) (xy 396.864008 -120.041678) (xy 396.808553 -119.970772) (xy 396.759583 -119.895242)
			(xy 396.717479 -119.815679) (xy 396.682572 -119.732707) (xy 396.655135 -119.646974) (xy 396.635382 -119.559152)
			(xy 396.623468 -119.469928) (xy 396.619486 -119.38) (xy 379.096016 -119.38) (xy 379.095518 -119.425008)
			(xy 379.087562 -119.514672) (xy 379.071713 -119.603282) (xy 379.048095 -119.690144) (xy 379.016892 -119.774579)
			(xy 378.978349 -119.855926) (xy 378.932767 -119.933548) (xy 378.880504 -120.006838) (xy 378.821967 -120.075222)
			(xy 378.757616 -120.138165) (xy 378.687954 -120.195175) (xy 378.613526 -120.245804) (xy 378.534914 -120.289658)
			(xy 378.452735 -120.326392) (xy 378.36763 -120.355719) (xy 378.280266 -120.37741) (xy 378.191327 -120.391295)
			(xy 378.10151 -120.397265) (xy 378.011515 -120.395274) (xy 377.92205 -120.385336) (xy 377.833812 -120.367531)
			(xy 377.747493 -120.341997) (xy 377.663769 -120.308934) (xy 377.583295 -120.268601) (xy 377.5067 -120.221313)
			(xy 377.434584 -120.167441) (xy 377.367512 -120.107406) (xy 377.306008 -120.041678) (xy 377.250553 -119.970772)
			(xy 377.201583 -119.895242) (xy 377.159479 -119.815679) (xy 377.124572 -119.732707) (xy 377.097135 -119.646974)
			(xy 377.077382 -119.559152) (xy 377.065468 -119.469928) (xy 377.061486 -119.38) (xy 352.515932 -119.38)
			(xy 352.515932 -119.641366) (xy 352.516448 -119.651942) (xy 352.524971 -119.671297) (xy 352.540609 -119.685534)
			(xy 352.550476 -119.689372) (xy 352.590802 -119.703408) (xy 352.668804 -119.738159) (xy 352.743117 -119.780224)
			(xy 352.813057 -119.829217) (xy 352.87798 -119.884686) (xy 352.93729 -119.946121) (xy 352.990439 -120.012958)
			(xy 353.036938 -120.084579) (xy 353.076361 -120.160327) (xy 353.108343 -120.239504) (xy 353.132591 -120.321382)
			(xy 353.148881 -120.405206) (xy 353.157064 -120.490206) (xy 353.157064 -120.575598) (xy 353.148881 -120.660598)
			(xy 353.13259 -120.744422) (xy 353.108342 -120.826299) (xy 353.076359 -120.905476) (xy 353.036936 -120.981224)
			(xy 352.990436 -121.052846) (xy 352.937287 -121.119681) (xy 352.877978 -121.181117) (xy 352.813054 -121.236586)
			(xy 352.743114 -121.285578) (xy 352.668801 -121.327643) (xy 352.590799 -121.362393) (xy 352.550476 -121.37644)
			(xy 352.534982 -121.381774) (xy 352.515932 -121.40819) (xy 352.515932 -124.721366) (xy 352.516448 -124.731942)
			(xy 352.524971 -124.751297) (xy 352.540609 -124.765534) (xy 352.550476 -124.769372) (xy 352.590802 -124.783408)
			(xy 352.668804 -124.818159) (xy 352.743117 -124.860224) (xy 352.813057 -124.909217) (xy 352.87798 -124.964686)
			(xy 352.93729 -125.026121) (xy 352.990439 -125.092958) (xy 353.036938 -125.164579) (xy 353.076361 -125.240327)
			(xy 353.108343 -125.319504) (xy 353.132591 -125.401382) (xy 353.148881 -125.485206) (xy 353.157064 -125.570206)
			(xy 353.157064 -125.655598) (xy 353.148881 -125.740598) (xy 353.13259 -125.824422) (xy 353.108342 -125.906299)
			(xy 353.076359 -125.985476) (xy 353.036936 -126.061224) (xy 352.990436 -126.132846) (xy 352.937287 -126.199681)
			(xy 352.877978 -126.261117) (xy 352.813054 -126.316586) (xy 352.743114 -126.365578) (xy 352.668801 -126.407643)
			(xy 352.590799 -126.442393) (xy 352.550476 -126.45644) (xy 352.534982 -126.461774) (xy 352.515932 -126.48819)
			(xy 352.515932 -129.801366) (xy 352.516448 -129.811942) (xy 352.524971 -129.831297) (xy 352.540609 -129.845534)
			(xy 352.550476 -129.849372) (xy 352.590802 -129.863408) (xy 352.668804 -129.898159) (xy 352.743117 -129.940224)
			(xy 352.813057 -129.989217) (xy 352.87798 -130.044686) (xy 352.93729 -130.106121) (xy 352.990439 -130.172958)
			(xy 353.036938 -130.244579) (xy 353.076361 -130.320327) (xy 353.108343 -130.399504) (xy 353.132591 -130.481382)
			(xy 353.148881 -130.565206) (xy 353.157064 -130.650206) (xy 353.157064 -130.735598) (xy 353.148881 -130.820598)
			(xy 353.13259 -130.904422) (xy 353.108342 -130.986299) (xy 353.076359 -131.065476) (xy 353.036936 -131.141224)
			(xy 352.990436 -131.212846) (xy 352.937287 -131.279681) (xy 352.877978 -131.341117) (xy 352.813054 -131.396586)
			(xy 352.743114 -131.445578) (xy 352.668801 -131.487643) (xy 352.590799 -131.522393) (xy 352.550476 -131.53644)
			(xy 352.534982 -131.541774) (xy 352.515932 -131.56819) (xy 352.515932 -132.199888) (xy 376.553741 -132.199888)
			(xy 376.557716 -132.089829) (xy 376.569624 -131.980343) (xy 376.5894 -131.872002) (xy 376.616943 -131.765371)
			(xy 376.652108 -131.661005) (xy 376.694712 -131.559448) (xy 376.744533 -131.461231) (xy 376.801312 -131.366864)
			(xy 376.864751 -131.27684) (xy 376.934522 -131.191629) (xy 377.010259 -131.111674) (xy 377.091568 -131.037393)
			(xy 377.178025 -130.969173) (xy 377.269179 -130.907368) (xy 377.364556 -130.852303) (xy 377.463657 -130.804263)
			(xy 377.565966 -130.763499) (xy 377.67095 -130.730224) (xy 377.778061 -130.704611) (xy 377.886741 -130.686794)
			(xy 377.996424 -130.676865) (xy 378.106537 -130.674877) (xy 378.216507 -130.680839) (xy 378.32576 -130.694721)
			(xy 378.433726 -130.716451) (xy 378.539843 -130.745914) (xy 378.643557 -130.782957) (xy 378.744328 -130.827388)
			(xy 378.84163 -130.878975) (xy 378.934956 -130.937447) (xy 379.023819 -131.002502) (xy 379.107757 -131.0738)
			(xy 379.186332 -131.150968) (xy 379.259133 -131.233605) (xy 379.325781 -131.321279) (xy 379.38593 -131.413535)
			(xy 379.439264 -131.50989) (xy 379.485507 -131.609842) (xy 379.524417 -131.71287) (xy 379.555791 -131.818438)
			(xy 379.579466 -131.925994) (xy 379.595318 -132.034978) (xy 379.603265 -132.144822) (xy 379.603762 -132.199888)
			(xy 396.111741 -132.199888) (xy 396.115716 -132.089829) (xy 396.127624 -131.980343) (xy 396.1474 -131.872002)
			(xy 396.174943 -131.765371) (xy 396.210108 -131.661005) (xy 396.252712 -131.559448) (xy 396.302533 -131.461231)
			(xy 396.359312 -131.366864) (xy 396.422751 -131.27684) (xy 396.492522 -131.191629) (xy 396.568259 -131.111674)
			(xy 396.649568 -131.037393) (xy 396.736025 -130.969173) (xy 396.827179 -130.907368) (xy 396.922556 -130.852303)
			(xy 397.021657 -130.804263) (xy 397.123966 -130.763499) (xy 397.22895 -130.730224) (xy 397.336061 -130.704611)
			(xy 397.444741 -130.686794) (xy 397.554424 -130.676865) (xy 397.664537 -130.674877) (xy 397.774507 -130.680839)
			(xy 397.88376 -130.694721) (xy 397.991726 -130.716451) (xy 398.097843 -130.745914) (xy 398.201557 -130.782957)
			(xy 398.302328 -130.827388) (xy 398.39963 -130.878975) (xy 398.492956 -130.937447) (xy 398.581819 -131.002502)
			(xy 398.665757 -131.0738) (xy 398.744332 -131.150968) (xy 398.817133 -131.233605) (xy 398.883781 -131.321279)
			(xy 398.94393 -131.413535) (xy 398.997264 -131.50989) (xy 399.043507 -131.609842) (xy 399.082417 -131.71287)
			(xy 399.113791 -131.818438) (xy 399.137466 -131.925994) (xy 399.153318 -132.034978) (xy 399.161265 -132.144822)
			(xy 399.161762 -132.199888) (xy 399.161265 -132.254954) (xy 399.153318 -132.364798) (xy 399.137466 -132.473782)
			(xy 399.113791 -132.581338) (xy 399.082417 -132.686906) (xy 399.043507 -132.789934) (xy 398.997264 -132.889886)
			(xy 398.94393 -132.986241) (xy 398.883781 -133.078497) (xy 398.817133 -133.166171) (xy 398.744332 -133.248808)
			(xy 398.665757 -133.325976) (xy 398.581819 -133.397274) (xy 398.492956 -133.462329) (xy 398.39963 -133.520801)
			(xy 398.302328 -133.572388) (xy 398.201557 -133.616819) (xy 398.097843 -133.653862) (xy 397.991726 -133.683325)
			(xy 397.88376 -133.705055) (xy 397.774507 -133.718937) (xy 397.664537 -133.724899) (xy 397.554424 -133.722911)
			(xy 397.444741 -133.712982) (xy 397.336061 -133.695165) (xy 397.22895 -133.669552) (xy 397.123966 -133.636277)
			(xy 397.021657 -133.595513) (xy 396.922556 -133.547473) (xy 396.827179 -133.492408) (xy 396.736025 -133.430603)
			(xy 396.649568 -133.362383) (xy 396.568259 -133.288102) (xy 396.492522 -133.208147) (xy 396.422751 -133.122936)
			(xy 396.359312 -133.032912) (xy 396.302533 -132.938545) (xy 396.252712 -132.840328) (xy 396.210108 -132.738771)
			(xy 396.174943 -132.634405) (xy 396.1474 -132.527774) (xy 396.127624 -132.419433) (xy 396.115716 -132.309947)
			(xy 396.111741 -132.199888) (xy 379.603762 -132.199888) (xy 379.603265 -132.254954) (xy 379.595318 -132.364798)
			(xy 379.579466 -132.473782) (xy 379.555791 -132.581338) (xy 379.524417 -132.686906) (xy 379.485507 -132.789934)
			(xy 379.439264 -132.889886) (xy 379.38593 -132.986241) (xy 379.325781 -133.078497) (xy 379.259133 -133.166171)
			(xy 379.186332 -133.248808) (xy 379.107757 -133.325976) (xy 379.023819 -133.397274) (xy 378.934956 -133.462329)
			(xy 378.84163 -133.520801) (xy 378.744328 -133.572388) (xy 378.643557 -133.616819) (xy 378.539843 -133.653862)
			(xy 378.433726 -133.683325) (xy 378.32576 -133.705055) (xy 378.216507 -133.718937) (xy 378.106537 -133.724899)
			(xy 377.996424 -133.722911) (xy 377.886741 -133.712982) (xy 377.778061 -133.695165) (xy 377.67095 -133.669552)
			(xy 377.565966 -133.636277) (xy 377.463657 -133.595513) (xy 377.364556 -133.547473) (xy 377.269179 -133.492408)
			(xy 377.178025 -133.430603) (xy 377.091568 -133.362383) (xy 377.010259 -133.288102) (xy 376.934522 -133.208147)
			(xy 376.864751 -133.122936) (xy 376.801312 -133.032912) (xy 376.744533 -132.938545) (xy 376.694712 -132.840328)
			(xy 376.652108 -132.738771) (xy 376.616943 -132.634405) (xy 376.5894 -132.527774) (xy 376.569624 -132.419433)
			(xy 376.557716 -132.309947) (xy 376.553741 -132.199888) (xy 352.515932 -132.199888) (xy 352.515932 -134.881366)
			(xy 352.516448 -134.891942) (xy 352.524971 -134.911297) (xy 352.540609 -134.925534) (xy 352.550476 -134.929372)
			(xy 352.590802 -134.943408) (xy 352.668804 -134.978159) (xy 352.743117 -135.020224) (xy 352.813057 -135.069217)
			(xy 352.87798 -135.124686) (xy 352.93729 -135.186121) (xy 352.990439 -135.252958) (xy 353.036938 -135.324579)
			(xy 353.076361 -135.400327) (xy 353.108343 -135.479504) (xy 353.132591 -135.561382) (xy 353.148881 -135.645206)
			(xy 353.157064 -135.730206) (xy 353.157064 -135.815598) (xy 353.148881 -135.900598) (xy 353.13259 -135.984422)
			(xy 353.108342 -136.066299) (xy 353.076359 -136.145476) (xy 353.036936 -136.221224) (xy 352.990436 -136.292846)
			(xy 352.937287 -136.359681) (xy 352.877978 -136.421117) (xy 352.813054 -136.476586) (xy 352.743114 -136.525578)
			(xy 352.668801 -136.567643) (xy 352.590799 -136.602393) (xy 352.550476 -136.61644) (xy 352.534982 -136.621774)
			(xy 352.515932 -136.64819) (xy 352.515932 -139.961366) (xy 352.516448 -139.971942) (xy 352.524971 -139.991297)
			(xy 352.540609 -140.005534) (xy 352.550476 -140.009372) (xy 352.590802 -140.023408) (xy 352.668804 -140.058159)
			(xy 352.743117 -140.100224) (xy 352.813057 -140.149217) (xy 352.87798 -140.204686) (xy 352.93729 -140.266121)
			(xy 352.990439 -140.332958) (xy 353.036938 -140.404579) (xy 353.076361 -140.480327) (xy 353.108343 -140.559504)
			(xy 353.132591 -140.641382) (xy 353.148881 -140.725206) (xy 353.157064 -140.810206) (xy 353.157064 -140.895598)
			(xy 353.148881 -140.980598) (xy 353.13259 -141.064422) (xy 353.108342 -141.146299) (xy 353.076359 -141.225476)
			(xy 353.036936 -141.301224) (xy 352.990436 -141.372846) (xy 352.937287 -141.439681) (xy 352.877978 -141.501117)
			(xy 352.813054 -141.556586) (xy 352.743114 -141.605578) (xy 352.668801 -141.647643) (xy 352.590799 -141.682393)
			(xy 352.550476 -141.69644) (xy 352.534982 -141.701774) (xy 352.515932 -141.72819) (xy 352.515932 -145.041366)
			(xy 352.516448 -145.051942) (xy 352.524971 -145.071297) (xy 352.540609 -145.085534) (xy 352.550476 -145.089372)
			(xy 352.590802 -145.103408) (xy 352.668804 -145.138159) (xy 352.743117 -145.180224) (xy 352.813057 -145.229217)
			(xy 352.87798 -145.284686) (xy 352.93729 -145.346121) (xy 352.990439 -145.412958) (xy 353.036938 -145.484579)
			(xy 353.076361 -145.560327) (xy 353.108343 -145.639504) (xy 353.132591 -145.721382) (xy 353.148881 -145.805206)
			(xy 353.157064 -145.890206) (xy 353.157064 -145.975598) (xy 353.148881 -146.060598) (xy 353.13259 -146.144422)
			(xy 353.108342 -146.226299) (xy 353.076359 -146.305476) (xy 353.036936 -146.381224) (xy 352.990436 -146.452846)
			(xy 352.937287 -146.519681) (xy 352.877978 -146.581117) (xy 352.813054 -146.636586) (xy 352.743114 -146.685578)
			(xy 352.668801 -146.727643) (xy 352.590799 -146.762393) (xy 352.550476 -146.77644) (xy 352.534982 -146.781774)
			(xy 352.515932 -146.80819) (xy 352.515932 -147.500086) (xy 354.864924 -147.500086) (xy 354.864924 -142.500096)
			(xy 354.865419 -142.399255) (xy 354.873337 -142.197728) (xy 354.889161 -141.996668) (xy 354.912866 -141.796384)
			(xy 354.944416 -141.597185) (xy 354.983762 -141.399378) (xy 355.030844 -141.203269) (xy 355.085589 -141.009159)
			(xy 355.147912 -140.817348) (xy 355.217717 -140.628131) (xy 355.294898 -140.441802) (xy 355.379334 -140.258645)
			(xy 355.470896 -140.078945) (xy 355.569442 -139.902979) (xy 355.67482 -139.731016) (xy 355.786869 -139.563324)
			(xy 355.905415 -139.40016) (xy 356.030275 -139.241775) (xy 356.161257 -139.088415) (xy 356.298159 -138.940315)
			(xy 356.440769 -138.797705) (xy 356.588869 -138.660803) (xy 356.742229 -138.529821) (xy 356.900614 -138.404961)
			(xy 357.063778 -138.286415) (xy 357.23147 -138.174366) (xy 357.403433 -138.068988) (xy 357.579399 -137.970442)
			(xy 357.759099 -137.87888) (xy 357.942256 -137.794444) (xy 358.128585 -137.717263) (xy 358.317802 -137.647458)
			(xy 358.509613 -137.585135) (xy 358.703723 -137.53039) (xy 358.899832 -137.483308) (xy 359.097639 -137.443962)
			(xy 359.296838 -137.412412) (xy 359.497122 -137.388707) (xy 359.698182 -137.372883) (xy 359.899709 -137.364965)
			(xy 360.101391 -137.364965) (xy 360.302918 -137.372883) (xy 360.503978 -137.388707) (xy 360.704262 -137.412412)
			(xy 360.903461 -137.443962) (xy 361.101268 -137.483308) (xy 361.297377 -137.53039) (xy 361.491487 -137.585135)
			(xy 361.683298 -137.647458) (xy 361.872515 -137.717263) (xy 362.058844 -137.794444) (xy 362.242001 -137.87888)
			(xy 362.421701 -137.970442) (xy 362.597667 -138.068988) (xy 362.76963 -138.174366) (xy 362.937322 -138.286415)
			(xy 363.100486 -138.404961) (xy 363.258871 -138.529821) (xy 363.412231 -138.660803) (xy 363.560331 -138.797705)
			(xy 363.702941 -138.940315) (xy 363.839843 -139.088415) (xy 363.970825 -139.241775) (xy 364.095685 -139.40016)
			(xy 364.214231 -139.563324) (xy 364.305556 -139.7) (xy 377.061486 -139.7) (xy 377.065468 -139.610072)
			(xy 377.077382 -139.520848) (xy 377.097135 -139.433026) (xy 377.124572 -139.347293) (xy 377.159479 -139.264321)
			(xy 377.201583 -139.184758) (xy 377.250553 -139.109228) (xy 377.306008 -139.038322) (xy 377.367512 -138.972594)
			(xy 377.434584 -138.912559) (xy 377.5067 -138.858687) (xy 377.583295 -138.811399) (xy 377.663769 -138.771066)
			(xy 377.747493 -138.738003) (xy 377.833812 -138.712469) (xy 377.92205 -138.694664) (xy 378.011515 -138.684726)
			(xy 378.10151 -138.682735) (xy 378.191327 -138.688705) (xy 378.280266 -138.70259) (xy 378.36763 -138.724281)
			(xy 378.452735 -138.753608) (xy 378.534914 -138.790342) (xy 378.613526 -138.834196) (xy 378.687954 -138.884825)
			(xy 378.757616 -138.941835) (xy 378.821967 -139.004778) (xy 378.880504 -139.073162) (xy 378.932767 -139.146452)
			(xy 378.978349 -139.224074) (xy 379.016892 -139.305421) (xy 379.048095 -139.389856) (xy 379.071713 -139.476718)
			(xy 379.087562 -139.565328) (xy 379.095518 -139.654992) (xy 379.096016 -139.7) (xy 396.619486 -139.7)
			(xy 396.623468 -139.610072) (xy 396.635382 -139.520848) (xy 396.655135 -139.433026) (xy 396.682572 -139.347293)
			(xy 396.717479 -139.264321) (xy 396.759583 -139.184758) (xy 396.808553 -139.109228) (xy 396.864008 -139.038322)
			(xy 396.925512 -138.972594) (xy 396.992584 -138.912559) (xy 397.0647 -138.858687) (xy 397.141295 -138.811399)
			(xy 397.221769 -138.771066) (xy 397.305493 -138.738003) (xy 397.391812 -138.712469) (xy 397.48005 -138.694664)
			(xy 397.569515 -138.684726) (xy 397.65951 -138.682735) (xy 397.749327 -138.688705) (xy 397.838266 -138.70259)
			(xy 397.92563 -138.724281) (xy 398.010735 -138.753608) (xy 398.092914 -138.790342) (xy 398.171526 -138.834196)
			(xy 398.245954 -138.884825) (xy 398.315616 -138.941835) (xy 398.379967 -139.004778) (xy 398.438504 -139.073162)
			(xy 398.490767 -139.146452) (xy 398.536349 -139.224074) (xy 398.574892 -139.305421) (xy 398.606095 -139.389856)
			(xy 398.629713 -139.476718) (xy 398.645562 -139.565328) (xy 398.653518 -139.654992) (xy 398.654016 -139.7)
			(xy 398.653518 -139.745008) (xy 398.645562 -139.834672) (xy 398.629713 -139.923282) (xy 398.606095 -140.010144)
			(xy 398.574892 -140.094579) (xy 398.536349 -140.175926) (xy 398.490767 -140.253548) (xy 398.438504 -140.326838)
			(xy 398.379967 -140.395222) (xy 398.315616 -140.458165) (xy 398.245954 -140.515175) (xy 398.171526 -140.565804)
			(xy 398.092914 -140.609658) (xy 398.010735 -140.646392) (xy 397.92563 -140.675719) (xy 397.838266 -140.69741)
			(xy 397.749327 -140.711295) (xy 397.65951 -140.717265) (xy 397.569515 -140.715274) (xy 397.48005 -140.705336)
			(xy 397.391812 -140.687531) (xy 397.305493 -140.661997) (xy 397.221769 -140.628934) (xy 397.141295 -140.588601)
			(xy 397.0647 -140.541313) (xy 396.992584 -140.487441) (xy 396.925512 -140.427406) (xy 396.864008 -140.361678)
			(xy 396.808553 -140.290772) (xy 396.759583 -140.215242) (xy 396.717479 -140.135679) (xy 396.682572 -140.052707)
			(xy 396.655135 -139.966974) (xy 396.635382 -139.879152) (xy 396.623468 -139.789928) (xy 396.619486 -139.7)
			(xy 379.096016 -139.7) (xy 379.095518 -139.745008) (xy 379.087562 -139.834672) (xy 379.071713 -139.923282)
			(xy 379.048095 -140.010144) (xy 379.016892 -140.094579) (xy 378.978349 -140.175926) (xy 378.932767 -140.253548)
			(xy 378.880504 -140.326838) (xy 378.821967 -140.395222) (xy 378.757616 -140.458165) (xy 378.687954 -140.515175)
			(xy 378.613526 -140.565804) (xy 378.534914 -140.609658) (xy 378.452735 -140.646392) (xy 378.36763 -140.675719)
			(xy 378.280266 -140.69741) (xy 378.191327 -140.711295) (xy 378.10151 -140.717265) (xy 378.011515 -140.715274)
			(xy 377.92205 -140.705336) (xy 377.833812 -140.687531) (xy 377.747493 -140.661997) (xy 377.663769 -140.628934)
			(xy 377.583295 -140.588601) (xy 377.5067 -140.541313) (xy 377.434584 -140.487441) (xy 377.367512 -140.427406)
			(xy 377.306008 -140.361678) (xy 377.250553 -140.290772) (xy 377.201583 -140.215242) (xy 377.159479 -140.135679)
			(xy 377.124572 -140.052707) (xy 377.097135 -139.966974) (xy 377.077382 -139.879152) (xy 377.065468 -139.789928)
			(xy 377.061486 -139.7) (xy 364.305556 -139.7) (xy 364.32628 -139.731016) (xy 364.431658 -139.902979)
			(xy 364.530204 -140.078945) (xy 364.621766 -140.258645) (xy 364.706202 -140.441802) (xy 364.783383 -140.628131)
			(xy 364.853188 -140.817348) (xy 364.915511 -141.009159) (xy 364.970256 -141.203269) (xy 365.017338 -141.399378)
			(xy 365.056684 -141.597185) (xy 365.088234 -141.796384) (xy 365.111939 -141.996668) (xy 365.127763 -142.197728)
			(xy 365.135681 -142.399255) (xy 365.136176 -142.500096) (xy 365.136176 -147.500086) (xy 365.135681 -147.600927)
			(xy 365.127763 -147.802454) (xy 365.111939 -148.003514) (xy 365.088234 -148.203798) (xy 365.056684 -148.402997)
			(xy 365.017338 -148.600804) (xy 364.970256 -148.796913) (xy 364.915511 -148.991023) (xy 364.853188 -149.182834)
			(xy 364.783383 -149.372051) (xy 364.706202 -149.55838) (xy 364.621766 -149.741537) (xy 364.530204 -149.921237)
			(xy 364.431658 -150.097203) (xy 364.32628 -150.269166) (xy 364.214231 -150.436858) (xy 364.095685 -150.600022)
			(xy 363.970825 -150.758407) (xy 363.839843 -150.911767) (xy 363.702941 -151.059867) (xy 363.560331 -151.202477)
			(xy 363.412231 -151.339379) (xy 363.258871 -151.470361) (xy 363.100486 -151.595221) (xy 362.937322 -151.713767)
			(xy 362.76963 -151.825816) (xy 362.597667 -151.931194) (xy 362.421701 -152.02974) (xy 362.242001 -152.121302)
			(xy 362.058844 -152.205738) (xy 361.872515 -152.282919) (xy 361.683298 -152.352724) (xy 361.491487 -152.415047)
			(xy 361.297377 -152.469792) (xy 361.101268 -152.516874) (xy 360.903461 -152.55622) (xy 360.704262 -152.58777)
			(xy 360.503978 -152.611475) (xy 360.302918 -152.627299) (xy 360.101391 -152.635217) (xy 359.899709 -152.635217)
			(xy 359.698182 -152.627299) (xy 359.497122 -152.611475) (xy 359.296838 -152.58777) (xy 359.097639 -152.55622)
			(xy 358.899832 -152.516874) (xy 358.703723 -152.469792) (xy 358.509613 -152.415047) (xy 358.317802 -152.352724)
			(xy 358.128585 -152.282919) (xy 357.942256 -152.205738) (xy 357.759099 -152.121302) (xy 357.579399 -152.02974)
			(xy 357.403433 -151.931194) (xy 357.23147 -151.825816) (xy 357.063778 -151.713767) (xy 356.900614 -151.595221)
			(xy 356.742229 -151.470361) (xy 356.588869 -151.339379) (xy 356.440769 -151.202477) (xy 356.298159 -151.059867)
			(xy 356.161257 -150.911767) (xy 356.030275 -150.758407) (xy 355.905415 -150.600022) (xy 355.786869 -150.436858)
			(xy 355.67482 -150.269166) (xy 355.569442 -150.097203) (xy 355.470896 -149.921237) (xy 355.379334 -149.741537)
			(xy 355.294898 -149.55838) (xy 355.217717 -149.372051) (xy 355.147912 -149.182834) (xy 355.085589 -148.991023)
			(xy 355.030844 -148.796913) (xy 354.983762 -148.600804) (xy 354.944416 -148.402997) (xy 354.912866 -148.203798)
			(xy 354.889161 -148.003514) (xy 354.873337 -147.802454) (xy 354.865419 -147.600927) (xy 354.864924 -147.500086)
			(xy 352.515932 -147.500086) (xy 352.515932 -150.121366) (xy 352.516448 -150.131942) (xy 352.524971 -150.151297)
			(xy 352.540609 -150.165534) (xy 352.550476 -150.169372) (xy 352.590802 -150.183408) (xy 352.668804 -150.218159)
			(xy 352.743117 -150.260224) (xy 352.813057 -150.309217) (xy 352.87798 -150.364686) (xy 352.93729 -150.426121)
			(xy 352.990439 -150.492958) (xy 353.036938 -150.564579) (xy 353.076361 -150.640327) (xy 353.108343 -150.719504)
			(xy 353.132591 -150.801382) (xy 353.148881 -150.885206) (xy 353.157064 -150.970206) (xy 353.157064 -151.055598)
			(xy 353.148881 -151.140598) (xy 353.13259 -151.224422) (xy 353.108342 -151.306299) (xy 353.076359 -151.385476)
			(xy 353.036936 -151.461224) (xy 352.990436 -151.532846) (xy 352.937287 -151.599681) (xy 352.877978 -151.661117)
			(xy 352.813054 -151.716586) (xy 352.743114 -151.765578) (xy 352.668801 -151.807643) (xy 352.590799 -151.842393)
			(xy 352.550476 -151.85644) (xy 352.534982 -151.861774) (xy 352.515932 -151.88819) (xy 352.515932 -153.299922)
			(xy 352.516443 -153.390713) (xy 352.524716 -153.572106) (xy 352.541243 -153.752934) (xy 352.56599 -153.932822)
			(xy 352.598906 -154.111396) (xy 352.639923 -154.288284) (xy 352.688955 -154.463121) (xy 352.7459 -154.635542)
			(xy 352.777806 -154.720544) (xy 352.7825 -154.731157) (xy 352.799467 -154.746955) (xy 352.821633 -154.753745)
			(xy 352.833178 -154.752548) (xy 352.866749 -154.747691) (xy 352.934387 -154.742476) (xy 352.968306 -154.742134)
			(xy 352.969322 -154.742134) (xy 353.010424 -154.742595) (xy 353.092277 -154.750182) (xy 353.17308 -154.765289)
			(xy 353.252145 -154.787788) (xy 353.328797 -154.817485) (xy 353.402381 -154.854129) (xy 353.472271 -154.897406)
			(xy 353.537869 -154.946947) (xy 353.598616 -155.002329) (xy 353.653994 -155.06308) (xy 353.70353 -155.128682)
			(xy 353.746802 -155.198575) (xy 353.783441 -155.272162) (xy 353.813133 -155.348816) (xy 353.835625 -155.427882)
			(xy 353.850727 -155.508687) (xy 353.858308 -155.59054) (xy 353.85883 -155.631642) (xy 353.858362 -155.672957)
			(xy 353.850699 -155.755231) (xy 353.835433 -155.836439) (xy 353.812698 -155.915879) (xy 353.782688 -155.992867)
			(xy 353.745663 -156.066738) (xy 353.72421 -156.10205) (xy 353.71659 -156.128974) (xy 353.717062 -156.139216)
			(xy 353.725064 -156.158075) (xy 353.732084 -156.16555) (xy 353.794273 -156.224978) (xy 353.923053 -156.339046)
			(xy 354.056638 -156.447448) (xy 354.194778 -156.549982) (xy 354.337215 -156.646457) (xy 354.483684 -156.736693)
			(xy 354.633912 -156.820522) (xy 354.787619 -156.897789) (xy 354.944518 -156.968347) (xy 355.104317 -157.032067)
			(xy 355.266717 -157.08883) (xy 355.431416 -157.138528) (xy 355.514656 -157.160214) (xy 355.526067 -157.162509)
			(xy 355.548824 -157.157736) (xy 355.56719 -157.143476) (xy 355.572822 -157.13329) (xy 355.591468 -157.096463)
			(xy 355.634624 -157.026091) (xy 355.684114 -156.96002) (xy 355.739513 -156.898817) (xy 355.800344 -156.843011)
			(xy 355.866083 -156.79308) (xy 355.936165 -156.749455) (xy 356.009988 -156.71251) (xy 356.086915 -156.682563)
			(xy 356.166287 -156.659872) (xy 356.247419 -156.644631) (xy 356.329614 -156.636973) (xy 356.37089 -156.636466)
			(xy 356.414138 -156.636976) (xy 356.500225 -156.645364) (xy 356.585091 -156.662071) (xy 356.667935 -156.686939)
			(xy 356.747972 -156.719733) (xy 356.824447 -156.760143) (xy 356.896636 -156.807788) (xy 356.963859 -156.862218)
			(xy 357.025479 -156.922917) (xy 357.080914 -156.989312) (xy 357.129641 -157.060776) (xy 357.171199 -157.136634)
			(xy 357.205195 -157.216168) (xy 357.218742 -157.257242) (xy 357.222252 -157.266862) (xy 357.235506 -157.282449)
			(xy 357.253778 -157.291658) (xy 357.263954 -157.292802) (xy 357.350776 -157.298975) (xy 357.523824 -157.317909)
			(xy 357.695888 -157.344324) (xy 357.866646 -157.378171) (xy 358.035777 -157.419386) (xy 358.202963 -157.467892)
			(xy 358.36789 -157.523598) (xy 358.530247 -157.586399) (xy 358.689731 -157.656177) (xy 358.846041 -157.7328)
			(xy 358.998883 -157.816126) (xy 359.147971 -157.905997) (xy 359.22077 -157.95371) (xy 359.289013 -157.999499)
			(xy 359.422125 -158.095911) (xy 359.551179 -158.197693) (xy 359.675957 -158.304672) (xy 359.73639 -158.360364)
			(xy 359.804033 -158.424058) (xy 359.934042 -158.556823) (xy 360.057773 -158.695458) (xy 360.174962 -158.839665)
			(xy 360.285357 -158.989136) (xy 360.388724 -159.143553) (xy 360.48484 -159.302583) (xy 360.529632 -159.383984)
			(xy 360.55333 -159.427998) (xy 360.598801 -159.517035) (xy 360.620564 -159.562038) (xy 360.623104 -159.567372)
			(xy 360.652644 -159.63011) (xy 371.481871 -159.63011) (xy 371.485828 -159.520564) (xy 371.49768 -159.411589)
			(xy 371.517364 -159.303754) (xy 371.544778 -159.19762) (xy 371.579779 -159.09374) (xy 371.622185 -158.992657)
			(xy 371.671774 -158.894898) (xy 371.728287 -158.800971) (xy 371.791431 -158.711368) (xy 371.860876 -158.626554)
			(xy 371.93626 -158.546972) (xy 372.01719 -158.473037) (xy 372.103244 -158.405135) (xy 372.193973 -158.343619)
			(xy 372.288904 -158.288811) (xy 372.387543 -158.240995) (xy 372.489375 -158.200421) (xy 372.593869 -158.167301)
			(xy 372.700481 -158.141808) (xy 372.808654 -158.124074) (xy 372.917825 -158.114191) (xy 373.027425 -158.112212)
			(xy 373.136881 -158.118147) (xy 373.245625 -158.131964) (xy 373.353087 -158.153592) (xy 373.458709 -158.182918)
			(xy 373.561939 -158.219789) (xy 373.66224 -158.264012) (xy 373.759089 -158.315358) (xy 373.851979 -158.373558)
			(xy 373.940428 -158.438309) (xy 374.023975 -158.509274) (xy 374.102182 -158.586083) (xy 374.174644 -158.668334)
			(xy 374.240982 -158.7556) (xy 374.300849 -158.847424) (xy 374.353935 -158.94333) (xy 374.399962 -159.042816)
			(xy 374.438691 -159.145364) (xy 374.469919 -159.250439) (xy 374.493483 -159.357494) (xy 374.509262 -159.46597)
			(xy 374.517171 -159.575301) (xy 374.517666 -159.63011) (xy 374.517171 -159.684919) (xy 374.509262 -159.79425)
			(xy 374.493483 -159.902726) (xy 374.469919 -160.009781) (xy 374.438691 -160.114856) (xy 374.399962 -160.217404)
			(xy 374.353935 -160.31689) (xy 374.300849 -160.412796) (xy 374.240982 -160.50462) (xy 374.174644 -160.591886)
			(xy 374.102182 -160.674137) (xy 374.023975 -160.750946) (xy 373.940428 -160.821911) (xy 373.851979 -160.886662)
			(xy 373.759089 -160.944862) (xy 373.66224 -160.996208) (xy 373.561939 -161.040431) (xy 373.458709 -161.077302)
			(xy 373.353087 -161.106628) (xy 373.245625 -161.128256) (xy 373.136881 -161.142073) (xy 373.027425 -161.148008)
			(xy 372.917825 -161.146029) (xy 372.808654 -161.136146) (xy 372.700481 -161.118412) (xy 372.593869 -161.092919)
			(xy 372.489375 -161.059799) (xy 372.387543 -161.019225) (xy 372.288904 -160.971409) (xy 372.193973 -160.916601)
			(xy 372.103244 -160.855085) (xy 372.01719 -160.787183) (xy 371.93626 -160.713248) (xy 371.860876 -160.633666)
			(xy 371.791431 -160.548852) (xy 371.728287 -160.459249) (xy 371.671774 -160.365322) (xy 371.622185 -160.267563)
			(xy 371.579779 -160.16648) (xy 371.544778 -160.0626) (xy 371.517364 -159.956466) (xy 371.49768 -159.848631)
			(xy 371.485828 -159.739656) (xy 371.481871 -159.63011) (xy 360.652644 -159.63011) (xy 360.664407 -159.655093)
			(xy 360.739524 -159.833866) (xy 360.805921 -160.016057) (xy 360.863444 -160.201241) (xy 360.911958 -160.388987)
			(xy 360.932222 -160.483804) (xy 360.93461 -160.493151) (xy 360.945243 -160.509229) (xy 360.961045 -160.520268)
			(xy 360.970322 -160.52292) (xy 361.011571 -160.533226) (xy 361.092046 -160.560675) (xy 361.169536 -160.595675)
			(xy 361.243335 -160.637907) (xy 361.312768 -160.686986) (xy 361.377204 -160.742464) (xy 361.436053 -160.803836)
			(xy 361.48878 -160.870541) (xy 361.534904 -160.941971) (xy 361.574005 -161.017476) (xy 361.605724 -161.096366)
			(xy 361.629774 -161.177921) (xy 361.645935 -161.261399) (xy 361.65406 -161.346038) (xy 361.654598 -161.388552)
			(xy 361.654097 -161.431124) (xy 361.645958 -161.515877) (xy 361.629759 -161.599465) (xy 361.605649 -161.681124)
			(xy 361.573848 -161.760106) (xy 361.534647 -161.835688) (xy 361.488405 -161.90718) (xy 361.435544 -161.973926)
			(xy 361.376549 -162.035318) (xy 361.311958 -162.090793) (xy 361.242363 -162.139843) (xy 361.168401 -162.182021)
			(xy 361.090747 -162.216939) (xy 361.050586 -162.23107) (xy 361.040761 -162.234968) (xy 361.02518 -162.249218)
			(xy 361.016625 -162.268521) (xy 361.016219 -162.275866) (xy 385.708125 -162.275866) (xy 385.716065 -162.167119)
			(xy 385.731923 -162.059242) (xy 385.755612 -161.95281) (xy 385.787008 -161.848391) (xy 385.825942 -161.746543)
			(xy 385.872206 -161.647808) (xy 385.925554 -161.552714) (xy 385.985702 -161.461768) (xy 386.052327 -161.375455)
			(xy 386.125075 -161.294235) (xy 386.203558 -161.218542) (xy 386.287357 -161.14878) (xy 386.376024 -161.085322)
			(xy 386.469087 -161.028504) (xy 386.566049 -160.978632) (xy 386.666393 -160.93597) (xy 386.769583 -160.900747)
			(xy 386.87507 -160.87315) (xy 386.982289 -160.853327) (xy 387.090669 -160.841383) (xy 387.199632 -160.837382)
			(xy 387.308596 -160.841346) (xy 387.41698 -160.853253) (xy 387.524206 -160.873039) (xy 387.629702 -160.9006)
			(xy 387.732904 -160.935789) (xy 387.833263 -160.978416) (xy 387.930242 -161.028256) (xy 388.023324 -161.085041)
			(xy 388.112013 -161.14847) (xy 388.195836 -161.218203) (xy 388.274344 -161.293869) (xy 388.34712 -161.375064)
			(xy 388.413775 -161.461355) (xy 388.473953 -161.55228) (xy 388.527334 -161.647356) (xy 388.573632 -161.746075)
			(xy 388.6126 -161.84791) (xy 388.644031 -161.952318) (xy 388.667757 -162.058742) (xy 388.683651 -162.166614)
			(xy 388.691629 -162.275358) (xy 388.692136 -162.329876) (xy 388.691647 -162.384394) (xy 388.683707 -162.493141)
			(xy 388.667849 -162.601018) (xy 388.64416 -162.70745) (xy 388.612764 -162.811869) (xy 388.57383 -162.913717)
			(xy 388.527566 -163.012452) (xy 388.474218 -163.107546) (xy 388.41407 -163.198492) (xy 388.347445 -163.284805)
			(xy 388.274697 -163.366025) (xy 388.196214 -163.441718) (xy 388.112415 -163.51148) (xy 388.023748 -163.574938)
			(xy 387.930685 -163.631756) (xy 387.833723 -163.681628) (xy 387.733379 -163.72429) (xy 387.630189 -163.759513)
			(xy 387.524702 -163.78711) (xy 387.417483 -163.806933) (xy 387.309103 -163.818877) (xy 387.20014 -163.822878)
			(xy 387.091176 -163.818914) (xy 386.982792 -163.807007) (xy 386.875566 -163.787221) (xy 386.77007 -163.75966)
			(xy 386.666868 -163.724471) (xy 386.566509 -163.681844) (xy 386.46953 -163.632004) (xy 386.376448 -163.575219)
			(xy 386.287759 -163.51179) (xy 386.203936 -163.442057) (xy 386.125428 -163.366391) (xy 386.052652 -163.285196)
			(xy 385.985997 -163.198905) (xy 385.925819 -163.10798) (xy 385.872438 -163.012904) (xy 385.82614 -162.914185)
			(xy 385.787172 -162.81235) (xy 385.755741 -162.707942) (xy 385.732015 -162.601518) (xy 385.716121 -162.493646)
			(xy 385.708143 -162.384902) (xy 385.708125 -162.275866) (xy 361.016219 -162.275866) (xy 361.016042 -162.279076)
			(xy 361.016042 -165.578028) (xy 361.01657 -165.588595) (xy 361.025106 -165.607928) (xy 361.040744 -165.622143)
			(xy 361.050586 -165.626034) (xy 361.090748 -165.640167) (xy 361.168412 -165.675071) (xy 361.242386 -165.717238)
			(xy 361.31199 -165.766281) (xy 361.376589 -165.821751) (xy 361.435591 -165.883142) (xy 361.488456 -165.94989)
			(xy 361.534699 -166.021385) (xy 361.573898 -166.096973) (xy 361.605694 -166.17596) (xy 361.629795 -166.257625)
			(xy 361.645982 -166.34122) (xy 361.654105 -166.425978) (xy 361.654598 -166.468552) (xy 361.654065 -166.512125)
			(xy 361.645539 -166.598852) (xy 361.628575 -166.684331) (xy 361.603334 -166.767741) (xy 361.570059 -166.848284)
			(xy 361.529069 -166.925187) (xy 361.480756 -166.997715) (xy 361.425583 -167.06517) (xy 361.364079 -167.126909)
			(xy 361.296833 -167.182338) (xy 361.22449 -167.230927) (xy 361.147743 -167.272209) (xy 361.107736 -167.28948)
			(xy 361.076494 -167.33647) (xy 361.077256 -167.34536) (xy 361.09275 -167.428672) (xy 361.110489 -167.515171)
			(xy 361.152661 -167.686657) (xy 361.202391 -167.856105) (xy 361.259583 -168.023183) (xy 361.324123 -168.187561)
			(xy 361.395886 -168.348918) (xy 361.47473 -168.506935) (xy 361.5605 -168.661303) (xy 361.606338 -168.736772)
			(xy 361.612312 -168.745464) (xy 361.629635 -168.757454) (xy 361.650314 -168.761486) (xy 361.660694 -168.759632)
			(xy 361.75442 -168.73855) (xy 361.79379 -168.694608) (xy 361.799966 -168.644266) (xy 361.819647 -168.54476)
			(xy 361.847569 -168.447244) (xy 361.883535 -168.352401) (xy 361.927295 -168.260892) (xy 361.978544 -168.173357)
			(xy 362.036923 -168.090407) (xy 362.102024 -168.012621) (xy 362.173394 -167.940543) (xy 362.21162 -167.907208)
			(xy 362.219642 -167.899635) (xy 362.228862 -167.879619) (xy 362.2294 -167.8686) (xy 362.2294 -167.791384)
			(xy 362.228856 -167.780367) (xy 362.219633 -167.760357) (xy 362.21162 -167.752776) (xy 362.173997 -167.719952)
			(xy 362.103676 -167.649059) (xy 362.039418 -167.572629) (xy 361.981656 -167.491178) (xy 361.930781 -167.405257)
			(xy 361.887136 -167.315447) (xy 361.851018 -167.222355) (xy 361.822669 -167.12661) (xy 361.802282 -167.02886)
			(xy 361.789995 -166.929765) (xy 361.78589 -166.829996) (xy 361.789995 -166.730227) (xy 361.802283 -166.631133)
			(xy 361.822671 -166.533383) (xy 361.85102 -166.437638) (xy 361.887139 -166.344546) (xy 361.930784 -166.254736)
			(xy 361.98166 -166.168815) (xy 362.039423 -166.087365) (xy 362.103682 -166.010935) (xy 362.174002 -165.940043)
			(xy 362.21162 -165.907212) (xy 362.219643 -165.89964) (xy 362.228865 -165.879623) (xy 362.2294 -165.868604)
			(xy 362.2294 -165.791388) (xy 362.228857 -165.780371) (xy 362.219635 -165.760359) (xy 362.21162 -165.75278)
			(xy 362.175696 -165.721462) (xy 362.108321 -165.654045) (xy 362.046442 -165.581551) (xy 361.990439 -165.504427)
			(xy 361.940659 -165.423147) (xy 361.897406 -165.338214) (xy 361.86095 -165.250149) (xy 361.831512 -165.159497)
			(xy 361.809276 -165.066814) (xy 361.794378 -164.972674) (xy 361.78691 -164.877654) (xy 361.786424 -164.829998)
			(xy 361.786942 -164.77982) (xy 361.795228 -164.679807) (xy 361.811744 -164.58082) (xy 361.836377 -164.483534)
			(xy 361.868958 -164.388615) (xy 361.909266 -164.296709) (xy 361.957024 -164.208446) (xy 362.011906 -164.124427)
			(xy 362.073539 -164.045227) (xy 362.1415 -163.971386) (xy 362.215327 -163.903408) (xy 362.294514 -163.841759)
			(xy 362.378521 -163.786858) (xy 362.466774 -163.739081) (xy 362.55867 -163.698754) (xy 362.653583 -163.666152)
			(xy 362.750863 -163.641498) (xy 362.849847 -163.624961) (xy 362.949858 -163.616653) (xy 363.000036 -163.616132)
			(xy 363.047697 -163.616612) (xy 363.142723 -163.624113) (xy 363.236868 -163.639043) (xy 363.329552 -163.661309)
			(xy 363.420205 -163.690775) (xy 363.508268 -163.727259) (xy 363.593199 -163.770536) (xy 363.674475 -163.820339)
			(xy 363.751595 -163.876363) (xy 363.824085 -163.938262) (xy 363.891497 -164.005655) (xy 363.922818 -164.041582)
			(xy 363.93039 -164.049605) (xy 363.950407 -164.058822) (xy 363.961426 -164.059362) (xy 364.038642 -164.059362)
			(xy 364.049658 -164.058815) (xy 364.069668 -164.049593) (xy 364.07725 -164.041582) (xy 364.10856 -164.005644)
			(xy 364.175965 -163.938241) (xy 364.24845 -163.876333) (xy 364.325568 -163.820304) (xy 364.406845 -163.770496)
			(xy 364.491778 -163.727219) (xy 364.579845 -163.690738) (xy 364.670502 -163.661279) (xy 364.763191 -163.639023)
			(xy 364.857341 -163.624107) (xy 364.95237 -163.616623) (xy 365.000032 -163.616132) (xy 365.050198 -163.616651)
			(xy 365.150186 -163.624938) (xy 365.249149 -163.641453) (xy 365.346411 -163.666082) (xy 365.441307 -163.698658)
			(xy 365.533189 -163.738958) (xy 365.621429 -163.786708) (xy 365.705426 -163.84158) (xy 365.784605 -163.9032)
			(xy 365.858426 -163.971148) (xy 365.926385 -164.044959) (xy 365.988017 -164.124129) (xy 366.042901 -164.208118)
			(xy 366.090663 -164.296351) (xy 366.130977 -164.388227) (xy 366.163567 -164.483118) (xy 366.188211 -164.580376)
			(xy 366.20474 -164.679337) (xy 366.213041 -164.779324) (xy 366.213644 -164.82949) (xy 366.213644 -164.829998)
			(xy 366.213177 -164.877655) (xy 366.205703 -164.972675) (xy 366.190801 -165.066816) (xy 366.168562 -165.159499)
			(xy 366.139123 -165.250152) (xy 366.102666 -165.338218) (xy 366.059416 -165.423154) (xy 366.009638 -165.504436)
			(xy 365.953639 -165.581565) (xy 365.891765 -165.654065) (xy 365.824396 -165.721489) (xy 365.788448 -165.75278)
			(xy 365.780428 -165.760354) (xy 365.771209 -165.78037) (xy 365.770668 -165.791388) (xy 365.770668 -165.868604)
			(xy 365.771208 -165.879623) (xy 365.780424 -165.899641) (xy 365.788448 -165.907212) (xy 365.826878 -165.940716)
			(xy 365.898589 -166.013199) (xy 365.963965 -166.091445) (xy 366.022543 -166.174901) (xy 366.073912 -166.262978)
			(xy 366.096296 -166.308786) (xy 366.10136 -166.318177) (xy 366.117499 -166.332098) (xy 366.127538 -166.33571)
			(xy 366.199166 -166.3573) (xy 366.209432 -166.359843) (xy 366.230411 -166.357336) (xy 366.239806 -166.352474)
			(xy 366.285768 -166.325669) (xy 366.380871 -166.277934) (xy 366.479145 -166.237121) (xy 366.580085 -166.203441)
			(xy 366.683175 -166.177064) (xy 366.787887 -166.158126) (xy 366.893685 -166.146725) (xy 367.000028 -166.142918)
			(xy 367.106371 -166.146725) (xy 367.212169 -166.158126) (xy 367.316881 -166.177064) (xy 367.419971 -166.203441)
			(xy 367.520911 -166.237121) (xy 367.619185 -166.277934) (xy 367.714288 -166.325669) (xy 367.76025 -166.352474)
			(xy 367.769591 -166.3575) (xy 367.790635 -166.360005) (xy 367.80089 -166.3573) (xy 367.872518 -166.33571)
			(xy 367.882603 -166.332179) (xy 367.898768 -166.318234) (xy 367.90376 -166.308786) (xy 367.926137 -166.262975)
			(xy 367.977514 -166.174903) (xy 368.036098 -166.091451) (xy 368.101474 -166.013207) (xy 368.173183 -165.940722)
			(xy 368.211608 -165.907212) (xy 368.219633 -165.89964) (xy 368.228856 -165.879624) (xy 368.229388 -165.868604)
			(xy 368.229388 -165.791388) (xy 368.228845 -165.780371) (xy 368.219621 -165.760361) (xy 368.211608 -165.75278)
			(xy 368.175684 -165.721462) (xy 368.10831 -165.654045) (xy 368.046431 -165.58155) (xy 367.990429 -165.504426)
			(xy 367.940649 -165.423146) (xy 367.897398 -165.338213) (xy 367.860941 -165.250149) (xy 367.831504 -165.159496)
			(xy 367.809268 -165.066814) (xy 367.79437 -164.972673) (xy 367.786903 -164.877654) (xy 367.786412 -164.829998)
			(xy 367.78693 -164.77982) (xy 367.795216 -164.679807) (xy 367.811732 -164.580819) (xy 367.836365 -164.483533)
			(xy 367.868946 -164.388613) (xy 367.909253 -164.296707) (xy 367.957011 -164.208443) (xy 368.011894 -164.124424)
			(xy 368.073526 -164.045223) (xy 368.141488 -163.971381) (xy 368.215314 -163.903403) (xy 368.294501 -163.841753)
			(xy 368.378508 -163.786852) (xy 368.466761 -163.739074) (xy 368.558658 -163.698746) (xy 368.65357 -163.666143)
			(xy 368.750851 -163.641489) (xy 368.849835 -163.62495) (xy 368.949846 -163.616642) (xy 369.000024 -163.616132)
			(xy 369.047685 -163.616612) (xy 369.142711 -163.624112) (xy 369.236857 -163.639041) (xy 369.329542 -163.661306)
			(xy 369.420195 -163.690771) (xy 369.508259 -163.727254) (xy 369.593191 -163.770531) (xy 369.674468 -163.820334)
			(xy 369.751588 -163.876358) (xy 369.824079 -163.938256) (xy 369.891492 -164.005649) (xy 369.922806 -164.041582)
			(xy 369.930377 -164.049607) (xy 369.950394 -164.058829) (xy 369.961414 -164.059362) (xy 370.03863 -164.059362)
			(xy 370.049647 -164.058818) (xy 370.069661 -164.049599) (xy 370.077238 -164.041582) (xy 370.108548 -164.005644)
			(xy 370.175953 -163.93824) (xy 370.248438 -163.876332) (xy 370.325556 -163.820301) (xy 370.406832 -163.770493)
			(xy 370.491765 -163.727215) (xy 370.579832 -163.690733) (xy 370.67049 -163.661273) (xy 370.763179 -163.639016)
			(xy 370.857328 -163.624099) (xy 370.952358 -163.616615) (xy 371.00002 -163.616132) (xy 371.050186 -163.616651)
			(xy 371.150175 -163.624937) (xy 371.249139 -163.64145) (xy 371.346402 -163.666079) (xy 371.441298 -163.698655)
			(xy 371.533181 -163.738955) (xy 371.621423 -163.786704) (xy 371.70542 -163.841576) (xy 371.7846 -163.903196)
			(xy 371.858422 -163.971144) (xy 371.926381 -164.044955) (xy 371.988014 -164.124125) (xy 372.042899 -164.208114)
			(xy 372.090662 -164.296348) (xy 372.130976 -164.388225) (xy 372.163566 -164.483116) (xy 372.18821 -164.580375)
			(xy 372.20474 -164.679336) (xy 372.213041 -164.779324) (xy 372.213632 -164.82949) (xy 372.213632 -164.829998)
			(xy 372.213165 -164.877655) (xy 372.205691 -164.972675) (xy 372.190788 -165.066816) (xy 372.168549 -165.159498)
			(xy 372.13911 -165.250152) (xy 372.102653 -165.338217) (xy 372.059403 -165.423153) (xy 372.009624 -165.504435)
			(xy 371.953625 -165.581563) (xy 371.891751 -165.654062) (xy 371.824381 -165.721486) (xy 371.788436 -165.75278)
			(xy 371.780404 -165.760348) (xy 371.771169 -165.780366) (xy 371.770656 -165.791388) (xy 371.770656 -165.868604)
			(xy 371.771196 -165.879623) (xy 371.78041 -165.899643) (xy 371.788436 -165.907212) (xy 371.826061 -165.940035)
			(xy 371.896385 -166.010927) (xy 371.960646 -166.087357) (xy 372.018411 -166.168807) (xy 372.069289 -166.254728)
			(xy 372.112936 -166.344539) (xy 372.149057 -166.437632) (xy 372.177408 -166.533378) (xy 372.197796 -166.631129)
			(xy 372.210085 -166.730226) (xy 372.214191 -166.829996) (xy 372.210086 -166.929767) (xy 372.197798 -167.028863)
			(xy 372.17741 -167.126614) (xy 372.14906 -167.22236) (xy 372.112939 -167.315454) (xy 372.069293 -167.405265)
			(xy 372.018416 -167.491186) (xy 371.960651 -167.572637) (xy 371.89639 -167.649067) (xy 371.826067 -167.719959)
			(xy 371.788436 -167.752776) (xy 371.780404 -167.760344) (xy 371.771167 -167.780361) (xy 371.770656 -167.791384)
			(xy 371.770656 -167.8686) (xy 371.771195 -167.87962) (xy 371.780408 -167.899641) (xy 371.788436 -167.907208)
			(xy 371.824361 -167.938525) (xy 371.891739 -168.005941) (xy 371.953621 -168.078434) (xy 372.009627 -168.155558)
			(xy 372.05941 -168.236837) (xy 372.102665 -168.32177) (xy 372.139124 -168.409835) (xy 372.168563 -168.500488)
			(xy 372.190801 -168.593171) (xy 372.2057 -168.687313) (xy 372.21317 -168.782333) (xy 372.213632 -168.82999)
			(xy 372.213114 -168.880168) (xy 372.204829 -168.98018) (xy 372.188314 -169.079167) (xy 372.163681 -169.176452)
			(xy 372.1311 -169.271371) (xy 372.090793 -169.363275) (xy 372.043035 -169.451538) (xy 371.988152 -169.535556)
			(xy 371.926519 -169.614755) (xy 371.858557 -169.688594) (xy 371.78473 -169.75657) (xy 371.705543 -169.818218)
			(xy 371.621535 -169.873117) (xy 371.533282 -169.920892) (xy 371.441385 -169.961217) (xy 371.346472 -169.993816)
			(xy 371.249192 -170.018466) (xy 371.150208 -170.035) (xy 371.050197 -170.043305) (xy 371.00002 -170.043856)
			(xy 370.952359 -170.043378) (xy 370.857331 -170.035881) (xy 370.763183 -170.020955) (xy 370.670496 -169.998692)
			(xy 370.579841 -169.969229) (xy 370.491775 -169.932748) (xy 370.406841 -169.889473) (xy 370.325562 -169.839671)
			(xy 370.248439 -169.783648) (xy 370.175946 -169.72175) (xy 370.108531 -169.654358) (xy 370.077238 -169.618406)
			(xy 370.069669 -169.610375) (xy 370.049652 -169.601139) (xy 370.03863 -169.600626) (xy 369.961414 -169.600626)
			(xy 369.950395 -169.601164) (xy 369.930378 -169.610383) (xy 369.922806 -169.618406) (xy 369.891496 -169.654346)
			(xy 369.824093 -169.721753) (xy 369.751609 -169.783664) (xy 369.674491 -169.839698) (xy 369.593216 -169.88951)
			(xy 369.508283 -169.932791) (xy 369.420216 -169.969276) (xy 369.329558 -169.99874) (xy 369.236868 -170.021001)
			(xy 369.142718 -170.035921) (xy 369.047687 -170.043409) (xy 369.000024 -170.043856) (xy 368.950042 -170.043347)
			(xy 368.850416 -170.035126) (xy 368.751805 -170.018737) (xy 368.654876 -169.994292) (xy 368.560286 -169.961956)
			(xy 368.468677 -169.921949) (xy 368.380669 -169.874542) (xy 368.296859 -169.820056) (xy 368.217816 -169.75886)
			(xy 368.144074 -169.691369) (xy 368.076134 -169.618041) (xy 368.014457 -169.539373) (xy 367.95946 -169.455897)
			(xy 367.911516 -169.368181) (xy 367.87095 -169.276818) (xy 367.838037 -169.182427) (xy 367.813001 -169.085649)
			(xy 367.803938 -169.036492) (xy 367.801338 -169.024871) (xy 367.787292 -169.005679) (xy 367.777014 -168.999662)
			(xy 367.693702 -168.957244) (xy 367.669826 -168.957244) (xy 367.658904 -168.962578) (xy 367.611629 -168.985448)
			(xy 367.514429 -169.02524) (xy 367.414663 -169.058071) (xy 367.312828 -169.083778) (xy 367.209432 -169.102232)
			(xy 367.104992 -169.113342) (xy 367.000028 -169.117051) (xy 366.895064 -169.113342) (xy 366.790624 -169.102232)
			(xy 366.687228 -169.083778) (xy 366.585393 -169.058071) (xy 366.485627 -169.02524) (xy 366.388427 -168.985448)
			(xy 366.341152 -168.962578) (xy 366.33023 -168.957244) (xy 366.306354 -168.957244) (xy 366.223042 -168.999662)
			(xy 366.212731 -169.005639) (xy 366.198685 -169.024854) (xy 366.196118 -169.036492) (xy 366.18711 -169.085657)
			(xy 366.162054 -169.182427) (xy 366.129125 -169.276809) (xy 366.088546 -169.368163) (xy 366.040591 -169.455871)
			(xy 365.985586 -169.539338) (xy 365.923902 -169.617998) (xy 365.855959 -169.691318) (xy 365.782215 -169.758803)
			(xy 365.703172 -169.819995) (xy 365.619363 -169.874478) (xy 365.531358 -169.921885) (xy 365.439753 -169.961893)
			(xy 365.345167 -169.994232) (xy 365.248242 -170.018683) (xy 365.149634 -170.03508) (xy 365.050013 -170.043311)
			(xy 365.000032 -170.043856) (xy 364.95237 -170.043378) (xy 364.857342 -170.035882) (xy 364.763194 -170.020957)
			(xy 364.670507 -169.998695) (xy 364.57985 -169.969233) (xy 364.491784 -169.932752) (xy 364.406849 -169.889478)
			(xy 364.325569 -169.839676) (xy 364.248446 -169.783654) (xy 364.175952 -169.721756) (xy 364.108537 -169.654364)
			(xy 364.07725 -169.618406) (xy 364.069682 -169.610373) (xy 364.049665 -169.601132) (xy 364.038642 -169.600626)
			(xy 363.961426 -169.600626) (xy 363.950406 -169.601162) (xy 363.930385 -169.610378) (xy 363.922818 -169.618406)
			(xy 363.889364 -169.656744) (xy 363.816994 -169.728279) (xy 363.738877 -169.79349) (xy 363.69752 -169.82313)
			(xy 363.690104 -169.828832) (xy 363.679658 -169.84433) (xy 363.675474 -169.862546) (xy 363.678111 -169.881049)
			(xy 363.68228 -169.889424) (xy 363.703462 -169.928949) (xy 363.738682 -170.011422) (xy 363.765422 -170.097022)
			(xy 363.783409 -170.184878) (xy 363.792463 -170.274099) (xy 363.793024 -170.318938) (xy 363.792889 -170.340053)
			(xy 363.790854 -170.382235) (xy 363.78896 -170.403266) (xy 363.788421 -170.414903) (xy 363.796623 -170.436682)
			(xy 363.81357 -170.452631) (xy 363.82452 -170.456606) (xy 363.906061 -170.48131) (xy 364.070879 -170.524571)
			(xy 364.237395 -170.560745) (xy 364.405306 -170.589766) (xy 364.574304 -170.611582) (xy 364.74408 -170.626152)
			(xy 364.914324 -170.633449) (xy 364.999524 -170.633898)
		)
		(stroke
			(width 0)
			(type solid)
		)
		(fill yes)
		(layer "In4.Cu")
		(net "P52V_HS1")
	)
	(gr_poly
		(pts
			(xy 419.547802 -77.088492) (xy 419.567357 -77.085572) (xy 419.606772 -77.082396) (xy 419.626542 -77.082142)
			(xy 419.646313 -77.082381) (xy 419.685728 -77.085563) (xy 419.705282 -77.088492) (xy 419.7096 -77.089)
			(xy 472.437206 -77.089) (xy 472.447084 -77.088542) (xy 472.465386 -77.081102) (xy 472.472766 -77.074522)
			(xy 472.47302 -77.074268) (xy 472.780614 -76.766674) (xy 472.781122 -76.766166) (xy 472.787711 -76.758787)
			(xy 472.795173 -76.740488) (xy 472.7956 -76.730606) (xy 472.7956 -68.303394) (xy 472.795176 -68.293324)
			(xy 472.78746 -68.274721) (xy 472.780614 -68.267326) (xy 472.473274 -67.959986) (xy 472.466162 -67.95262)
			(xy 472.447366 -67.945) (xy 468.0458 -67.945) (xy 468.01254 -67.944479) (xy 467.94659 -67.935791)
			(xy 467.882339 -67.918566) (xy 467.820888 -67.893097) (xy 467.763289 -67.859821) (xy 467.710529 -67.819308)
			(xy 467.686644 -67.796156) (xy 466.619844 -66.729356) (xy 466.596688 -66.705476) (xy 466.556182 -66.652712)
			(xy 466.522911 -66.595111) (xy 466.497447 -66.53366) (xy 466.480225 -66.469409) (xy 466.471539 -66.403459)
			(xy 466.471 -66.3702) (xy 466.471 -41.658794) (xy 466.470576 -41.648724) (xy 466.46286 -41.630121)
			(xy 466.456014 -41.622726) (xy 460.306674 -35.473386) (xy 460.299562 -35.46602) (xy 460.280766 -35.4584)
			(xy 452.923148 -35.4584) (xy 452.889887 -35.457882) (xy 452.823933 -35.4492) (xy 452.759679 -35.431979)
			(xy 452.698223 -35.406515) (xy 452.64062 -35.373242) (xy 452.587856 -35.332731) (xy 452.563992 -35.309556)
			(xy 450.931534 -33.677352) (xy 450.898768 -33.672272) (xy 450.883782 -33.680146) (xy 450.845449 -33.69975)
			(xy 450.765736 -33.732302) (xy 450.68325 -33.756999) (xy 450.598764 -33.77361) (xy 450.513068 -33.78198)
			(xy 450.470016 -33.782508) (xy 450.469 -33.782508) (xy 450.427898 -33.782033) (xy 450.346043 -33.774448)
			(xy 450.265238 -33.759343) (xy 450.186171 -33.736847) (xy 450.109517 -33.707151) (xy 450.03593 -33.670509)
			(xy 449.966038 -33.627234) (xy 449.900437 -33.577694) (xy 449.839687 -33.522313) (xy 449.784306 -33.461563)
			(xy 449.734766 -33.395962) (xy 449.691491 -33.32607) (xy 449.654849 -33.252483) (xy 449.625153 -33.175829)
			(xy 449.602657 -33.096762) (xy 449.587552 -33.015957) (xy 449.579967 -32.934102) (xy 449.579492 -32.893)
			(xy 449.579492 -32.891984) (xy 449.580022 -32.848933) (xy 449.588392 -32.763237) (xy 449.605003 -32.678751)
			(xy 449.6297 -32.596265) (xy 449.662252 -32.516552) (xy 449.681854 -32.478218) (xy 449.689728 -32.463232)
			(xy 449.684648 -32.430466) (xy 448.440048 -31.185866) (xy 448.410838 -31.179516) (xy 448.396614 -31.18485)
			(xy 448.349878 -31.201106) (xy 448.339972 -31.204408) (xy 448.324478 -31.217616) (xy 448.287902 -31.29153)
			(xy 448.284595 -31.298802) (xy 448.282269 -31.3146) (xy 448.28333 -31.322518) (xy 448.284854 -31.331916)
			(xy 448.286124 -31.33598) (xy 448.298072 -31.371331) (xy 448.316699 -31.443597) (xy 448.329209 -31.517168)
			(xy 448.335514 -31.591529) (xy 448.335908 -31.628842) (xy 448.335908 -31.629096) (xy 448.335404 -31.671444)
			(xy 448.327353 -31.755758) (xy 448.311324 -31.838924) (xy 448.287463 -31.920191) (xy 448.255984 -31.998821)
			(xy 448.217173 -32.074102) (xy 448.171383 -32.145354) (xy 448.119027 -32.21193) (xy 448.060579 -32.273228)
			(xy 447.996569 -32.328693) (xy 447.927577 -32.377822) (xy 447.854227 -32.420171) (xy 447.777184 -32.455355)
			(xy 447.697145 -32.483057) (xy 447.614836 -32.503025) (xy 447.531001 -32.515078) (xy 447.4464 -32.519109)
			(xy 447.361799 -32.515078) (xy 447.277964 -32.503025) (xy 447.195655 -32.483057) (xy 447.115616 -32.455355)
			(xy 447.038573 -32.420171) (xy 446.965223 -32.377822) (xy 446.896231 -32.328693) (xy 446.832221 -32.273228)
			(xy 446.773773 -32.21193) (xy 446.721417 -32.145354) (xy 446.675627 -32.074102) (xy 446.636816 -31.998821)
			(xy 446.605337 -31.920191) (xy 446.581476 -31.838924) (xy 446.565447 -31.755758) (xy 446.557396 -31.671444)
			(xy 446.556892 -31.629096) (xy 446.557412 -31.585836) (xy 446.565821 -31.499726) (xy 446.582549 -31.414839)
			(xy 446.607438 -31.331977) (xy 446.640252 -31.251922) (xy 446.680683 -31.17543) (xy 446.728349 -31.103224)
			(xy 446.782798 -31.035987) (xy 446.843517 -30.974352) (xy 446.909932 -30.918902) (xy 446.981416 -30.870162)
			(xy 447.057294 -30.82859) (xy 447.136849 -30.794581) (xy 447.177922 -30.78099) (xy 447.187828 -30.777688)
			(xy 447.203322 -30.76448) (xy 447.239898 -30.690566) (xy 447.243204 -30.683294) (xy 447.245529 -30.667497)
			(xy 447.24447 -30.659578) (xy 447.242946 -30.65018) (xy 447.241676 -30.646116) (xy 447.229729 -30.610765)
			(xy 447.211101 -30.538499) (xy 447.198592 -30.464928) (xy 447.192287 -30.390567) (xy 447.191892 -30.353254)
			(xy 447.191892 -30.352492) (xy 447.192338 -30.312241) (xy 447.199611 -30.232067) (xy 447.214105 -30.15288)
			(xy 447.235702 -30.075329) (xy 447.24955 -30.037532) (xy 447.254884 -30.023562) (xy 447.249042 -29.995114)
			(xy 447.238628 -29.984192) (xy 447.237866 -29.98343) (xy 447.226436 -29.972) (xy 447.225928 -29.971492)
			(xy 447.212466 -29.958284) (xy 447.205088 -29.951695) (xy 447.186788 -29.944232) (xy 447.176906 -29.943806)
			(xy 447.162682 -29.943806) (xy 447.156586 -29.94533) (xy 447.120912 -29.953966) (xy 447.048509 -29.966042)
			(xy 446.975356 -29.972111) (xy 446.938654 -29.972508) (xy 446.9384 -29.972508) (xy 446.897298 -29.972033)
			(xy 446.815443 -29.964448) (xy 446.734638 -29.949343) (xy 446.655571 -29.926847) (xy 446.578917 -29.897151)
			(xy 446.50533 -29.860509) (xy 446.435438 -29.817234) (xy 446.369837 -29.767694) (xy 446.309087 -29.712313)
			(xy 446.253706 -29.651563) (xy 446.204166 -29.585962) (xy 446.160891 -29.51607) (xy 446.124249 -29.442483)
			(xy 446.094553 -29.365829) (xy 446.072057 -29.286762) (xy 446.056952 -29.205957) (xy 446.049367 -29.124102)
			(xy 446.048892 -29.083) (xy 446.048892 -29.082746) (xy 446.049288 -29.045037) (xy 446.055699 -28.969891)
			(xy 446.068462 -28.895561) (xy 446.077594 -28.858972) (xy 446.08115 -28.845764) (xy 446.074038 -28.819856)
			(xy 435.031642 -17.777206) (xy 435.02453 -17.76984) (xy 435.005734 -17.76222) (xy 428.27702 -17.76222)
			(xy 428.243759 -17.7617) (xy 428.177808 -17.753015) (xy 428.113555 -17.735792) (xy 428.052101 -17.710326)
			(xy 427.9945 -17.677052) (xy 427.941737 -17.636541) (xy 427.917864 -17.613376) (xy 422.315386 -12.010898)
			(xy 422.292226 -11.98702) (xy 422.251712 -11.934258) (xy 422.218434 -11.876658) (xy 422.192963 -11.815206)
			(xy 422.175734 -11.750954) (xy 422.167042 -11.685003) (xy 422.166542 -11.651742) (xy 422.166542 -2.091944)
			(xy 422.166448 -2.086783) (xy 422.164398 -2.076669) (xy 422.162478 -2.071878) (xy 422.150794 -2.045208)
			(xy 422.143682 -2.038096) (xy 422.135808 -2.030222) (xy 421.136318 -1.030986) (xy 421.129206 -1.02362)
			(xy 421.11041 -1.016) (xy 419.582092 -1.016) (xy 419.55593 -1.034796) (xy 419.550596 -1.05029) (xy 419.536394 -1.090337)
			(xy 419.501383 -1.167764) (xy 419.459148 -1.2415) (xy 419.410073 -1.310871) (xy 419.354606 -1.375247)
			(xy 419.293253 -1.434039) (xy 419.226572 -1.486713) (xy 419.155173 -1.532787) (xy 419.079704 -1.571843)
			(xy 419.000856 -1.603523) (xy 418.919345 -1.627539) (xy 418.835915 -1.643673) (xy 418.751328 -1.651777)
			(xy 418.666352 -1.651777) (xy 418.581765 -1.643673) (xy 418.498335 -1.627539) (xy 418.416824 -1.603523)
			(xy 418.337976 -1.571843) (xy 418.262507 -1.532787) (xy 418.191108 -1.486713) (xy 418.124427 -1.434039)
			(xy 418.063074 -1.375247) (xy 418.007607 -1.310871) (xy 417.958532 -1.2415) (xy 417.916297 -1.167764)
			(xy 417.881286 -1.090337) (xy 417.867084 -1.05029) (xy 417.86175 -1.034796) (xy 417.835588 -1.016)
			(xy 414.502092 -1.016) (xy 414.47593 -1.034796) (xy 414.470596 -1.05029) (xy 414.456394 -1.090337)
			(xy 414.421383 -1.167764) (xy 414.379148 -1.2415) (xy 414.330073 -1.310871) (xy 414.274606 -1.375247)
			(xy 414.213253 -1.434039) (xy 414.146572 -1.486713) (xy 414.075173 -1.532787) (xy 413.999704 -1.571843)
			(xy 413.920856 -1.603523) (xy 413.839345 -1.627539) (xy 413.755915 -1.643673) (xy 413.671328 -1.651777)
			(xy 413.586352 -1.651777) (xy 413.501765 -1.643673) (xy 413.418335 -1.627539) (xy 413.336824 -1.603523)
			(xy 413.257976 -1.571843) (xy 413.182507 -1.532787) (xy 413.111108 -1.486713) (xy 413.044427 -1.434039)
			(xy 412.983074 -1.375247) (xy 412.927607 -1.310871) (xy 412.878532 -1.2415) (xy 412.836297 -1.167764)
			(xy 412.801286 -1.090337) (xy 412.787084 -1.05029) (xy 412.78175 -1.034796) (xy 412.755588 -1.016)
			(xy 409.422092 -1.016) (xy 409.39593 -1.034796) (xy 409.390596 -1.05029) (xy 409.376394 -1.090337)
			(xy 409.341383 -1.167764) (xy 409.299148 -1.2415) (xy 409.250073 -1.310871) (xy 409.194606 -1.375247)
			(xy 409.133253 -1.434039) (xy 409.066572 -1.486713) (xy 408.995173 -1.532787) (xy 408.919704 -1.571843)
			(xy 408.840856 -1.603523) (xy 408.759345 -1.627539) (xy 408.675915 -1.643673) (xy 408.591328 -1.651777)
			(xy 408.506352 -1.651777) (xy 408.421765 -1.643673) (xy 408.338335 -1.627539) (xy 408.256824 -1.603523)
			(xy 408.177976 -1.571843) (xy 408.102507 -1.532787) (xy 408.031108 -1.486713) (xy 407.964427 -1.434039)
			(xy 407.903074 -1.375247) (xy 407.847607 -1.310871) (xy 407.798532 -1.2415) (xy 407.756297 -1.167764)
			(xy 407.721286 -1.090337) (xy 407.707084 -1.05029) (xy 407.70175 -1.034796) (xy 407.675588 -1.016)
			(xy 404.342092 -1.016) (xy 404.31593 -1.034796) (xy 404.310596 -1.05029) (xy 404.296394 -1.090337)
			(xy 404.261383 -1.167764) (xy 404.219148 -1.2415) (xy 404.170073 -1.310871) (xy 404.114606 -1.375247)
			(xy 404.053253 -1.434039) (xy 403.986572 -1.486713) (xy 403.915173 -1.532787) (xy 403.839704 -1.571843)
			(xy 403.760856 -1.603523) (xy 403.679345 -1.627539) (xy 403.595915 -1.643673) (xy 403.511328 -1.651777)
			(xy 403.426352 -1.651777) (xy 403.341765 -1.643673) (xy 403.258335 -1.627539) (xy 403.176824 -1.603523)
			(xy 403.097976 -1.571843) (xy 403.022507 -1.532787) (xy 402.951108 -1.486713) (xy 402.884427 -1.434039)
			(xy 402.823074 -1.375247) (xy 402.767607 -1.310871) (xy 402.718532 -1.2415) (xy 402.676297 -1.167764)
			(xy 402.641286 -1.090337) (xy 402.627084 -1.05029) (xy 402.62175 -1.034796) (xy 402.595588 -1.016)
			(xy 399.262092 -1.016) (xy 399.23593 -1.034796) (xy 399.230596 -1.05029) (xy 399.216394 -1.090337)
			(xy 399.181383 -1.167764) (xy 399.139148 -1.2415) (xy 399.090073 -1.310871) (xy 399.034606 -1.375247)
			(xy 398.973253 -1.434039) (xy 398.906572 -1.486713) (xy 398.835173 -1.532787) (xy 398.759704 -1.571843)
			(xy 398.680856 -1.603523) (xy 398.599345 -1.627539) (xy 398.515915 -1.643673) (xy 398.431328 -1.651777)
			(xy 398.346352 -1.651777) (xy 398.261765 -1.643673) (xy 398.178335 -1.627539) (xy 398.096824 -1.603523)
			(xy 398.017976 -1.571843) (xy 397.942507 -1.532787) (xy 397.871108 -1.486713) (xy 397.804427 -1.434039)
			(xy 397.743074 -1.375247) (xy 397.687607 -1.310871) (xy 397.638532 -1.2415) (xy 397.596297 -1.167764)
			(xy 397.561286 -1.090337) (xy 397.547084 -1.05029) (xy 397.54175 -1.034796) (xy 397.515588 -1.016)
			(xy 394.182092 -1.016) (xy 394.15593 -1.034796) (xy 394.150596 -1.05029) (xy 394.136394 -1.090337)
			(xy 394.101383 -1.167764) (xy 394.059148 -1.2415) (xy 394.010073 -1.310871) (xy 393.954606 -1.375247)
			(xy 393.893253 -1.434039) (xy 393.826572 -1.486713) (xy 393.755173 -1.532787) (xy 393.679704 -1.571843)
			(xy 393.600856 -1.603523) (xy 393.519345 -1.627539) (xy 393.435915 -1.643673) (xy 393.351328 -1.651777)
			(xy 393.266352 -1.651777) (xy 393.181765 -1.643673) (xy 393.098335 -1.627539) (xy 393.016824 -1.603523)
			(xy 392.937976 -1.571843) (xy 392.862507 -1.532787) (xy 392.791108 -1.486713) (xy 392.724427 -1.434039)
			(xy 392.663074 -1.375247) (xy 392.607607 -1.310871) (xy 392.558532 -1.2415) (xy 392.516297 -1.167764)
			(xy 392.481286 -1.090337) (xy 392.467084 -1.05029) (xy 392.46175 -1.034796) (xy 392.435588 -1.016)
			(xy 389.102092 -1.016) (xy 389.07593 -1.034796) (xy 389.070596 -1.05029) (xy 389.056394 -1.090337)
			(xy 389.021383 -1.167764) (xy 388.979148 -1.2415) (xy 388.930073 -1.310871) (xy 388.874606 -1.375247)
			(xy 388.813253 -1.434039) (xy 388.746572 -1.486713) (xy 388.675173 -1.532787) (xy 388.599704 -1.571843)
			(xy 388.520856 -1.603523) (xy 388.439345 -1.627539) (xy 388.355915 -1.643673) (xy 388.271328 -1.651777)
			(xy 388.186352 -1.651777) (xy 388.101765 -1.643673) (xy 388.018335 -1.627539) (xy 387.936824 -1.603523)
			(xy 387.857976 -1.571843) (xy 387.782507 -1.532787) (xy 387.711108 -1.486713) (xy 387.644427 -1.434039)
			(xy 387.583074 -1.375247) (xy 387.527607 -1.310871) (xy 387.478532 -1.2415) (xy 387.436297 -1.167764)
			(xy 387.401286 -1.090337) (xy 387.387084 -1.05029) (xy 387.38175 -1.034796) (xy 387.355588 -1.016)
			(xy 384.022092 -1.016) (xy 383.99593 -1.034796) (xy 383.990596 -1.05029) (xy 383.976394 -1.090337)
			(xy 383.941383 -1.167764) (xy 383.899148 -1.2415) (xy 383.850073 -1.310871) (xy 383.794606 -1.375247)
			(xy 383.733253 -1.434039) (xy 383.666572 -1.486713) (xy 383.595173 -1.532787) (xy 383.519704 -1.571843)
			(xy 383.440856 -1.603523) (xy 383.359345 -1.627539) (xy 383.275915 -1.643673) (xy 383.191328 -1.651777)
			(xy 383.106352 -1.651777) (xy 383.021765 -1.643673) (xy 382.938335 -1.627539) (xy 382.856824 -1.603523)
			(xy 382.777976 -1.571843) (xy 382.702507 -1.532787) (xy 382.631108 -1.486713) (xy 382.564427 -1.434039)
			(xy 382.503074 -1.375247) (xy 382.447607 -1.310871) (xy 382.398532 -1.2415) (xy 382.356297 -1.167764)
			(xy 382.321286 -1.090337) (xy 382.307084 -1.05029) (xy 382.30175 -1.034796) (xy 382.275588 -1.016)
			(xy 380.150878 -1.016) (xy 380.142392 -1.01631) (xy 380.126356 -1.021866) (xy 380.113038 -1.032385)
			(xy 380.108206 -1.039368) (xy 380.101348 -1.050036) (xy 380.099316 -1.075944) (xy 380.110492 -1.100328)
			(xy 380.116842 -1.10871) (xy 380.120906 -1.112266) (xy 380.168811 -1.155144) (xy 380.25956 -1.246231)
			(xy 380.344173 -1.343046) (xy 380.422288 -1.445176) (xy 380.493573 -1.552185) (xy 380.557724 -1.663617)
			(xy 380.614467 -1.778997) (xy 380.66356 -1.897835) (xy 380.704794 -2.019622) (xy 380.737995 -2.14384)
			(xy 380.763019 -2.26996) (xy 380.77976 -2.397444) (xy 380.788147 -2.525749) (xy 380.788672 -2.590038)
			(xy 380.788185 -2.651893) (xy 380.780415 -2.775358) (xy 380.764908 -2.898092) (xy 380.741725 -3.01961)
			(xy 380.710958 -3.139432) (xy 380.672728 -3.257087) (xy 380.627186 -3.372108) (xy 380.574512 -3.484043)
			(xy 380.514913 -3.59245) (xy 380.448626 -3.696901) (xy 380.37591 -3.796984) (xy 380.297054 -3.892303)
			(xy 380.212369 -3.982483) (xy 380.122188 -4.067167) (xy 380.026868 -4.146022) (xy 379.926784 -4.218737)
			(xy 379.822333 -4.285024) (xy 379.713925 -4.344621) (xy 379.60199 -4.397294) (xy 379.486968 -4.442835)
			(xy 379.369313 -4.481064) (xy 379.24949 -4.51183) (xy 379.127972 -4.535011) (xy 379.005238 -4.550517)
			(xy 378.881773 -4.558286) (xy 378.819918 -4.558792) (xy 378.755106 -4.558265) (xy 378.625764 -4.54974)
			(xy 378.497262 -4.532727) (xy 378.370158 -4.507299) (xy 378.245001 -4.473566) (xy 378.122334 -4.431675)
			(xy 378.002688 -4.381806) (xy 377.88658 -4.324176) (xy 377.774515 -4.259034) (xy 377.666977 -4.186662)
			(xy 377.564432 -4.107374) (xy 377.467323 -4.021513) (xy 377.376072 -3.929451) (xy 377.291074 -3.831586)
			(xy 377.251468 -3.780282) (xy 377.24334 -3.76936) (xy 377.218956 -3.758946) (xy 377.10491 -3.772154)
			(xy 377.083574 -3.787648) (xy 377.077986 -3.800348) (xy 377.05741 -3.845183) (xy 377.009983 -3.931692)
			(xy 376.955688 -4.014063) (xy 376.894883 -4.091754) (xy 376.827969 -4.16425) (xy 376.755389 -4.231072)
			(xy 376.677622 -4.291779) (xy 376.595182 -4.345971) (xy 376.508614 -4.393288) (xy 376.418488 -4.43342)
			(xy 376.325401 -4.466099) (xy 376.229968 -4.491111) (xy 376.132819 -4.50829) (xy 376.034596 -4.517524)
			(xy 375.985278 -4.51866) (xy 375.975118 -4.51866) (xy 375.957084 -4.52628) (xy 375.94413 -4.539234)
			(xy 375.937456 -4.546645) (xy 375.929876 -4.565072) (xy 375.92989 -4.584996) (xy 375.937494 -4.603412)
			(xy 375.94413 -4.610862) (xy 375.957084 -4.623816) (xy 375.975118 -4.631436) (xy 375.985278 -4.631436)
			(xy 376.034332 -4.632539) (xy 376.132033 -4.641692) (xy 376.228676 -4.658703) (xy 376.32363 -4.68346)
			(xy 376.416276 -4.715802) (xy 376.506008 -4.755519) (xy 376.59224 -4.80235) (xy 376.67441 -4.855991)
			(xy 376.751982 -4.91609) (xy 376.824448 -4.982256) (xy 376.891336 -5.054056) (xy 376.952208 -5.131022)
			(xy 377.006668 -5.212651) (xy 377.054361 -5.29841) (xy 377.094974 -5.38774) (xy 377.128242 -5.480057)
			(xy 377.153949 -5.574759) (xy 377.171926 -5.671226) (xy 377.182056 -5.768831) (xy 377.184273 -5.866934)
			(xy 377.178563 -5.964897) (xy 377.164962 -6.062078) (xy 377.14356 -6.157844) (xy 377.114496 -6.25157)
			(xy 377.07796 -6.342644) (xy 377.034191 -6.43047) (xy 376.983474 -6.514476) (xy 376.926141 -6.594113)
			(xy 376.862565 -6.668862) (xy 376.793162 -6.738234) (xy 376.718385 -6.801776) (xy 376.638722 -6.859074)
			(xy 376.554693 -6.909753) (xy 376.466847 -6.953483) (xy 376.375758 -6.989978) (xy 376.282019 -7.019)
			(xy 376.186243 -7.040359) (xy 376.089055 -7.053916) (xy 375.991091 -7.059582) (xy 375.892988 -7.057321)
			(xy 375.795388 -7.047148) (xy 375.698928 -7.029127) (xy 375.604238 -7.003378) (xy 375.511936 -6.970069)
			(xy 375.422625 -6.929416) (xy 375.336887 -6.881685) (xy 375.255282 -6.827188) (xy 375.178343 -6.766281)
			(xy 375.106573 -6.699361) (xy 375.04044 -6.626866) (xy 374.980375 -6.549267) (xy 374.926772 -6.467073)
			(xy 374.879979 -6.38082) (xy 374.840303 -6.29107) (xy 374.808002 -6.19841) (xy 374.783287 -6.103445)
			(xy 374.76632 -6.006794) (xy 374.757211 -5.909089) (xy 374.756172 -5.860034) (xy 374.756172 -5.849874)
			(xy 374.748552 -5.83184) (xy 374.705372 -5.78866) (xy 374.694704 -5.78866) (xy 374.651524 -5.83184)
			(xy 374.643904 -5.849874) (xy 374.643904 -5.860034) (xy 374.642787 -5.909818) (xy 374.633403 -6.008963)
			(xy 374.615928 -6.107006) (xy 374.590478 -6.203287) (xy 374.557225 -6.29716) (xy 374.516393 -6.387992)
			(xy 374.468257 -6.475174) (xy 374.413139 -6.558119) (xy 374.35141 -6.636269) (xy 374.283487 -6.709098)
			(xy 374.209824 -6.776118) (xy 374.130918 -6.836877) (xy 374.047299 -6.890967) (xy 373.95953 -6.938024)
			(xy 373.868201 -6.977731) (xy 373.773925 -7.009823) (xy 373.677336 -7.034082) (xy 373.579085 -7.050346)
			(xy 373.479832 -7.058505) (xy 373.380244 -7.058505) (xy 373.280991 -7.050346) (xy 373.18274 -7.034082)
			(xy 373.086151 -7.009823) (xy 372.991875 -6.977731) (xy 372.900546 -6.938024) (xy 372.812777 -6.890967)
			(xy 372.729158 -6.836877) (xy 372.650252 -6.776118) (xy 372.576589 -6.709098) (xy 372.508666 -6.636269)
			(xy 372.446937 -6.558119) (xy 372.391819 -6.475174) (xy 372.343683 -6.387992) (xy 372.302851 -6.29716)
			(xy 372.269598 -6.203287) (xy 372.244148 -6.107006) (xy 372.226673 -6.008963) (xy 372.217289 -5.909818)
			(xy 372.216172 -5.860034) (xy 372.216172 -5.849874) (xy 372.208552 -5.83184) (xy 372.172992 -5.79628)
			(xy 372.154958 -5.78866) (xy 372.144798 -5.78866) (xy 372.095028 -5.787535) (xy 371.995913 -5.778136)
			(xy 371.897901 -5.76065) (xy 371.801651 -5.735193) (xy 371.707809 -5.701936) (xy 371.617008 -5.661104)
			(xy 371.529857 -5.61297) (xy 371.446942 -5.557858) (xy 371.368821 -5.496139) (xy 371.296018 -5.428228)
			(xy 371.229024 -5.35458) (xy 371.168288 -5.275692) (xy 371.114219 -5.192094) (xy 371.067181 -5.104347)
			(xy 371.027489 -5.013041) (xy 370.99541 -4.918791) (xy 370.97116 -4.822229) (xy 370.954903 -4.724006)
			(xy 370.946747 -4.624781) (xy 370.946747 -4.525221) (xy 370.954903 -4.425995) (xy 370.97116 -4.327772)
			(xy 370.99541 -4.23121) (xy 371.027488 -4.13696) (xy 371.06718 -4.045654) (xy 371.114219 -3.957907)
			(xy 371.168288 -3.874309) (xy 371.229023 -3.79542) (xy 371.296018 -3.721773) (xy 371.36882 -3.653862)
			(xy 371.446941 -3.592142) (xy 371.529856 -3.537031) (xy 371.617007 -3.488897) (xy 371.707808 -3.448064)
			(xy 371.801649 -3.414807) (xy 371.8979 -3.38935) (xy 371.995912 -3.371864) (xy 372.095027 -3.362465)
			(xy 372.144798 -3.361436) (xy 372.154958 -3.361436) (xy 372.172992 -3.353816) (xy 372.185946 -3.340862)
			(xy 372.192642 -3.333451) (xy 372.20026 -3.31501) (xy 372.200273 -3.295058) (xy 372.19268 -3.276606)
			(xy 372.185946 -3.269234) (xy 372.172992 -3.25628) (xy 372.154958 -3.24866) (xy 372.144798 -3.24866)
			(xy 372.095029 -3.247535) (xy 371.995917 -3.238137) (xy 371.897907 -3.220651) (xy 371.801659 -3.195195)
			(xy 371.70782 -3.16194) (xy 371.61702 -3.12111) (xy 371.529871 -3.072978) (xy 371.446957 -3.017869)
			(xy 371.368837 -2.956153) (xy 371.296035 -2.888245) (xy 371.229041 -2.814601) (xy 371.168305 -2.735716)
			(xy 371.114235 -2.652121) (xy 371.067195 -2.564377) (xy 371.027502 -2.473075) (xy 370.995421 -2.378828)
			(xy 370.971169 -2.28227) (xy 370.954908 -2.184049) (xy 370.946749 -2.084827) (xy 370.946172 -2.035048)
			(xy 370.946629 -1.988194) (xy 370.953874 -1.894767) (xy 370.968301 -1.802177) (xy 370.989825 -1.710975)
			(xy 371.018317 -1.621704) (xy 371.053607 -1.534896) (xy 371.095486 -1.451067) (xy 371.143704 -1.370717)
			(xy 371.197974 -1.294325) (xy 371.257973 -1.222344) (xy 371.290342 -1.188466) (xy 371.30101 -1.177544)
			(xy 371.306598 -1.147572) (xy 371.264434 -1.047242) (xy 371.260985 -1.039611) (xy 371.249959 -1.027019)
			(xy 371.242844 -1.022604) (xy 371.230906 -1.016) (xy 77.750924 -1.016) (xy 77.742434 -1.016303) (xy 77.726387 -1.021848)
			(xy 77.713057 -1.032364) (xy 77.708252 -1.039368) (xy 77.701394 -1.050036) (xy 77.699362 -1.075944)
			(xy 77.710538 -1.100328) (xy 77.716888 -1.10871) (xy 77.720952 -1.112266) (xy 77.768858 -1.155143)
			(xy 77.85961 -1.246229) (xy 77.944225 -1.343043) (xy 78.022342 -1.445172) (xy 78.093629 -1.552181)
			(xy 78.157781 -1.663613) (xy 78.214526 -1.778994) (xy 78.26362 -1.897831) (xy 78.304856 -2.019619)
			(xy 78.338057 -2.143838) (xy 78.363082 -2.269958) (xy 78.379824 -2.397443) (xy 78.388211 -2.525748)
			(xy 78.388718 -2.590038) (xy 78.388231 -2.651892) (xy 78.380461 -2.775356) (xy 78.364954 -2.898089)
			(xy 78.341771 -3.019605) (xy 78.311004 -3.139427) (xy 78.272773 -3.257079) (xy 78.227231 -3.3721)
			(xy 78.174557 -3.484033) (xy 78.114958 -3.592439) (xy 78.048669 -3.696888) (xy 77.975954 -3.796968)
			(xy 77.897097 -3.892286) (xy 77.832663 -3.960899) (xy 361.610479 -3.960899) (xy 361.613141 -3.835526)
			(xy 361.623776 -3.710577) (xy 361.642341 -3.586557) (xy 361.668761 -3.463971) (xy 361.702929 -3.343314)
			(xy 361.744705 -3.225076) (xy 361.793922 -3.109736) (xy 361.850378 -2.997762) (xy 361.913847 -2.889608)
			(xy 361.984069 -2.785713) (xy 362.060761 -2.686496) (xy 362.143611 -2.592362) (xy 362.232283 -2.50369)
			(xy 362.326419 -2.420841) (xy 362.425637 -2.344151) (xy 362.529534 -2.273931) (xy 362.637689 -2.210464)
			(xy 362.749663 -2.154009) (xy 362.865004 -2.104794) (xy 362.983242 -2.063019) (xy 363.1039 -2.028854)
			(xy 363.226487 -2.002436) (xy 363.350507 -1.983872) (xy 363.475456 -1.973239) (xy 363.600829 -1.970579)
			(xy 363.726118 -1.975903) (xy 363.850813 -1.989189) (xy 363.97441 -2.010384) (xy 364.096408 -2.039401)
			(xy 364.216312 -2.076123) (xy 364.333636 -2.120402) (xy 364.447905 -2.172057) (xy 364.558654 -2.230879)
			(xy 364.665436 -2.296629) (xy 364.767817 -2.369042) (xy 364.865383 -2.447823) (xy 364.957737 -2.532654)
			(xy 365.044505 -2.62319) (xy 365.125336 -2.719064) (xy 365.199902 -2.819888) (xy 365.2679 -2.925253)
			(xy 365.329055 -3.034731) (xy 365.38312 -3.147879) (xy 365.429874 -3.264239) (xy 365.469128 -3.383338)
			(xy 365.500724 -3.504694) (xy 365.524533 -3.627814) (xy 365.540458 -3.7522) (xy 365.548435 -3.877347)
			(xy 365.548926 -3.940048) (xy 365.548617 -3.98941) (xy 365.543662 -4.088008) (xy 365.53902 -4.137152)
			(xy 365.538484 -4.14788) (xy 365.545289 -4.168231) (xy 365.559804 -4.184035) (xy 365.579505 -4.192542)
			(xy 365.600961 -4.192272) (xy 365.610902 -4.188206) (xy 365.65882 -4.166657) (xy 365.757652 -4.130978)
			(xy 365.859199 -4.103978) (xy 365.9627 -4.08586) (xy 366.067381 -4.076759) (xy 366.119918 -4.076192)
			(xy 366.168813 -4.076769) (xy 366.266286 -4.084639) (xy 366.36281 -4.100327) (xy 366.457758 -4.123731)
			(xy 366.550516 -4.154699) (xy 366.64048 -4.193031) (xy 366.727069 -4.238477) (xy 366.80972 -4.290743)
			(xy 366.887897 -4.349491) (xy 366.961093 -4.414338) (xy 367.028834 -4.484865) (xy 367.090681 -4.560615)
			(xy 367.146232 -4.641095) (xy 367.195126 -4.725784) (xy 367.237048 -4.814133) (xy 367.271725 -4.905568)
			(xy 367.298931 -4.999498) (xy 367.318492 -5.095312) (xy 367.330279 -5.192389) (xy 367.334215 -5.290058)
			(xy 367.445547 -5.290058) (xy 367.449587 -5.191075) (xy 367.461682 -5.092752) (xy 367.481752 -4.995741)
			(xy 367.509662 -4.900689) (xy 367.545226 -4.808228) (xy 367.588209 -4.718973) (xy 367.638324 -4.633519)
			(xy 367.695237 -4.552434) (xy 367.75857 -4.476258) (xy 367.827901 -4.405498) (xy 367.90277 -4.340624)
			(xy 367.982677 -4.282069) (xy 368.067091 -4.230221) (xy 368.15545 -4.185427) (xy 368.247166 -4.147984)
			(xy 368.341629 -4.118141) (xy 368.43821 -4.096097) (xy 368.536267 -4.081998) (xy 368.635147 -4.075939)
			(xy 368.734191 -4.07796) (xy 368.832741 -4.088047) (xy 368.930141 -4.106133) (xy 369.025743 -4.132098)
			(xy 369.11891 -4.16577) (xy 369.209023 -4.206923) (xy 369.295481 -4.255284) (xy 369.37771 -4.310531)
			(xy 369.455162 -4.372297) (xy 369.527322 -4.440171) (xy 369.59371 -4.5137) (xy 369.653883 -4.592396)
			(xy 369.707441 -4.675735) (xy 369.754029 -4.763162) (xy 369.793335 -4.854095) (xy 369.825099 -4.94793)
			(xy 369.849108 -5.044041) (xy 369.865204 -5.14179) (xy 369.873279 -5.240526) (xy 369.873784 -5.290058)
			(xy 369.873279 -5.33959) (xy 369.865204 -5.438326) (xy 369.849108 -5.536075) (xy 369.825099 -5.632186)
			(xy 369.793335 -5.726021) (xy 369.754029 -5.816954) (xy 369.707441 -5.904381) (xy 369.653883 -5.98772)
			(xy 369.59371 -6.066416) (xy 369.527322 -6.139945) (xy 369.455162 -6.207819) (xy 369.37771 -6.269585)
			(xy 369.295481 -6.324832) (xy 369.209023 -6.373193) (xy 369.11891 -6.414346) (xy 369.025743 -6.448018)
			(xy 368.930141 -6.473983) (xy 368.832741 -6.492069) (xy 368.734191 -6.502156) (xy 368.635147 -6.504177)
			(xy 368.536267 -6.498118) (xy 368.43821 -6.484019) (xy 368.341629 -6.461975) (xy 368.247166 -6.432132)
			(xy 368.15545 -6.394689) (xy 368.067091 -6.349895) (xy 367.982677 -6.298047) (xy 367.90277 -6.239492)
			(xy 367.827901 -6.174618) (xy 367.75857 -6.103858) (xy 367.695237 -6.027682) (xy 367.638324 -5.946597)
			(xy 367.588209 -5.861143) (xy 367.545226 -5.771888) (xy 367.509662 -5.679427) (xy 367.481752 -5.584375)
			(xy 367.461682 -5.487364) (xy 367.449587 -5.389041) (xy 367.445547 -5.290058) (xy 367.334215 -5.290058)
			(xy 367.334217 -5.2901) (xy 367.330279 -5.387811) (xy 367.318492 -5.484888) (xy 367.298931 -5.580702)
			(xy 367.271725 -5.674632) (xy 367.237048 -5.766067) (xy 367.195126 -5.854416) (xy 367.146232 -5.939105)
			(xy 367.090681 -6.019585) (xy 367.028834 -6.095335) (xy 366.961093 -6.165862) (xy 366.887897 -6.230709)
			(xy 366.80972 -6.289457) (xy 366.727069 -6.341723) (xy 366.64048 -6.387169) (xy 366.550516 -6.425501)
			(xy 366.457758 -6.456469) (xy 366.36281 -6.479873) (xy 366.266286 -6.495561) (xy 366.168813 -6.503431)
			(xy 366.119918 -6.503924) (xy 366.06958 -6.503389) (xy 365.969249 -6.495043) (xy 365.869955 -6.478416)
			(xy 365.772379 -6.453621) (xy 365.677192 -6.42083) (xy 365.585048 -6.380267) (xy 365.496581 -6.332211)
			(xy 365.412398 -6.276992) (xy 365.333078 -6.214991) (xy 365.259166 -6.146633) (xy 365.19117 -6.072387)
			(xy 365.129557 -5.992765) (xy 365.074751 -5.908312) (xy 365.027129 -5.819611) (xy 364.987017 -5.72727)
			(xy 364.954692 -5.631924) (xy 364.930375 -5.534227) (xy 364.9218 -5.484622) (xy 364.919547 -5.474131)
			(xy 364.907728 -5.456246) (xy 364.889642 -5.444737) (xy 364.868435 -5.441607) (xy 364.847796 -5.447401)
			(xy 364.83925 -5.453888) (xy 364.791204 -5.493253) (xy 364.690882 -5.566511) (xy 364.58614 -5.633297)
			(xy 364.477396 -5.693346) (xy 364.365083 -5.74642) (xy 364.249646 -5.792307) (xy 364.131546 -5.830824)
			(xy 364.011252 -5.861819) (xy 363.889244 -5.885167) (xy 363.766006 -5.900776) (xy 363.642029 -5.908584)
			(xy 363.579918 -5.909056) (xy 363.517217 -5.908534) (xy 363.39207 -5.900555) (xy 363.267684 -5.884628)
			(xy 363.144564 -5.860817) (xy 363.023209 -5.82922) (xy 362.904111 -5.789964) (xy 362.787752 -5.743208)
			(xy 362.674604 -5.689141) (xy 362.565127 -5.627985) (xy 362.459763 -5.559985) (xy 362.358941 -5.485417)
			(xy 362.263068 -5.404585) (xy 362.172533 -5.317815) (xy 362.087704 -5.22546) (xy 362.008924 -5.127893)
			(xy 361.936513 -5.025511) (xy 361.870764 -4.918728) (xy 361.811943 -4.807978) (xy 361.76029 -4.693709)
			(xy 361.716014 -4.576384) (xy 361.679293 -4.456479) (xy 361.650278 -4.334481) (xy 361.629085 -4.210883)
			(xy 361.615801 -4.086188) (xy 361.610479 -3.960899) (xy 77.832663 -3.960899) (xy 77.812411 -3.982464)
			(xy 77.72223 -4.067146) (xy 77.62691 -4.145999) (xy 77.526826 -4.218711) (xy 77.422375 -4.284995)
			(xy 77.313967 -4.34459) (xy 77.202032 -4.397261) (xy 77.08701 -4.442799) (xy 76.969355 -4.481024)
			(xy 76.849533 -4.511787) (xy 76.728016 -4.534965) (xy 76.605282 -4.550468) (xy 76.481818 -4.558233)
			(xy 76.419964 -4.558792) (xy 76.355152 -4.558266) (xy 76.225808 -4.549745) (xy 76.097305 -4.532734)
			(xy 75.970198 -4.507309) (xy 75.845039 -4.473578) (xy 75.72237 -4.431689) (xy 75.602722 -4.381822)
			(xy 75.486612 -4.324193) (xy 75.374545 -4.259052) (xy 75.267004 -4.186682) (xy 75.164457 -4.107394)
			(xy 75.067346 -4.021534) (xy 74.976093 -3.929473) (xy 74.891092 -3.831609) (xy 74.851514 -3.780282)
			(xy 74.843386 -3.76936) (xy 74.819002 -3.758946) (xy 74.704956 -3.772154) (xy 74.68362 -3.787648)
			(xy 74.678032 -3.800348) (xy 74.657456 -3.845184) (xy 74.61003 -3.931695) (xy 74.555736 -4.014069)
			(xy 74.494931 -4.091761) (xy 74.428018 -4.16426) (xy 74.355439 -4.231085) (xy 74.277672 -4.291795)
			(xy 74.195232 -4.34599) (xy 74.108664 -4.39331) (xy 74.018538 -4.433445) (xy 73.925451 -4.466128)
			(xy 73.830018 -4.491143) (xy 73.732868 -4.508326) (xy 73.634643 -4.517563) (xy 73.585324 -4.51866)
			(xy 73.575164 -4.51866) (xy 73.55713 -4.52628) (xy 73.513696 -4.569714) (xy 73.513696 -4.580382)
			(xy 73.55713 -4.623816) (xy 73.575164 -4.631436) (xy 73.585324 -4.631436) (xy 73.635092 -4.632558)
			(xy 73.734203 -4.641951) (xy 73.832212 -4.659432) (xy 73.928459 -4.684885) (xy 74.022296 -4.718138)
			(xy 74.113094 -4.758968) (xy 74.200242 -4.807099) (xy 74.283153 -4.862209) (xy 74.36127 -4.923926)
			(xy 74.434067 -4.991837) (xy 74.501056 -5.065483) (xy 74.561786 -5.14437) (xy 74.615848 -5.227968)
			(xy 74.662878 -5.315715) (xy 74.702562 -5.407019) (xy 74.734631 -5.501268) (xy 74.758871 -5.597827)
			(xy 74.775118 -5.696048) (xy 74.783262 -5.79527) (xy 74.783696 -5.845048) (xy 74.783176 -5.89522)
			(xy 74.774886 -5.995222) (xy 74.758366 -6.094198) (xy 74.733729 -6.191471) (xy 74.701144 -6.286378)
			(xy 74.660833 -6.37827) (xy 74.613071 -6.466519) (xy 74.558185 -6.550523) (xy 74.49655 -6.629707)
			(xy 74.428586 -6.703532) (xy 74.354758 -6.771491) (xy 74.275571 -6.833123) (xy 74.191564 -6.888004)
			(xy 74.103312 -6.935761) (xy 74.011419 -6.976067) (xy 73.91651 -7.008647) (xy 73.819235 -7.033279)
			(xy 73.720259 -7.049794) (xy 73.620256 -7.058079) (xy 73.570084 -7.05866) (xy 73.520312 -7.058154)
			(xy 73.421103 -7.049991) (xy 73.322895 -7.033729) (xy 73.22635 -7.009478) (xy 73.132116 -6.9774)
			(xy 73.040826 -6.937711) (xy 72.953093 -6.890678) (xy 72.869508 -6.836617) (xy 72.790631 -6.775892)
			(xy 72.716994 -6.70891) (xy 72.64909 -6.636121) (xy 72.587377 -6.558015) (xy 72.532269 -6.475116)
			(xy 72.484136 -6.387982) (xy 72.443302 -6.297198) (xy 72.410041 -6.203375) (xy 72.384577 -6.107142)
			(xy 72.367081 -6.009148) (xy 72.35767 -5.910049) (xy 72.356472 -5.860288) (xy 72.356472 -5.850128)
			(xy 72.348852 -5.832094) (xy 72.305418 -5.78866) (xy 72.29475 -5.78866) (xy 72.251316 -5.832094)
			(xy 72.243696 -5.850128) (xy 72.243696 -5.860288) (xy 72.242569 -5.910055) (xy 72.233169 -6.009164)
			(xy 72.21568 -6.10717) (xy 72.190222 -6.203414) (xy 72.156965 -6.297248) (xy 72.116133 -6.388043)
			(xy 72.068 -6.475188) (xy 72.01289 -6.558097) (xy 71.951173 -6.636213) (xy 71.883264 -6.70901) (xy 71.80962 -6.775999)
			(xy 71.730736 -6.83673) (xy 71.647142 -6.890795) (xy 71.5594 -6.93783) (xy 71.468099 -6.977518) (xy 71.373854 -7.009595)
			(xy 71.277298 -7.033842) (xy 71.17908 -7.050098) (xy 71.079861 -7.058254) (xy 70.980307 -7.058254)
			(xy 70.881088 -7.050098) (xy 70.78287 -7.033842) (xy 70.686314 -7.009595) (xy 70.592069 -6.977518)
			(xy 70.500768 -6.93783) (xy 70.413026 -6.890795) (xy 70.329432 -6.83673) (xy 70.250548 -6.775999)
			(xy 70.176904 -6.70901) (xy 70.108995 -6.636213) (xy 70.047278 -6.558097) (xy 69.992168 -6.475188)
			(xy 69.944035 -6.388043) (xy 69.903203 -6.297248) (xy 69.869946 -6.203414) (xy 69.844488 -6.10717)
			(xy 69.826999 -6.009164) (xy 69.817599 -5.910055) (xy 69.816472 -5.860288) (xy 69.816472 -5.850128)
			(xy 69.808852 -5.832094) (xy 69.773038 -5.79628) (xy 69.755004 -5.78866) (xy 69.744844 -5.78866)
			(xy 69.695077 -5.787533) (xy 69.595968 -5.778133) (xy 69.497962 -5.760645) (xy 69.401718 -5.735187)
			(xy 69.307883 -5.70193) (xy 69.217088 -5.661098) (xy 69.129943 -5.612966) (xy 69.047034 -5.557856)
			(xy 68.968918 -5.496139) (xy 68.896121 -5.42823) (xy 68.829132 -5.354586) (xy 68.768401 -5.275702)
			(xy 68.714336 -5.192108) (xy 68.667301 -5.104366) (xy 68.627612 -5.013065) (xy 68.595536 -4.91882)
			(xy 68.571288 -4.822264) (xy 68.555032 -4.724046) (xy 68.546876 -4.624827) (xy 68.546876 -4.525273)
			(xy 68.555032 -4.426054) (xy 68.571288 -4.327836) (xy 68.595536 -4.23128) (xy 68.627612 -4.137035)
			(xy 68.667301 -4.045734) (xy 68.714336 -3.957992) (xy 68.768401 -3.874398) (xy 68.829132 -3.795513)
			(xy 68.896121 -3.72187) (xy 68.968919 -3.653961) (xy 69.047034 -3.592244) (xy 69.129943 -3.537134)
			(xy 69.217088 -3.489002) (xy 69.307883 -3.44817) (xy 69.401718 -3.414913) (xy 69.497962 -3.389455)
			(xy 69.595968 -3.371967) (xy 69.695077 -3.362567) (xy 69.744844 -3.361436) (xy 69.755004 -3.361436)
			(xy 69.773038 -3.353816) (xy 69.816472 -3.310382) (xy 69.816472 -3.299714) (xy 69.773038 -3.25628)
			(xy 69.755004 -3.24866) (xy 69.744844 -3.24866) (xy 69.695077 -3.247537) (xy 69.595968 -3.238142)
			(xy 69.497961 -3.220658) (xy 69.401717 -3.195203) (xy 69.307881 -3.161949) (xy 69.217086 -3.121119)
			(xy 69.129941 -3.072986) (xy 69.047032 -3.017876) (xy 68.968918 -2.956158) (xy 68.896123 -2.888248)
			(xy 68.829136 -2.814602) (xy 68.768409 -2.735715) (xy 68.714349 -2.652118) (xy 68.667319 -2.564373)
			(xy 68.627637 -2.47307) (xy 68.595569 -2.378822) (xy 68.571331 -2.282264) (xy 68.555085 -2.184045)
			(xy 68.546941 -2.084825) (xy 68.546472 -2.035048) (xy 68.546921 -1.9882) (xy 68.554148 -1.894783)
			(xy 68.568555 -1.802201) (xy 68.590057 -1.711005) (xy 68.618525 -1.621739) (xy 68.65379 -1.534932)
			(xy 68.695643 -1.451103) (xy 68.743833 -1.37075) (xy 68.798074 -1.29435) (xy 68.858044 -1.22236)
			(xy 68.890388 -1.188466) (xy 68.901056 -1.177544) (xy 68.906644 -1.147572) (xy 68.86448 -1.047242)
			(xy 68.861028 -1.039615) (xy 68.849996 -1.027032) (xy 68.84289 -1.022604) (xy 68.830952 -1.016) (xy 60.070238 -1.016)
			(xy 60.060173 -1.016435) (xy 60.041585 -1.024165) (xy 60.03417 -1.030986) (xy 59.33948 -1.725676)
			(xy 59.332114 -1.732788) (xy 59.324494 -1.751584) (xy 59.324494 -3.033268) (xy 59.325051 -3.04438)
			(xy 59.334427 -3.064528) (xy 59.351436 -3.078829) (xy 59.372895 -3.084606) (xy 59.394785 -3.080777)
			(xy 59.40425 -3.074924) (xy 59.409398 -3.07115) (xy 59.417754 -3.061505) (xy 59.42076 -3.055874)
			(xy 59.449952 -2.998914) (xy 59.514728 -2.888509) (xy 59.586541 -2.782546) (xy 59.665086 -2.681472)
			(xy 59.750032 -2.585715) (xy 59.84102 -2.495678) (xy 59.937665 -2.411744) (xy 60.039558 -2.334265)
			(xy 60.146271 -2.263571) (xy 60.257351 -2.199958) (xy 60.372329 -2.143697) (xy 60.490719 -2.095024)
			(xy 60.612021 -2.054146) (xy 60.735723 -2.021235) (xy 60.861302 -1.996431) (xy 60.988227 -1.979838)
			(xy 61.115961 -1.971525) (xy 61.179964 -1.97104) (xy 61.241828 -1.971515) (xy 61.365311 -1.979282)
			(xy 61.488064 -1.994787) (xy 61.6096 -2.01797) (xy 61.729441 -2.048738) (xy 61.847113 -2.086971)
			(xy 61.962152 -2.132517) (xy 62.074105 -2.185197) (xy 62.182528 -2.244803) (xy 62.286995 -2.311099)
			(xy 62.387093 -2.383824) (xy 62.482427 -2.462691) (xy 62.57262 -2.547389) (xy 62.657317 -2.637582)
			(xy 62.736183 -2.732917) (xy 62.808908 -2.833015) (xy 62.875203 -2.937482) (xy 62.934808 -3.045906)
			(xy 62.987488 -3.157859) (xy 63.033033 -3.272898) (xy 63.071265 -3.390571) (xy 63.102033 -3.510412)
			(xy 63.125215 -3.631948) (xy 63.14072 -3.754701) (xy 63.148486 -3.878184) (xy 63.148972 -3.940048)
			(xy 63.148693 -3.989089) (xy 63.143865 -4.087051) (xy 63.13932 -4.135882) (xy 63.138304 -4.143756)
			(xy 63.140082 -4.151884) (xy 63.142664 -4.161594) (xy 63.154183 -4.178037) (xy 63.171124 -4.188812)
			(xy 63.1909 -4.192273) (xy 63.200788 -4.190492) (xy 63.210948 -4.188206) (xy 63.215774 -4.18592)
			(xy 63.263304 -4.164808) (xy 63.361258 -4.129838) (xy 63.461847 -4.103384) (xy 63.564332 -4.085642)
			(xy 63.667959 -4.076741) (xy 63.719964 -4.076192) (xy 63.769128 -4.076681) (xy 63.867134 -4.084635)
			(xy 63.964174 -4.100493) (xy 64.059613 -4.124152) (xy 64.152825 -4.155457) (xy 64.243198 -4.194202)
			(xy 64.330139 -4.240132) (xy 64.413078 -4.292948) (xy 64.491471 -4.352301) (xy 64.564805 -4.417804)
			(xy 64.632597 -4.489026) (xy 64.694403 -4.565501) (xy 64.749819 -4.646726) (xy 64.79848 -4.732169)
			(xy 64.840067 -4.821269) (xy 64.874308 -4.913443) (xy 64.900978 -5.008085) (xy 64.919901 -5.104574)
			(xy 64.930955 -5.202279) (xy 64.933734 -5.290058) (xy 65.045593 -5.290058) (xy 65.049633 -5.191075)
			(xy 65.061728 -5.092752) (xy 65.081798 -4.995741) (xy 65.109708 -4.900689) (xy 65.145272 -4.808228)
			(xy 65.188255 -4.718973) (xy 65.23837 -4.633519) (xy 65.295283 -4.552434) (xy 65.358616 -4.476258)
			(xy 65.427947 -4.405498) (xy 65.502816 -4.340624) (xy 65.582723 -4.282069) (xy 65.667137 -4.230221)
			(xy 65.755496 -4.185427) (xy 65.847212 -4.147984) (xy 65.941675 -4.118141) (xy 66.038256 -4.096097)
			(xy 66.136313 -4.081998) (xy 66.235193 -4.075939) (xy 66.334237 -4.07796) (xy 66.432787 -4.088047)
			(xy 66.530187 -4.106133) (xy 66.625789 -4.132098) (xy 66.718956 -4.16577) (xy 66.809069 -4.206923)
			(xy 66.895527 -4.255284) (xy 66.977756 -4.310531) (xy 67.055208 -4.372297) (xy 67.127368 -4.440171)
			(xy 67.193756 -4.5137) (xy 67.253929 -4.592396) (xy 67.307487 -4.675735) (xy 67.354075 -4.763162)
			(xy 67.393381 -4.854095) (xy 67.425145 -4.94793) (xy 67.449154 -5.044041) (xy 67.46525 -5.14179)
			(xy 67.473325 -5.240526) (xy 67.47383 -5.290058) (xy 67.473325 -5.33959) (xy 67.46525 -5.438326)
			(xy 67.449154 -5.536075) (xy 67.425145 -5.632186) (xy 67.393381 -5.726021) (xy 67.354075 -5.816954)
			(xy 67.307487 -5.904381) (xy 67.253929 -5.98772) (xy 67.193756 -6.066416) (xy 67.127368 -6.139945)
			(xy 67.055208 -6.207819) (xy 66.977756 -6.269585) (xy 66.895527 -6.324832) (xy 66.809069 -6.373193)
			(xy 66.718956 -6.414346) (xy 66.625789 -6.448018) (xy 66.530187 -6.473983) (xy 66.432787 -6.492069)
			(xy 66.334237 -6.502156) (xy 66.235193 -6.504177) (xy 66.136313 -6.498118) (xy 66.038256 -6.484019)
			(xy 65.941675 -6.461975) (xy 65.847212 -6.432132) (xy 65.755496 -6.394689) (xy 65.667137 -6.349895)
			(xy 65.582723 -6.298047) (xy 65.502816 -6.239492) (xy 65.427947 -6.174618) (xy 65.358616 -6.103858)
			(xy 65.295283 -6.027682) (xy 65.23837 -5.946597) (xy 65.188255 -5.861143) (xy 65.145272 -5.771888)
			(xy 65.109708 -5.679427) (xy 65.081798 -5.584375) (xy 65.061728 -5.487364) (xy 65.049633 -5.389041)
			(xy 65.045593 -5.290058) (xy 64.933734 -5.290058) (xy 64.934066 -5.300558) (xy 64.929214 -5.398766)
			(xy 64.916431 -5.496259) (xy 64.8958 -5.592399) (xy 64.867457 -5.686553) (xy 64.831589 -5.778105)
			(xy 64.788429 -5.866455) (xy 64.738262 -5.951022) (xy 64.681416 -6.031252) (xy 64.618264 -6.106619)
			(xy 64.54922 -6.176629) (xy 64.474737 -6.240822) (xy 64.395305 -6.298777) (xy 64.311443 -6.350115)
			(xy 64.223701 -6.394498) (xy 64.132656 -6.431635) (xy 64.038904 -6.461283) (xy 63.943061 -6.483247)
			(xy 63.845755 -6.497383) (xy 63.747623 -6.503599) (xy 63.649311 -6.501854) (xy 63.551462 -6.492159)
			(xy 63.454719 -6.474577) (xy 63.359715 -6.449225) (xy 63.267075 -6.416268) (xy 63.177406 -6.375923)
			(xy 63.091295 -6.328454) (xy 63.009308 -6.274172) (xy 62.931982 -6.213434) (xy 62.859825 -6.146638)
			(xy 62.79331 -6.074221) (xy 62.732873 -5.99666) (xy 62.67891 -5.914463) (xy 62.631776 -5.828168)
			(xy 62.59178 -5.738342) (xy 62.559183 -5.645575) (xy 62.5342 -5.550474) (xy 62.525148 -5.502148)
			(xy 62.523624 -5.493512) (xy 62.514734 -5.478272) (xy 62.481206 -5.449824) (xy 62.44463 -5.44957)
			(xy 62.430406 -5.461254) (xy 62.382519 -5.49998) (xy 62.282651 -5.572069) (xy 62.178473 -5.637778)
			(xy 62.070393 -5.696848) (xy 61.958833 -5.749049) (xy 61.84423 -5.794178) (xy 61.72703 -5.832058)
			(xy 61.607693 -5.86254) (xy 61.486684 -5.885506) (xy 61.364477 -5.900866) (xy 61.241548 -5.90856)
			(xy 61.179964 -5.909056) (xy 61.115963 -5.908542) (xy 60.988231 -5.900224) (xy 60.861309 -5.883627)
			(xy 60.735733 -5.858819) (xy 60.612035 -5.825906) (xy 60.490735 -5.785027) (xy 60.372348 -5.736354)
			(xy 60.257372 -5.680093) (xy 60.146294 -5.616483) (xy 60.039583 -5.54579) (xy 59.93769 -5.468315)
			(xy 59.841044 -5.384385) (xy 59.750056 -5.294353) (xy 59.665108 -5.198601) (xy 59.586559 -5.097532)
			(xy 59.514743 -4.991575) (xy 59.449961 -4.881176) (xy 59.42076 -4.824222) (xy 59.417721 -4.818613)
			(xy 59.409375 -4.80897) (xy 59.40425 -4.805172) (xy 59.394807 -4.799302) (xy 59.372922 -4.795515)
			(xy 59.351481 -4.801307) (xy 59.33448 -4.815598) (xy 59.325089 -4.835724) (xy 59.324494 -4.846828)
			(xy 59.324494 -18.236946) (xy 59.324821 -18.24546) (xy 59.33041 -18.261546) (xy 59.335416 -18.268442)
			(xy 59.341004 -18.275554) (xy 59.355228 -18.284444) (xy 59.36361 -18.286476) (xy 59.430146 -18.302606)
			(xy 59.561393 -18.341619) (xy 59.690145 -18.388208) (xy 59.815966 -18.442217) (xy 59.93118 -18.499836)
			(xy 65.86474 -18.499836) (xy 65.86474 -13.499846) (xy 65.865235 -13.399005) (xy 65.873153 -13.197478)
			(xy 65.888977 -12.996418) (xy 65.912682 -12.796134) (xy 65.944232 -12.596935) (xy 65.983578 -12.399128)
			(xy 66.03066 -12.203019) (xy 66.085405 -12.008909) (xy 66.147728 -11.817098) (xy 66.217533 -11.627881)
			(xy 66.294714 -11.441552) (xy 66.37915 -11.258395) (xy 66.470712 -11.078695) (xy 66.569258 -10.902729)
			(xy 66.674636 -10.730766) (xy 66.786685 -10.563074) (xy 66.905231 -10.39991) (xy 67.030091 -10.241525)
			(xy 67.161073 -10.088165) (xy 67.297975 -9.940065) (xy 67.440585 -9.797455) (xy 67.588685 -9.660553)
			(xy 67.742045 -9.529571) (xy 67.90043 -9.404711) (xy 68.063594 -9.286165) (xy 68.231286 -9.174116)
			(xy 68.403249 -9.068738) (xy 68.579215 -8.970192) (xy 68.758915 -8.87863) (xy 68.942072 -8.794194)
			(xy 69.128401 -8.717013) (xy 69.317618 -8.647208) (xy 69.509429 -8.584885) (xy 69.703539 -8.53014)
			(xy 69.899648 -8.483058) (xy 70.097455 -8.443712) (xy 70.296654 -8.412162) (xy 70.496938 -8.388457)
			(xy 70.697998 -8.372633) (xy 70.899525 -8.364715) (xy 71.101207 -8.364715) (xy 71.302734 -8.372633)
			(xy 71.503794 -8.388457) (xy 71.704078 -8.412162) (xy 71.903277 -8.443712) (xy 72.101084 -8.483058)
			(xy 72.297193 -8.53014) (xy 72.491303 -8.584885) (xy 72.683114 -8.647208) (xy 72.872331 -8.717013)
			(xy 73.05866 -8.794194) (xy 73.241817 -8.87863) (xy 73.421517 -8.970192) (xy 73.597483 -9.068738)
			(xy 73.769446 -9.174116) (xy 73.937138 -9.286165) (xy 74.100302 -9.404711) (xy 74.258687 -9.529571)
			(xy 74.412047 -9.660553) (xy 74.560147 -9.797455) (xy 74.702757 -9.940065) (xy 74.720815 -9.9596)
			(xy 79.060327 -9.9596) (xy 79.064359 -9.874976) (xy 79.076415 -9.791119) (xy 79.096388 -9.708788)
			(xy 79.124096 -9.628727) (xy 79.159289 -9.551663) (xy 79.201648 -9.478293) (xy 79.250789 -9.409282)
			(xy 79.306267 -9.345254) (xy 79.367581 -9.28679) (xy 79.434174 -9.234418) (xy 79.505443 -9.188613)
			(xy 79.580744 -9.149791) (xy 79.659394 -9.118301) (xy 79.740681 -9.09443) (xy 79.823869 -9.078394)
			(xy 79.908204 -9.070338) (xy 79.950564 -9.069832) (xy 79.996967 -9.07044) (xy 80.089264 -9.080136)
			(xy 80.18005 -9.099395) (xy 80.268334 -9.128008) (xy 80.31099 -9.146286) (xy 80.320932 -9.150092)
			(xy 80.342196 -9.150092) (xy 80.352138 -9.146286) (xy 80.394802 -9.128033) (xy 80.483089 -9.099438)
			(xy 80.573871 -9.080178) (xy 80.666163 -9.070463) (xy 80.712564 -9.069832) (xy 80.758967 -9.07044)
			(xy 80.851264 -9.080136) (xy 80.94205 -9.099395) (xy 81.030334 -9.128008) (xy 81.07299 -9.146286)
			(xy 81.082932 -9.150092) (xy 81.104196 -9.150092) (xy 81.114138 -9.146286) (xy 81.156802 -9.128033)
			(xy 81.245089 -9.099438) (xy 81.335871 -9.080178) (xy 81.428163 -9.070463) (xy 81.474564 -9.069832)
			(xy 81.520967 -9.07044) (xy 81.613264 -9.080136) (xy 81.70405 -9.099395) (xy 81.792334 -9.128008)
			(xy 81.83499 -9.146286) (xy 81.844932 -9.150092) (xy 81.866196 -9.150092) (xy 81.876138 -9.146286)
			(xy 81.918802 -9.128033) (xy 82.007089 -9.099438) (xy 82.097871 -9.080178) (xy 82.190163 -9.070463)
			(xy 82.236564 -9.069832) (xy 82.278926 -9.070331) (xy 82.363267 -9.078381) (xy 82.446461 -9.094412)
			(xy 82.527754 -9.118279) (xy 82.60641 -9.149766) (xy 82.681717 -9.188586) (xy 82.752993 -9.23439)
			(xy 82.819592 -9.286761) (xy 82.880911 -9.345227) (xy 82.936395 -9.409256) (xy 82.985541 -9.478269)
			(xy 83.027904 -9.551642) (xy 83.0631 -9.62871) (xy 83.090812 -9.708774) (xy 83.110787 -9.79111) (xy 83.122845 -9.874972)
			(xy 83.126876 -9.9596) (xy 83.122845 -10.044228) (xy 83.110787 -10.12809) (xy 83.090812 -10.210426)
			(xy 83.0631 -10.29049) (xy 83.027904 -10.367558) (xy 82.985541 -10.440931) (xy 82.936395 -10.509944)
			(xy 82.880911 -10.573973) (xy 82.819592 -10.632439) (xy 82.752993 -10.68481) (xy 82.681717 -10.730614)
			(xy 82.60641 -10.769434) (xy 82.527754 -10.800921) (xy 82.446461 -10.824788) (xy 82.363267 -10.840819)
			(xy 82.278926 -10.848869) (xy 82.236564 -10.849356) (xy 82.190162 -10.848739) (xy 82.097864 -10.839046)
			(xy 82.007079 -10.819789) (xy 81.918794 -10.791179) (xy 81.876138 -10.772902) (xy 81.866196 -10.769096)
			(xy 81.844932 -10.769096) (xy 81.83499 -10.772902) (xy 81.792335 -10.791178) (xy 81.704045 -10.819767)
			(xy 81.61326 -10.83902) (xy 81.520965 -10.848729) (xy 81.474564 -10.849356) (xy 81.428162 -10.848739)
			(xy 81.335864 -10.839046) (xy 81.245079 -10.819789) (xy 81.156794 -10.791179) (xy 81.114138 -10.772902)
			(xy 81.104196 -10.769096) (xy 81.082932 -10.769096) (xy 81.07299 -10.772902) (xy 81.030335 -10.791178)
			(xy 80.942045 -10.819767) (xy 80.85126 -10.83902) (xy 80.758965 -10.848729) (xy 80.712564 -10.849356)
			(xy 80.666162 -10.848739) (xy 80.573864 -10.839046) (xy 80.483079 -10.819789) (xy 80.394794 -10.791179)
			(xy 80.352138 -10.772902) (xy 80.342196 -10.769096) (xy 80.320932 -10.769096) (xy 80.31099 -10.772902)
			(xy 80.268335 -10.791178) (xy 80.180045 -10.819767) (xy 80.08926 -10.83902) (xy 79.996965 -10.848729)
			(xy 79.950564 -10.849356) (xy 79.908204 -10.848862) (xy 79.823869 -10.840806) (xy 79.740681 -10.82477)
			(xy 79.659394 -10.800899) (xy 79.580744 -10.769409) (xy 79.505443 -10.730587) (xy 79.434174 -10.684782)
			(xy 79.367581 -10.63241) (xy 79.306267 -10.573946) (xy 79.250789 -10.509918) (xy 79.201648 -10.440907)
			(xy 79.159289 -10.367537) (xy 79.124096 -10.290473) (xy 79.096388 -10.210412) (xy 79.076415 -10.128081)
			(xy 79.064359 -10.044224) (xy 79.060327 -9.9596) (xy 74.720815 -9.9596) (xy 74.839659 -10.088165)
			(xy 74.970641 -10.241525) (xy 75.095501 -10.39991) (xy 75.214047 -10.563074) (xy 75.326096 -10.730766)
			(xy 75.431474 -10.902729) (xy 75.53002 -11.078695) (xy 75.621582 -11.258395) (xy 75.706018 -11.441552)
			(xy 75.783199 -11.627881) (xy 75.853004 -11.817098) (xy 75.915327 -12.008909) (xy 75.970072 -12.203019)
			(xy 76.017154 -12.399128) (xy 76.0565 -12.596935) (xy 76.08805 -12.796134) (xy 76.111755 -12.996418)
			(xy 76.127579 -13.197478) (xy 76.135497 -13.399005) (xy 76.135992 -13.499846) (xy 76.135992 -16.383)
			(xy 79.628492 -16.383) (xy 79.628492 -16.382746) (xy 79.628984 -16.338974) (xy 79.637598 -16.251856)
			(xy 79.654727 -16.166004) (xy 79.680206 -16.08225) (xy 79.713788 -16.001404) (xy 79.755149 -15.924247)
			(xy 79.803888 -15.851526) (xy 79.859534 -15.783944) (xy 79.92155 -15.722154) (xy 79.989335 -15.666755)
			(xy 80.025494 -15.642082) (xy 80.035908 -15.63497) (xy 80.0481 -15.612618) (xy 80.0481 -15.502382)
			(xy 80.035908 -15.48003) (xy 80.025494 -15.472918) (xy 79.989334 -15.448245) (xy 79.921543 -15.392853)
			(xy 79.859522 -15.331068) (xy 79.803872 -15.263488) (xy 79.755132 -15.190767) (xy 79.713774 -15.113608)
			(xy 79.680197 -15.032759) (xy 79.654728 -14.949002) (xy 79.637611 -14.863147) (xy 79.629013 -14.776026)
			(xy 79.628492 -14.732254) (xy 79.628492 -14.732) (xy 79.628996 -14.689652) (xy 79.637047 -14.605338)
			(xy 79.653076 -14.522172) (xy 79.676937 -14.440905) (xy 79.708416 -14.362275) (xy 79.747227 -14.286994)
			(xy 79.793017 -14.215742) (xy 79.845373 -14.149166) (xy 79.903821 -14.087868) (xy 79.967831 -14.032403)
			(xy 80.036823 -13.983274) (xy 80.110173 -13.940925) (xy 80.187216 -13.905741) (xy 80.267255 -13.878039)
			(xy 80.349564 -13.858071) (xy 80.433399 -13.846018) (xy 80.518 -13.841988) (xy 80.602601 -13.846018)
			(xy 80.686436 -13.858071) (xy 80.768745 -13.878039) (xy 80.848784 -13.905741) (xy 80.925827 -13.940925)
			(xy 80.999177 -13.983274) (xy 81.068169 -14.032403) (xy 81.132179 -14.087868) (xy 81.190627 -14.149166)
			(xy 81.242983 -14.215742) (xy 81.288773 -14.286994) (xy 81.327584 -14.362275) (xy 81.359063 -14.440905)
			(xy 81.382924 -14.522172) (xy 81.398953 -14.605338) (xy 81.407004 -14.689652) (xy 81.407508 -14.732)
			(xy 81.407508 -14.73327) (xy 81.406985 -14.775684) (xy 81.39886 -14.860123) (xy 81.382718 -14.943402)
			(xy 81.371186 -14.984222) (xy 81.36763 -14.99616) (xy 81.372202 -15.020544) (xy 81.440274 -15.105126)
			(xy 81.46288 -15.115032) (xy 81.475326 -15.11427) (xy 81.534 -15.112492) (xy 81.575796 -15.112999)
			(xy 81.659019 -15.120839) (xy 81.741139 -15.13645) (xy 81.821434 -15.159694) (xy 81.899195 -15.190366)
			(xy 81.973736 -15.228197) (xy 82.0444 -15.272851) (xy 82.110565 -15.323937) (xy 82.171647 -15.381003)
			(xy 82.199734 -15.411958) (xy 82.206925 -15.41932) (xy 82.225537 -15.428067) (xy 82.246085 -15.428874)
			(xy 82.255868 -15.425674) (xy 82.294054 -15.411496) (xy 82.372448 -15.389352) (xy 82.452538 -15.37447)
			(xy 82.533654 -15.366973) (xy 82.574384 -15.366492) (xy 82.5754 -15.366492) (xy 82.617748 -15.366996)
			(xy 82.702062 -15.375047) (xy 82.785228 -15.391076) (xy 82.866495 -15.414937) (xy 82.945125 -15.446416)
			(xy 83.020406 -15.485227) (xy 83.091658 -15.531017) (xy 83.158234 -15.583373) (xy 83.219532 -15.641821)
			(xy 83.274997 -15.705831) (xy 83.324126 -15.774823) (xy 83.366475 -15.848173) (xy 83.401659 -15.925216)
			(xy 83.429361 -16.005255) (xy 83.449329 -16.087564) (xy 83.454073 -16.120561) (xy 83.565742 -16.120561)
			(xy 83.565742 -16.035839) (xy 83.573795 -15.951502) (xy 83.589829 -15.868312) (xy 83.613697 -15.787022)
			(xy 83.645185 -15.70837) (xy 83.684007 -15.633067) (xy 83.72981 -15.561795) (xy 83.782181 -15.495199)
			(xy 83.840646 -15.433884) (xy 83.904674 -15.378403) (xy 83.973686 -15.32926) (xy 84.047056 -15.2869)
			(xy 84.124121 -15.251705) (xy 84.204183 -15.223996) (xy 84.286516 -15.204022) (xy 84.370375 -15.191965)
			(xy 84.455 -15.187934) (xy 84.539625 -15.191965) (xy 84.623484 -15.204022) (xy 84.705817 -15.223996)
			(xy 84.785879 -15.251705) (xy 84.862944 -15.2869) (xy 84.936314 -15.32926) (xy 85.005326 -15.378403)
			(xy 85.069354 -15.433884) (xy 85.127819 -15.495199) (xy 85.18019 -15.561795) (xy 85.225993 -15.633067)
			(xy 85.264815 -15.70837) (xy 85.296303 -15.787022) (xy 85.320171 -15.868312) (xy 85.336205 -15.951502)
			(xy 85.344258 -16.035839) (xy 85.344762 -16.0782) (xy 85.344258 -16.120561) (xy 85.336205 -16.204898)
			(xy 85.320171 -16.288088) (xy 85.296303 -16.369378) (xy 85.264815 -16.44803) (xy 85.225993 -16.523333)
			(xy 85.18019 -16.594605) (xy 85.127819 -16.661201) (xy 85.069354 -16.722516) (xy 85.005326 -16.777997)
			(xy 84.936314 -16.82714) (xy 84.862944 -16.8695) (xy 84.785879 -16.904695) (xy 84.705817 -16.932404)
			(xy 84.623484 -16.952378) (xy 84.539625 -16.964435) (xy 84.455 -16.968467) (xy 84.370375 -16.964435)
			(xy 84.286516 -16.952378) (xy 84.204183 -16.932404) (xy 84.124121 -16.904695) (xy 84.047056 -16.8695)
			(xy 83.973686 -16.82714) (xy 83.904674 -16.777997) (xy 83.840646 -16.722516) (xy 83.782181 -16.661201)
			(xy 83.72981 -16.594605) (xy 83.684007 -16.523333) (xy 83.645185 -16.44803) (xy 83.613697 -16.369378)
			(xy 83.589829 -16.288088) (xy 83.573795 -16.204898) (xy 83.565742 -16.120561) (xy 83.454073 -16.120561)
			(xy 83.461382 -16.171399) (xy 83.465413 -16.256) (xy 83.461382 -16.340601) (xy 83.449329 -16.424436)
			(xy 83.429361 -16.506745) (xy 83.401659 -16.586784) (xy 83.366475 -16.663827) (xy 83.324126 -16.737177)
			(xy 83.274997 -16.806169) (xy 83.219532 -16.870179) (xy 83.158234 -16.928627) (xy 83.091658 -16.980983)
			(xy 83.020406 -17.026773) (xy 82.945125 -17.065584) (xy 82.866495 -17.097063) (xy 82.785228 -17.120924)
			(xy 82.702062 -17.136953) (xy 82.617748 -17.145004) (xy 82.5754 -17.145508) (xy 82.551778 -17.145254)
			(xy 82.541009 -17.145479) (xy 82.521167 -17.153813) (xy 82.50646 -17.169526) (xy 82.502502 -17.179544)
			(xy 82.488271 -17.21954) (xy 82.453203 -17.29686) (xy 82.410929 -17.370486) (xy 82.361831 -17.43975)
			(xy 82.306357 -17.50402) (xy 82.245012 -17.562712) (xy 82.178353 -17.615292) (xy 82.106988 -17.661282)
			(xy 82.031566 -17.700262) (xy 81.952772 -17.731879) (xy 81.871325 -17.755844) (xy 81.787965 -17.77194)
			(xy 81.70345 -17.78002) (xy 81.661 -17.780508) (xy 81.618522 -17.779969) (xy 81.533953 -17.771871)
			(xy 81.450542 -17.755749) (xy 81.369046 -17.731751) (xy 81.290209 -17.700093) (xy 81.214749 -17.661066)
			(xy 81.143352 -17.615023) (xy 81.076669 -17.562385) (xy 81.015306 -17.50363) (xy 80.959824 -17.439294)
			(xy 80.910726 -17.369962) (xy 80.86846 -17.296267) (xy 80.850486 -17.257776) (xy 80.846331 -17.249478)
			(xy 80.833181 -17.236403) (xy 80.816233 -17.228878) (xy 80.797715 -17.227892) (xy 80.788764 -17.230344)
			(xy 80.744944 -17.243758) (xy 80.655239 -17.26252) (xy 80.564077 -17.271943) (xy 80.518254 -17.272508)
			(xy 80.518 -17.272508) (xy 80.476898 -17.272033) (xy 80.395043 -17.264448) (xy 80.314238 -17.249343)
			(xy 80.235171 -17.226847) (xy 80.158517 -17.197151) (xy 80.08493 -17.160509) (xy 80.015038 -17.117234)
			(xy 79.949437 -17.067694) (xy 79.888687 -17.012313) (xy 79.833306 -16.951563) (xy 79.783766 -16.885962)
			(xy 79.740491 -16.81607) (xy 79.703849 -16.742483) (xy 79.674153 -16.665829) (xy 79.651657 -16.586762)
			(xy 79.636552 -16.505957) (xy 79.628967 -16.424102) (xy 79.628492 -16.383) (xy 76.135992 -16.383)
			(xy 76.135992 -18.499836) (xy 76.135497 -18.600677) (xy 76.127579 -18.802204) (xy 76.118576 -18.9166)
			(xy 79.627784 -18.9166) (xy 79.631814 -18.83198) (xy 79.643871 -18.748125) (xy 79.663844 -18.665797)
			(xy 79.691552 -18.58574) (xy 79.726744 -18.508679) (xy 79.769102 -18.435313) (xy 79.818243 -18.366305)
			(xy 79.87372 -18.30228) (xy 79.935032 -18.243819) (xy 80.001624 -18.191451) (xy 80.072892 -18.14565)
			(xy 80.148191 -18.106831) (xy 80.226839 -18.075345) (xy 80.308124 -18.051477) (xy 80.391309 -18.035445)
			(xy 80.475642 -18.027392) (xy 80.518 -18.026888) (xy 80.559512 -18.02738) (xy 80.642172 -18.035148)
			(xy 80.723748 -18.050588) (xy 80.803529 -18.073566) (xy 80.880821 -18.103881) (xy 80.95495 -18.14127)
			(xy 81.02527 -18.185407) (xy 81.058512 -18.210276) (xy 81.067711 -18.216619) (xy 81.0895 -18.22145)
			(xy 81.111289 -18.216619) (xy 81.120488 -18.210276) (xy 81.153746 -18.185432) (xy 81.224072 -18.14131)
			(xy 81.298201 -18.103931) (xy 81.37549 -18.073618) (xy 81.455266 -18.050635) (xy 81.536836 -18.035183)
			(xy 81.61949 -18.027395) (xy 81.661 -18.026888) (xy 81.702547 -18.027384) (xy 81.785278 -18.035131)
			(xy 81.866928 -18.050558) (xy 81.946783 -18.073529) (xy 82.024148 -18.103846) (xy 82.098351 -18.141243)
			(xy 82.168743 -18.185396) (xy 82.20202 -18.210276) (xy 82.211199 -18.21654) (xy 82.232881 -18.221297)
			(xy 82.254563 -18.21654) (xy 82.263742 -18.210276) (xy 82.296989 -18.185466) (xy 82.367298 -18.141428)
			(xy 82.441403 -18.104129) (xy 82.518659 -18.073894) (xy 82.598395 -18.050984) (xy 82.679918 -18.0356)
			(xy 82.762519 -18.027874) (xy 82.804 -18.027396) (xy 82.845505 -18.027868) (xy 82.928151 -18.035625)
			(xy 83.009716 -18.051045) (xy 83.089491 -18.073992) (xy 83.166783 -18.104267) (xy 83.24092 -18.141608)
			(xy 83.311258 -18.18569) (xy 83.344512 -18.21053) (xy 83.353711 -18.216873) (xy 83.3755 -18.221704)
			(xy 83.397289 -18.216873) (xy 83.406488 -18.21053) (xy 83.439722 -18.18569) (xy 83.510017 -18.141604)
			(xy 83.584115 -18.104261) (xy 83.661371 -18.073986) (xy 83.741112 -18.051042) (xy 83.822644 -18.03563)
			(xy 83.905258 -18.027882) (xy 83.946746 -18.027396) (xy 83.947 -18.027396) (xy 83.989349 -18.027892)
			(xy 84.073663 -18.035943) (xy 84.156829 -18.051972) (xy 84.238096 -18.075834) (xy 84.316726 -18.107313)
			(xy 84.392008 -18.146123) (xy 84.46326 -18.191914) (xy 84.529837 -18.24427) (xy 84.591135 -18.302718)
			(xy 84.6466 -18.366728) (xy 84.69573 -18.435721) (xy 84.738078 -18.509071) (xy 84.773263 -18.586114)
			(xy 84.800965 -18.666153) (xy 84.820933 -18.748463) (xy 84.832986 -18.832299) (xy 84.837017 -18.9169)
			(xy 84.832986 -19.001501) (xy 84.820933 -19.085337) (xy 84.800965 -19.167647) (xy 84.773263 -19.247686)
			(xy 84.738078 -19.324729) (xy 84.69573 -19.398079) (xy 84.6466 -19.467072) (xy 84.591135 -19.531082)
			(xy 84.529837 -19.58953) (xy 84.46326 -19.641886) (xy 84.392008 -19.687677) (xy 84.316726 -19.726487)
			(xy 84.238096 -19.757966) (xy 84.156829 -19.781828) (xy 84.073663 -19.797857) (xy 83.989349 -19.805908)
			(xy 83.947 -19.806412) (xy 83.946746 -19.806412) (xy 83.90526 -19.805927) (xy 83.822651 -19.798153)
			(xy 83.741125 -19.782724) (xy 83.661389 -19.759774) (xy 83.584134 -19.729503) (xy 83.510033 -19.692173)
			(xy 83.439728 -19.648108) (xy 83.406488 -19.623278) (xy 83.397289 -19.616935) (xy 83.3755 -19.612104)
			(xy 83.353711 -19.616935) (xy 83.344512 -19.623278) (xy 83.308449 -19.650238) (xy 83.231848 -19.697573)
			(xy 83.191604 -19.717766) (xy 83.181507 -19.723256) (xy 83.167223 -19.741231) (xy 83.164172 -19.75231)
			(xy 83.154228 -19.794062) (xy 83.127492 -19.875624) (xy 83.093025 -19.954232) (xy 83.051147 -20.029155)
			(xy 83.002247 -20.099696) (xy 82.946781 -20.165199) (xy 82.885264 -20.225055) (xy 82.818267 -20.278709)
			(xy 82.746415 -20.325659) (xy 82.670374 -20.365472) (xy 82.590852 -20.397775) (xy 82.508589 -20.422269)
			(xy 82.424349 -20.438726) (xy 82.338916 -20.446993) (xy 82.296 -20.447508) (xy 82.254987 -20.44704)
			(xy 82.173311 -20.439473) (xy 82.092678 -20.424422) (xy 82.013773 -20.402015) (xy 81.937264 -20.372441)
			(xy 81.863801 -20.335953) (xy 81.794008 -20.292858) (xy 81.728476 -20.243524) (xy 81.667763 -20.188369)
			(xy 81.612383 -20.12786) (xy 81.562807 -20.062512) (xy 81.519454 -19.992879) (xy 81.482694 -19.919552)
			(xy 81.452837 -19.843153) (xy 81.441036 -19.803872) (xy 81.43843 -19.795746) (xy 81.428677 -19.781756)
			(xy 81.414834 -19.771796) (xy 81.406746 -19.769074) (xy 81.36817 -19.757065) (xy 81.293165 -19.727026)
			(xy 81.221192 -19.690309) (xy 81.152844 -19.647218) (xy 81.120488 -19.623024) (xy 81.111289 -19.616681)
			(xy 81.0895 -19.61185) (xy 81.067711 -19.616681) (xy 81.058512 -19.623024) (xy 81.025254 -19.647868)
			(xy 80.954928 -19.69199) (xy 80.880799 -19.729369) (xy 80.80351 -19.759682) (xy 80.723734 -19.782665)
			(xy 80.642164 -19.798117) (xy 80.55951 -19.805905) (xy 80.518 -19.806412) (xy 80.475642 -19.805808)
			(xy 80.391309 -19.797755) (xy 80.308124 -19.781723) (xy 80.226839 -19.757855) (xy 80.148191 -19.726369)
			(xy 80.072892 -19.68755) (xy 80.001624 -19.641749) (xy 79.935032 -19.589381) (xy 79.87372 -19.53092)
			(xy 79.818243 -19.466895) (xy 79.769102 -19.397887) (xy 79.726744 -19.324521) (xy 79.691552 -19.24746)
			(xy 79.663844 -19.167403) (xy 79.643871 -19.085075) (xy 79.631814 -19.00122) (xy 79.627784 -18.9166)
			(xy 76.118576 -18.9166) (xy 76.111755 -19.003264) (xy 76.08805 -19.203548) (xy 76.0565 -19.402747)
			(xy 76.017154 -19.600554) (xy 75.970072 -19.796663) (xy 75.915327 -19.990773) (xy 75.853004 -20.182584)
			(xy 75.783199 -20.371801) (xy 75.706018 -20.55813) (xy 75.621582 -20.741287) (xy 75.53002 -20.920987)
			(xy 75.431474 -21.096953) (xy 75.326096 -21.268916) (xy 75.214047 -21.436608) (xy 75.095501 -21.599772)
			(xy 74.970641 -21.758157) (xy 74.839659 -21.911517) (xy 74.702757 -22.059617) (xy 74.560147 -22.202227)
			(xy 74.412047 -22.339129) (xy 74.258687 -22.470111) (xy 74.100302 -22.594971) (xy 73.937138 -22.713517)
			(xy 73.769446 -22.825566) (xy 73.597483 -22.930944) (xy 73.421517 -23.02949) (xy 73.241817 -23.121052)
			(xy 73.05866 -23.205488) (xy 72.872331 -23.282669) (xy 72.683114 -23.352474) (xy 72.491303 -23.414797)
			(xy 72.297193 -23.469542) (xy 72.101084 -23.516624) (xy 71.903277 -23.55597) (xy 71.704078 -23.58752)
			(xy 71.503794 -23.611225) (xy 71.302734 -23.627049) (xy 71.101207 -23.634967) (xy 70.899525 -23.634967)
			(xy 70.697998 -23.627049) (xy 70.496938 -23.611225) (xy 70.296654 -23.58752) (xy 70.097455 -23.55597)
			(xy 69.899648 -23.516624) (xy 69.703539 -23.469542) (xy 69.509429 -23.414797) (xy 69.317618 -23.352474)
			(xy 69.128401 -23.282669) (xy 68.942072 -23.205488) (xy 68.758915 -23.121052) (xy 68.579215 -23.02949)
			(xy 68.403249 -22.930944) (xy 68.231286 -22.825566) (xy 68.063594 -22.713517) (xy 67.90043 -22.594971)
			(xy 67.742045 -22.470111) (xy 67.588685 -22.339129) (xy 67.440585 -22.202227) (xy 67.297975 -22.059617)
			(xy 67.161073 -21.911517) (xy 67.030091 -21.758157) (xy 66.905231 -21.599772) (xy 66.786685 -21.436608)
			(xy 66.674636 -21.268916) (xy 66.569258 -21.096953) (xy 66.470712 -20.920987) (xy 66.37915 -20.741287)
			(xy 66.294714 -20.55813) (xy 66.217533 -20.371801) (xy 66.147728 -20.182584) (xy 66.085405 -19.990773)
			(xy 66.03066 -19.796663) (xy 65.983578 -19.600554) (xy 65.944232 -19.402747) (xy 65.912682 -19.203548)
			(xy 65.888977 -19.003264) (xy 65.873153 -18.802204) (xy 65.865235 -18.600677) (xy 65.86474 -18.499836)
			(xy 59.93118 -18.499836) (xy 59.938429 -18.503461) (xy 60.057117 -18.571732) (xy 60.171627 -18.646799)
			(xy 60.281573 -18.728407) (xy 60.386579 -18.816279) (xy 60.48629 -18.910117) (xy 60.580367 -19.009602)
			(xy 60.668491 -19.114397) (xy 60.750363 -19.224145) (xy 60.825705 -19.338476) (xy 60.894261 -19.456999)
			(xy 60.955799 -19.579314) (xy 61.01011 -19.705005) (xy 61.057009 -19.833645) (xy 61.096337 -19.964798)
			(xy 61.127961 -20.098018) (xy 61.151773 -20.232854) (xy 61.167693 -20.368848) (xy 61.175667 -20.505539)
			(xy 61.176154 -20.574) (xy 61.175658 -20.642322) (xy 61.167718 -20.778734) (xy 61.151863 -20.914455)
			(xy 61.128148 -21.049025) (xy 61.096653 -21.181989) (xy 61.057484 -21.312899) (xy 61.010774 -21.44131)
			(xy 60.95668 -21.566791) (xy 60.895386 -21.688916) (xy 60.827098 -21.807272) (xy 60.752047 -21.92146)
			(xy 60.670488 -22.031094) (xy 60.582696 -22.135802) (xy 60.488966 -22.235232) (xy 60.389617 -22.329047)
			(xy 60.284984 -22.41693) (xy 60.230512 -22.458172) (xy 60.225432 -22.461728) (xy 60.21832 -22.470618)
			(xy 60.21197 -22.48281) (xy 60.207828 -22.491969) (xy 60.206348 -22.512) (xy 60.212653 -22.53107)
			(xy 60.22578 -22.546273) (xy 60.234576 -22.551136) (xy 60.24626 -22.556978) (xy 60.259468 -22.55647)
			(xy 60.297314 -22.555708) (xy 60.338428 -22.556184) (xy 60.420306 -22.563772) (xy 60.501134 -22.578882)
			(xy 60.580224 -22.601385) (xy 60.6569 -22.63109) (xy 60.730508 -22.667743) (xy 60.80042 -22.71103)
			(xy 60.86604 -22.760584) (xy 60.926808 -22.815981) (xy 60.982206 -22.876748) (xy 61.031761 -22.942367)
			(xy 61.07505 -23.012278) (xy 61.111703 -23.085886) (xy 61.141409 -23.162561) (xy 61.163914 -23.24165)
			(xy 61.179026 -23.322478) (xy 61.186616 -23.404356) (xy 61.187076 -23.44547) (xy 61.186584 -23.487343)
			(xy 61.178694 -23.570717) (xy 61.163009 -23.652982) (xy 61.139668 -23.73341) (xy 61.108876 -23.811291)
			(xy 61.090302 -23.848822) (xy 61.085222 -23.858728) (xy 61.08446 -23.877016) (xy 61.087508 -23.890224)
			(xy 61.091064 -23.896574) (xy 61.112458 -23.936246) (xy 61.148013 -24.019078) (xy 61.175006 -24.105081)
			(xy 61.193159 -24.193374) (xy 61.202286 -24.28305) (xy 61.202824 -24.32812) (xy 61.202333 -24.369661)
			(xy 61.194564 -24.452379) (xy 61.179113 -24.534013) (xy 61.156116 -24.613849) (xy 61.125773 -24.691192)
			(xy 61.088348 -24.765368) (xy 61.06668 -24.800814) (xy 61.063124 -24.806402) (xy 61.059314 -24.818086)
			(xy 61.058552 -24.831802) (xy 61.061346 -24.845772) (xy 61.064902 -24.852122) (xy 61.085266 -24.891062)
			(xy 61.119102 -24.972166) (xy 61.144782 -25.05621) (xy 61.162057 -25.142375) (xy 61.170758 -25.229823)
			(xy 61.171328 -25.273762) (xy 61.17084 -25.315007) (xy 61.163162 -25.39714) (xy 61.147914 -25.478209)
			(xy 61.125227 -25.557519) (xy 61.095297 -25.634388) (xy 61.05838 -25.708157) (xy 61.036962 -25.743408)
			(xy 61.033152 -25.749504) (xy 61.029342 -25.76322) (xy 61.029342 -25.777444) (xy 61.033152 -25.79116)
			(xy 61.036962 -25.797256) (xy 61.058355 -25.832498) (xy 61.095266 -25.906221) (xy 61.125194 -25.983045)
			(xy 61.147881 -26.062311) (xy 61.163132 -26.143336) (xy 61.170816 -26.225424) (xy 61.171328 -26.266648)
			(xy 61.170852 -26.307742) (xy 61.163266 -26.389579) (xy 61.148163 -26.470367) (xy 61.125672 -26.549418)
			(xy 61.095984 -26.626057) (xy 61.059354 -26.69963) (xy 61.016093 -26.769511) (xy 60.96657 -26.835103)
			(xy 60.911207 -26.895847) (xy 60.850477 -26.951225) (xy 60.784898 -27.000765) (xy 60.715028 -27.044044)
			(xy 60.641464 -27.080693) (xy 60.564832 -27.1104) (xy 60.485787 -27.132911) (xy 60.405003 -27.148034)
			(xy 60.323168 -27.155641) (xy 60.282074 -27.156156) (xy 60.281566 -27.156156) (xy 60.239252 -27.155653)
			(xy 60.155005 -27.147614) (xy 60.071903 -27.131611) (xy 59.990696 -27.107791) (xy 59.912117 -27.076367)
			(xy 59.836877 -27.037623) (xy 59.800998 -27.015186) (xy 59.794881 -27.011495) (xy 59.781212 -27.007362)
			(xy 59.774074 -27.007058) (xy 59.766681 -27.00727) (xy 59.752481 -27.011389) (xy 59.746134 -27.015186)
			(xy 59.71193 -27.036638) (xy 59.640336 -27.073969) (xy 59.565651 -27.104654) (xy 59.488491 -27.128441)
			(xy 59.409492 -27.145132) (xy 59.369452 -27.150314) (xy 59.369198 -27.150314) (xy 59.360059 -27.151814)
			(xy 59.343671 -27.16041) (xy 59.331421 -27.17428) (xy 59.324917 -27.191605) (xy 59.324494 -27.20086)
			(xy 59.324494 -32.85871) (xy 59.32424 -32.879538) (xy 59.323986 -32.889952) (xy 59.327796 -32.899604)
			(xy 59.329828 -32.904472) (xy 59.335595 -32.913303) (xy 59.339226 -32.91713) (xy 59.42711 -33.005014)
			(xy 59.427618 -33.005522) (xy 59.434996 -33.012113) (xy 59.453295 -33.019581) (xy 59.463178 -33.02)
			(xy 73.276206 -33.02) (xy 73.286084 -33.019542) (xy 73.304386 -33.012102) (xy 73.311766 -33.005522)
			(xy 73.31202 -33.005268) (xy 95.50527 -10.811764) (xy 95.511366 -10.804652) (xy 95.511366 -10.804398)
			(xy 95.516168 -10.796753) (xy 95.520573 -10.779256) (xy 95.518636 -10.761318) (xy 95.514922 -10.75309)
			(xy 95.46463 -10.652252) (xy 95.435928 -10.637012) (xy 95.419672 -10.639298) (xy 95.389598 -10.643204)
			(xy 95.329093 -10.647397) (xy 95.298768 -10.64768) (xy 95.252367 -10.647049) (xy 95.160075 -10.637334)
			(xy 95.069293 -10.618075) (xy 94.981006 -10.589481) (xy 94.938342 -10.571226) (xy 94.928436 -10.566908)
			(xy 94.9071 -10.566908) (xy 94.897194 -10.571226) (xy 94.854538 -10.589504) (xy 94.766254 -10.618117)
			(xy 94.675468 -10.637376) (xy 94.583171 -10.647072) (xy 94.536768 -10.64768) (xy 94.490367 -10.647049)
			(xy 94.398075 -10.637334) (xy 94.307293 -10.618075) (xy 94.219006 -10.589481) (xy 94.176342 -10.571226)
			(xy 94.166436 -10.566908) (xy 94.1451 -10.566908) (xy 94.135194 -10.571226) (xy 94.092538 -10.589504)
			(xy 94.004254 -10.618117) (xy 93.913468 -10.637376) (xy 93.821171 -10.647072) (xy 93.774768 -10.64768)
			(xy 93.732408 -10.647175) (xy 93.64807 -10.639119) (xy 93.564881 -10.623082) (xy 93.483593 -10.599211)
			(xy 93.404941 -10.567722) (xy 93.329639 -10.528898) (xy 93.258369 -10.483093) (xy 93.191774 -10.430721)
			(xy 93.13046 -10.372255) (xy 93.074981 -10.308227) (xy 93.025839 -10.239214) (xy 92.983479 -10.165843)
			(xy 92.948286 -10.088778) (xy 92.920577 -10.008717) (xy 92.900603 -9.926384) (xy 92.888547 -9.842525)
			(xy 92.884515 -9.7579) (xy 92.888547 -9.673275) (xy 92.900603 -9.589416) (xy 92.920577 -9.507083)
			(xy 92.948286 -9.427022) (xy 92.983479 -9.349957) (xy 93.025839 -9.276586) (xy 93.074981 -9.207573)
			(xy 93.13046 -9.143545) (xy 93.191774 -9.085079) (xy 93.258369 -9.032707) (xy 93.329639 -8.986902)
			(xy 93.404941 -8.948078) (xy 93.483593 -8.916589) (xy 93.564881 -8.892718) (xy 93.64807 -8.876681)
			(xy 93.732408 -8.868625) (xy 93.774768 -8.868156) (xy 93.821169 -8.868783) (xy 93.913464 -8.878492)
			(xy 94.004248 -8.897746) (xy 94.092538 -8.926336) (xy 94.135194 -8.94461) (xy 94.1451 -8.948928)
			(xy 94.166436 -8.948928) (xy 94.176342 -8.94461) (xy 94.218998 -8.926333) (xy 94.307283 -8.897723)
			(xy 94.398068 -8.878466) (xy 94.490366 -8.868773) (xy 94.536768 -8.868156) (xy 94.583169 -8.868783)
			(xy 94.675464 -8.878492) (xy 94.766248 -8.897746) (xy 94.854538 -8.926336) (xy 94.897194 -8.94461)
			(xy 94.9071 -8.948928) (xy 94.928436 -8.948928) (xy 94.938342 -8.94461) (xy 94.980998 -8.926333)
			(xy 95.069283 -8.897723) (xy 95.160068 -8.878466) (xy 95.252366 -8.868773) (xy 95.298768 -8.868156)
			(xy 95.345169 -8.868783) (xy 95.437464 -8.878492) (xy 95.528248 -8.897746) (xy 95.616538 -8.926336)
			(xy 95.659194 -8.94461) (xy 95.6691 -8.948928) (xy 95.690436 -8.948928) (xy 95.700342 -8.94461) (xy 95.742998 -8.926333)
			(xy 95.831283 -8.897723) (xy 95.922068 -8.878466) (xy 96.014366 -8.868773) (xy 96.060768 -8.868156)
			(xy 96.102891 -8.868647) (xy 96.18676 -8.87661) (xy 96.2695 -8.892466) (xy 96.350371 -8.916074) (xy 96.428647 -8.947222)
			(xy 96.503627 -8.985631) (xy 96.574641 -9.030958) (xy 96.64105 -9.082796) (xy 96.702261 -9.14068)
			(xy 96.757725 -9.204092) (xy 96.806945 -9.272464) (xy 96.82861 -9.308592) (xy 96.834706 -9.319006)
			(xy 96.85401 -9.331706) (xy 96.945704 -9.34339) (xy 96.957359 -9.344326) (xy 96.979453 -9.336762)
			(xy 96.988122 -9.328912) (xy 97.930462 -8.386826) (xy 97.954341 -8.363667) (xy 98.007102 -8.323157)
			(xy 98.064703 -8.289883) (xy 98.126155 -8.264417) (xy 98.190407 -8.247194) (xy 98.256358 -8.238509)
			(xy 98.289618 -8.237982) (xy 127.15494 -8.237982) (xy 127.161544 -8.236204) (xy 127.19401 -8.227995)
			(xy 127.260395 -8.219192) (xy 127.327361 -8.219192) (xy 127.393746 -8.227995) (xy 127.426212 -8.236204)
			(xy 127.432816 -8.237982) (xy 161.351468 -8.237982) (xy 161.358072 -8.236204) (xy 161.390538 -8.227995)
			(xy 161.456923 -8.219192) (xy 161.523889 -8.219192) (xy 161.590274 -8.227995) (xy 161.62274 -8.236204)
			(xy 161.629344 -8.237982) (xy 218.346274 -8.237982) (xy 218.351354 -8.237728) (xy 218.363305 -8.23584)
			(xy 218.383577 -8.222699) (xy 218.390216 -8.212582) (xy 218.392502 -8.208518) (xy 218.43746 -8.110982)
			(xy 218.433396 -8.081772) (xy 218.423744 -8.070342) (xy 218.395034 -8.03583) (xy 218.343936 -7.962011)
			(xy 218.300532 -7.883421) (xy 218.265266 -7.800859) (xy 218.238495 -7.715165) (xy 218.220491 -7.62721)
			(xy 218.211438 -7.537889) (xy 218.210892 -7.493) (xy 218.211367 -7.451898) (xy 218.218952 -7.370043)
			(xy 218.234057 -7.289238) (xy 218.256553 -7.210171) (xy 218.286249 -7.133517) (xy 218.322891 -7.05993)
			(xy 218.366166 -6.990038) (xy 218.415706 -6.924437) (xy 218.471087 -6.863687) (xy 218.531837 -6.808306)
			(xy 218.597438 -6.758766) (xy 218.66733 -6.715491) (xy 218.740917 -6.678849) (xy 218.817571 -6.649153)
			(xy 218.896638 -6.626657) (xy 218.977443 -6.611552) (xy 219.059298 -6.603967) (xy 219.1004 -6.603492)
			(xy 219.100908 -6.603492) (xy 219.141399 -6.603949) (xy 219.222044 -6.611334) (xy 219.301683 -6.626024)
			(xy 219.379655 -6.647896) (xy 219.417646 -6.661912) (xy 219.428314 -6.665976) (xy 219.450412 -6.664452)
			(xy 219.481146 -6.647434) (xy 219.490036 -6.638798) (xy 219.493338 -6.633464) (xy 219.515549 -6.599523)
			(xy 219.565254 -6.535414) (xy 219.620586 -6.476094) (xy 219.681086 -6.422055) (xy 219.746253 -6.373745)
			(xy 219.815545 -6.331565) (xy 219.888387 -6.295865) (xy 219.964176 -6.266941) (xy 220.042282 -6.245033)
			(xy 220.122057 -6.230323) (xy 220.20284 -6.222933) (xy 220.2434 -6.222492) (xy 220.286328 -6.223007)
			(xy 220.371784 -6.231276) (xy 220.456046 -6.247736) (xy 220.538331 -6.272235) (xy 220.617875 -6.304545)
			(xy 220.693937 -6.344365) (xy 220.765811 -6.391325) (xy 220.832828 -6.444989) (xy 220.894365 -6.504858)
			(xy 220.94985 -6.570375) (xy 220.998767 -6.640932) (xy 221.020132 -6.678168) (xy 221.025212 -6.687058)
			(xy 221.041468 -6.699758) (xy 221.094808 -6.713728) (xy 221.107762 -6.715506) (xy 221.154498 -6.715506)
			(xy 221.167198 -6.71195) (xy 221.173294 -6.708394) (xy 221.207441 -6.688873) (xy 221.278545 -6.655229)
			(xy 221.352343 -6.627996) (xy 221.428257 -6.607388) (xy 221.505695 -6.593564) (xy 221.584051 -6.586633)
			(xy 221.623382 -6.58622) (xy 221.66449 -6.586694) (xy 221.746354 -6.594277) (xy 221.82717 -6.609379)
			(xy 221.906249 -6.631873) (xy 221.982915 -6.661566) (xy 222.056515 -6.698205) (xy 222.12642 -6.741477)
			(xy 222.192036 -6.791013) (xy 222.252803 -6.846392) (xy 222.308201 -6.90714) (xy 222.357759 -6.97274)
			(xy 222.401054 -7.042632) (xy 222.437717 -7.11622) (xy 222.467435 -7.192876) (xy 222.489954 -7.271947)
			(xy 222.505083 -7.352758) (xy 222.512693 -7.434621) (xy 222.513144 -7.475728) (xy 222.512696 -7.515721)
			(xy 222.505494 -7.595384) (xy 222.491169 -7.674078) (xy 222.469837 -7.751168) (xy 222.44167 -7.826031)
			(xy 222.406894 -7.898063) (xy 222.365792 -7.966682) (xy 222.318696 -8.031334) (xy 222.292672 -8.061706)
			(xy 222.286576 -8.068564) (xy 222.278956 -8.08863) (xy 222.275871 -8.098088) (xy 222.276392 -8.117956)
			(xy 222.279972 -8.127238) (xy 222.31604 -8.207756) (xy 222.319245 -8.214398) (xy 222.328787 -8.225636)
			(xy 222.334836 -8.229854) (xy 222.347536 -8.237982) (xy 255.191006 -8.237982) (xy 255.199111 -8.23768)
			(xy 255.214513 -8.232621) (xy 255.221232 -8.228076) (xy 255.247597 -8.209158) (xy 255.304212 -8.177448)
			(xy 255.364403 -8.153203) (xy 255.427191 -8.136817) (xy 255.491555 -8.128557) (xy 255.556445 -8.128557)
			(xy 255.620809 -8.136817) (xy 255.683597 -8.153203) (xy 255.743788 -8.177448) (xy 255.800403 -8.209158)
			(xy 255.826768 -8.228076) (xy 255.833464 -8.232666) (xy 255.84888 -8.237727) (xy 255.856994 -8.237982)
			(xy 256.715006 -8.237982) (xy 256.723111 -8.23768) (xy 256.738513 -8.232621) (xy 256.745232 -8.228076)
			(xy 256.771593 -8.20915) (xy 256.828205 -8.177424) (xy 256.888395 -8.153166) (xy 256.951186 -8.136772)
			(xy 257.015552 -8.128507) (xy 257.048 -8.128) (xy 323.142356 -8.128) (xy 323.175617 -8.128519) (xy 323.24157 -8.137201)
			(xy 323.305825 -8.154422) (xy 323.36728 -8.179887) (xy 323.424882 -8.21316) (xy 323.477647 -8.253671)
			(xy 323.501512 -8.276844) (xy 324.773036 -9.548114) (xy 324.783704 -9.551924) (xy 324.813664 -9.563195)
			(xy 324.870719 -9.59222) (xy 324.923676 -9.62818) (xy 324.971698 -9.670507) (xy 325.014024 -9.71853)
			(xy 325.049984 -9.771488) (xy 325.051465 -9.7744) (xy 331.181015 -9.7744) (xy 331.185045 -9.689804)
			(xy 331.197098 -9.605974) (xy 331.217064 -9.523669) (xy 331.244764 -9.443634) (xy 331.279945 -9.366595)
			(xy 331.32229 -9.293249) (xy 331.371415 -9.22426) (xy 331.426876 -9.160253) (xy 331.488169 -9.101807)
			(xy 331.554741 -9.049453) (xy 331.625987 -9.003663) (xy 331.701263 -8.964853) (xy 331.779888 -8.933373)
			(xy 331.861149 -8.90951) (xy 331.94431 -8.893479) (xy 332.028618 -8.885425) (xy 332.070964 -8.88492)
			(xy 332.071472 -8.88492) (xy 332.117804 -8.885536) (xy 332.209961 -8.895204) (xy 332.300615 -8.914397)
			(xy 332.388784 -8.942906) (xy 332.43139 -8.96112) (xy 332.441332 -8.964926) (xy 332.462596 -8.964926)
			(xy 332.472538 -8.96112) (xy 332.515206 -8.942889) (xy 332.603496 -8.914341) (xy 332.694279 -8.895144)
			(xy 332.786568 -8.885507) (xy 332.832964 -8.88492) (xy 332.879359 -8.885513) (xy 332.971647 -8.895155)
			(xy 333.062431 -8.914348) (xy 333.150725 -8.942883) (xy 333.19339 -8.96112) (xy 333.203332 -8.964926)
			(xy 333.224596 -8.964926) (xy 333.234538 -8.96112) (xy 333.277206 -8.942889) (xy 333.365496 -8.914341)
			(xy 333.456279 -8.895144) (xy 333.548568 -8.885507) (xy 333.594964 -8.88492) (xy 333.641359 -8.885513)
			(xy 333.733647 -8.895155) (xy 333.824431 -8.914348) (xy 333.912725 -8.942883) (xy 333.95539 -8.96112)
			(xy 333.965332 -8.964926) (xy 333.986596 -8.964926) (xy 333.996538 -8.96112) (xy 334.039146 -8.942912)
			(xy 334.127312 -8.91439) (xy 334.217965 -8.895193) (xy 334.310124 -8.88553) (xy 334.356456 -8.88492)
			(xy 334.356964 -8.88492) (xy 334.399316 -8.88535) (xy 334.483636 -8.893399) (xy 334.566809 -8.909426)
			(xy 334.648082 -8.933287) (xy 334.726719 -8.964766) (xy 334.802007 -9.003577) (xy 334.873265 -9.049369)
			(xy 334.939848 -9.101728) (xy 335.001152 -9.160178) (xy 335.056622 -9.224192) (xy 335.105756 -9.293188)
			(xy 335.148108 -9.366543) (xy 335.183296 -9.443591) (xy 335.211001 -9.523636) (xy 335.230971 -9.605952)
			(xy 335.243026 -9.689793) (xy 335.247056 -9.7744) (xy 335.243026 -9.859007) (xy 335.24018 -9.8788)
			(xy 341.83444 -9.8788) (xy 341.838471 -9.794173) (xy 341.850529 -9.710312) (xy 341.870504 -9.627978)
			(xy 341.898215 -9.547915) (xy 341.933411 -9.470848) (xy 341.975773 -9.397477) (xy 342.024919 -9.328464)
			(xy 342.080402 -9.264436) (xy 342.14172 -9.205972) (xy 342.208318 -9.153602) (xy 342.279593 -9.107799)
			(xy 342.354899 -9.068979) (xy 342.433554 -9.037493) (xy 342.514846 -9.013627) (xy 342.598039 -8.997596)
			(xy 342.682378 -8.989547) (xy 342.72474 -8.98906) (xy 342.771142 -8.989674) (xy 342.86344 -8.999368)
			(xy 342.954225 -9.018625) (xy 343.04251 -9.047237) (xy 343.085166 -9.065514) (xy 343.095108 -9.06932)
			(xy 343.116372 -9.06932) (xy 343.126314 -9.065514) (xy 343.168969 -9.047237) (xy 343.257259 -9.018648)
			(xy 343.348044 -8.999395) (xy 343.440339 -8.989687) (xy 343.48674 -8.98906) (xy 343.533142 -8.989674)
			(xy 343.62544 -8.999368) (xy 343.716225 -9.018625) (xy 343.80451 -9.047237) (xy 343.847166 -9.065514)
			(xy 343.857108 -9.06932) (xy 343.878372 -9.06932) (xy 343.888314 -9.065514) (xy 343.930969 -9.047237)
			(xy 344.019259 -9.018648) (xy 344.110044 -8.999395) (xy 344.202339 -8.989687) (xy 344.24874 -8.98906)
			(xy 344.295142 -8.989674) (xy 344.38744 -8.999368) (xy 344.478225 -9.018625) (xy 344.56651 -9.047237)
			(xy 344.609166 -9.065514) (xy 344.619108 -9.06932) (xy 344.640372 -9.06932) (xy 344.650314 -9.065514)
			(xy 344.692969 -9.047237) (xy 344.781259 -9.018648) (xy 344.872044 -8.999395) (xy 344.964339 -8.989687)
			(xy 345.01074 -8.98906) (xy 345.0531 -8.989522) (xy 345.137437 -8.997579) (xy 345.220626 -9.013615)
			(xy 345.301915 -9.037487) (xy 345.380566 -9.068977) (xy 345.455867 -9.107801) (xy 345.527138 -9.153606)
			(xy 345.593731 -9.205979) (xy 345.655045 -9.264445) (xy 345.710525 -9.328474) (xy 345.759666 -9.397486)
			(xy 345.802026 -9.470857) (xy 345.837219 -9.547922) (xy 345.864928 -9.627984) (xy 345.884901 -9.710317)
			(xy 345.896957 -9.794175) (xy 345.900989 -9.8788) (xy 345.896957 -9.963425) (xy 345.884901 -10.047283)
			(xy 345.864928 -10.129616) (xy 345.837219 -10.209678) (xy 345.804101 -10.2822) (xy 358.852392 -10.2822)
			(xy 358.856424 -10.197568) (xy 358.868482 -10.113703) (xy 358.888458 -10.031364) (xy 358.91617 -9.951297)
			(xy 358.951368 -9.874226) (xy 358.993733 -9.800851) (xy 359.042881 -9.731835) (xy 359.098367 -9.667803)
			(xy 359.159689 -9.609336) (xy 359.22629 -9.556962) (xy 359.297569 -9.511157) (xy 359.372879 -9.472335)
			(xy 359.451539 -9.440848) (xy 359.532835 -9.41698) (xy 359.616032 -9.400949) (xy 359.700376 -9.392899)
			(xy 359.74274 -9.392412) (xy 359.789143 -9.393022) (xy 359.881441 -9.402716) (xy 359.972226 -9.421975)
			(xy 360.060511 -9.450588) (xy 360.103166 -9.468866) (xy 360.113108 -9.472672) (xy 360.134372 -9.472672)
			(xy 360.144314 -9.468866) (xy 360.186968 -9.450586) (xy 360.275259 -9.421999) (xy 360.366044 -9.402747)
			(xy 360.458338 -9.393039) (xy 360.50474 -9.392412) (xy 360.551143 -9.393022) (xy 360.643441 -9.402716)
			(xy 360.734226 -9.421975) (xy 360.822511 -9.450588) (xy 360.865166 -9.468866) (xy 360.875108 -9.472672)
			(xy 360.896372 -9.472672) (xy 360.906314 -9.468866) (xy 360.948968 -9.450586) (xy 361.037259 -9.421999)
			(xy 361.128044 -9.402747) (xy 361.220338 -9.393039) (xy 361.26674 -9.392412) (xy 361.313143 -9.393022)
			(xy 361.405441 -9.402716) (xy 361.496226 -9.421975) (xy 361.584511 -9.450588) (xy 361.627166 -9.468866)
			(xy 361.637108 -9.472672) (xy 361.658372 -9.472672) (xy 361.668314 -9.468866) (xy 361.710968 -9.450586)
			(xy 361.799259 -9.421999) (xy 361.890044 -9.402747) (xy 361.982338 -9.393039) (xy 362.02874 -9.392412)
			(xy 362.071098 -9.39297) (xy 362.15543 -9.401026) (xy 362.238615 -9.417062) (xy 362.319899 -9.440932)
			(xy 362.398546 -9.472421) (xy 362.473843 -9.511242) (xy 362.54511 -9.557046) (xy 362.6117 -9.609415)
			(xy 362.673011 -9.667878) (xy 362.728487 -9.731903) (xy 362.777626 -9.800912) (xy 362.819983 -9.874279)
			(xy 362.855174 -9.95134) (xy 362.882882 -10.031397) (xy 362.902854 -10.113726) (xy 362.91491 -10.19758)
			(xy 362.918941 -10.2822) (xy 362.91491 -10.36682) (xy 362.902854 -10.450674) (xy 362.882882 -10.533003)
			(xy 362.855174 -10.61306) (xy 362.819983 -10.690121) (xy 362.777626 -10.763488) (xy 362.728487 -10.832497)
			(xy 362.673011 -10.896522) (xy 362.6117 -10.954985) (xy 362.54511 -11.007354) (xy 362.473843 -11.053158)
			(xy 362.398546 -11.091979) (xy 362.319899 -11.123468) (xy 362.238615 -11.147338) (xy 362.15543 -11.163374)
			(xy 362.071098 -11.17143) (xy 362.02874 -11.171936) (xy 361.982337 -11.171329) (xy 361.890039 -11.161633)
			(xy 361.799254 -11.142374) (xy 361.710969 -11.11376) (xy 361.668314 -11.095482) (xy 361.658372 -11.091676)
			(xy 361.637108 -11.091676) (xy 361.627166 -11.095482) (xy 361.5845 -11.113732) (xy 361.496214 -11.142328)
			(xy 361.405433 -11.161589) (xy 361.313141 -11.171305) (xy 361.26674 -11.171936) (xy 361.220337 -11.171329)
			(xy 361.128039 -11.161633) (xy 361.037254 -11.142374) (xy 360.948969 -11.11376) (xy 360.906314 -11.095482)
			(xy 360.896372 -11.091676) (xy 360.875108 -11.091676) (xy 360.865166 -11.095482) (xy 360.8225 -11.113732)
			(xy 360.734214 -11.142328) (xy 360.643433 -11.161589) (xy 360.551141 -11.171305) (xy 360.50474 -11.171936)
			(xy 360.458337 -11.171329) (xy 360.366039 -11.161633) (xy 360.275254 -11.142374) (xy 360.186969 -11.11376)
			(xy 360.144314 -11.095482) (xy 360.134372 -11.091676) (xy 360.113108 -11.091676) (xy 360.103166 -11.095482)
			(xy 360.0605 -11.113732) (xy 359.972214 -11.142328) (xy 359.881433 -11.161589) (xy 359.789141 -11.171305)
			(xy 359.74274 -11.171936) (xy 359.700376 -11.171501) (xy 359.616032 -11.163451) (xy 359.532835 -11.14742)
			(xy 359.451539 -11.123552) (xy 359.372879 -11.092065) (xy 359.297569 -11.053243) (xy 359.22629 -11.007438)
			(xy 359.159689 -10.955064) (xy 359.098367 -10.896597) (xy 359.042881 -10.832565) (xy 358.993733 -10.763549)
			(xy 358.951368 -10.690174) (xy 358.91617 -10.613103) (xy 358.888458 -10.533036) (xy 358.868482 -10.450697)
			(xy 358.856424 -10.366832) (xy 358.852392 -10.2822) (xy 345.804101 -10.2822) (xy 345.802026 -10.286743)
			(xy 345.759666 -10.360114) (xy 345.710525 -10.429126) (xy 345.655045 -10.493155) (xy 345.593731 -10.551621)
			(xy 345.527138 -10.603994) (xy 345.455867 -10.649799) (xy 345.380566 -10.688623) (xy 345.301915 -10.720113)
			(xy 345.220626 -10.743985) (xy 345.137437 -10.760021) (xy 345.0531 -10.768078) (xy 345.01074 -10.768584)
			(xy 344.964337 -10.767982) (xy 344.872039 -10.758285) (xy 344.781254 -10.739024) (xy 344.692969 -10.710409)
			(xy 344.650314 -10.69213) (xy 344.640372 -10.688324) (xy 344.619108 -10.688324) (xy 344.609166 -10.69213)
			(xy 344.566501 -10.710383) (xy 344.478214 -10.738978) (xy 344.387433 -10.758237) (xy 344.295141 -10.767953)
			(xy 344.24874 -10.768584) (xy 344.202337 -10.767982) (xy 344.110039 -10.758285) (xy 344.019254 -10.739024)
			(xy 343.930969 -10.710409) (xy 343.888314 -10.69213) (xy 343.878372 -10.688324) (xy 343.857108 -10.688324)
			(xy 343.847166 -10.69213) (xy 343.804501 -10.710383) (xy 343.716214 -10.738978) (xy 343.625433 -10.758237)
			(xy 343.533141 -10.767953) (xy 343.48674 -10.768584) (xy 343.440337 -10.767982) (xy 343.348039 -10.758285)
			(xy 343.257254 -10.739024) (xy 343.168969 -10.710409) (xy 343.126314 -10.69213) (xy 343.116372 -10.688324)
			(xy 343.095108 -10.688324) (xy 343.085166 -10.69213) (xy 343.042501 -10.710383) (xy 342.954214 -10.738978)
			(xy 342.863433 -10.758237) (xy 342.771141 -10.767953) (xy 342.72474 -10.768584) (xy 342.682378 -10.768053)
			(xy 342.598039 -10.760004) (xy 342.514846 -10.743973) (xy 342.433554 -10.720107) (xy 342.354899 -10.688621)
			(xy 342.279593 -10.649801) (xy 342.208318 -10.603998) (xy 342.14172 -10.551628) (xy 342.080402 -10.493164)
			(xy 342.024919 -10.429136) (xy 341.975773 -10.360123) (xy 341.933411 -10.286752) (xy 341.898215 -10.209685)
			(xy 341.870504 -10.129622) (xy 341.850529 -10.047288) (xy 341.838471 -9.963427) (xy 341.83444 -9.8788)
			(xy 335.24018 -9.8788) (xy 335.230971 -9.942848) (xy 335.211001 -10.025164) (xy 335.183296 -10.105209)
			(xy 335.148108 -10.182257) (xy 335.105756 -10.255612) (xy 335.056622 -10.324608) (xy 335.001152 -10.388622)
			(xy 334.939848 -10.447072) (xy 334.873265 -10.499431) (xy 334.802007 -10.545223) (xy 334.726719 -10.584034)
			(xy 334.648082 -10.615513) (xy 334.566809 -10.639374) (xy 334.483636 -10.655401) (xy 334.399316 -10.66345)
			(xy 334.356964 -10.663936) (xy 334.356456 -10.663936) (xy 334.310125 -10.663305) (xy 334.217968 -10.653641)
			(xy 334.127314 -10.634452) (xy 334.039144 -10.605948) (xy 333.996538 -10.587736) (xy 333.986596 -10.58393)
			(xy 333.965332 -10.58393) (xy 333.95539 -10.587736) (xy 333.912733 -10.605994) (xy 333.824439 -10.634535)
			(xy 333.733652 -10.653724) (xy 333.641361 -10.663353) (xy 333.594964 -10.663936) (xy 333.548569 -10.663328)
			(xy 333.456282 -10.65369) (xy 333.365498 -10.634501) (xy 333.277204 -10.60597) (xy 333.234538 -10.587736)
			(xy 333.224596 -10.58393) (xy 333.203332 -10.58393) (xy 333.19339 -10.587736) (xy 333.150733 -10.605994)
			(xy 333.062439 -10.634535) (xy 332.971652 -10.653724) (xy 332.879361 -10.663353) (xy 332.832964 -10.663936)
			(xy 332.786569 -10.663328) (xy 332.694282 -10.65369) (xy 332.603498 -10.634501) (xy 332.515204 -10.60597)
			(xy 332.472538 -10.587736) (xy 332.462596 -10.58393) (xy 332.441332 -10.58393) (xy 332.43139 -10.587736)
			(xy 332.388793 -10.605972) (xy 332.300623 -10.634485) (xy 332.209966 -10.653674) (xy 332.117805 -10.66333)
			(xy 332.071472 -10.663936) (xy 332.070964 -10.663936) (xy 332.028618 -10.663375) (xy 331.94431 -10.655321)
			(xy 331.861149 -10.63929) (xy 331.779888 -10.615427) (xy 331.701263 -10.583947) (xy 331.625987 -10.545137)
			(xy 331.554741 -10.499347) (xy 331.488169 -10.446993) (xy 331.426876 -10.388547) (xy 331.371415 -10.32454)
			(xy 331.32229 -10.255551) (xy 331.279945 -10.182205) (xy 331.244764 -10.105166) (xy 331.217064 -10.025131)
			(xy 331.197098 -9.942826) (xy 331.185045 -9.858996) (xy 331.181015 -9.7744) (xy 325.051465 -9.7744)
			(xy 325.079008 -9.828543) (xy 325.090282 -9.858502) (xy 325.094092 -9.86917) (xy 330.297282 -15.072614)
			(xy 330.29779 -15.073122) (xy 330.305172 -15.079702) (xy 330.323471 -15.087144) (xy 330.33335 -15.0876)
			(xy 353.8982 -15.0876) (xy 353.93146 -15.088121) (xy 353.99741 -15.096809) (xy 354.061661 -15.114034)
			(xy 354.123112 -15.139503) (xy 354.180711 -15.172779) (xy 354.233471 -15.213292) (xy 354.257356 -15.236444)
			(xy 357.521002 -18.50009) (xy 363.864652 -18.50009) (xy 363.864652 -13.5001) (xy 363.865147 -13.399259)
			(xy 363.873065 -13.197732) (xy 363.888889 -12.996672) (xy 363.912594 -12.796388) (xy 363.944144 -12.597189)
			(xy 363.98349 -12.399382) (xy 364.030572 -12.203273) (xy 364.085317 -12.009163) (xy 364.14764 -11.817352)
			(xy 364.217445 -11.628135) (xy 364.294626 -11.441806) (xy 364.379062 -11.258649) (xy 364.470624 -11.078949)
			(xy 364.56917 -10.902983) (xy 364.674548 -10.73102) (xy 364.786597 -10.563328) (xy 364.905143 -10.400164)
			(xy 365.030003 -10.241779) (xy 365.160985 -10.088419) (xy 365.297887 -9.940319) (xy 365.440497 -9.797709)
			(xy 365.588597 -9.660807) (xy 365.741957 -9.529825) (xy 365.900342 -9.404965) (xy 366.063506 -9.286419)
			(xy 366.231198 -9.17437) (xy 366.403161 -9.068992) (xy 366.579127 -8.970446) (xy 366.758827 -8.878884)
			(xy 366.941984 -8.794448) (xy 367.128313 -8.717267) (xy 367.31753 -8.647462) (xy 367.509341 -8.585139)
			(xy 367.703451 -8.530394) (xy 367.89956 -8.483312) (xy 368.097367 -8.443966) (xy 368.296566 -8.412416)
			(xy 368.49685 -8.388711) (xy 368.69791 -8.372887) (xy 368.899437 -8.364969) (xy 369.101119 -8.364969)
			(xy 369.302646 -8.372887) (xy 369.503706 -8.388711) (xy 369.70399 -8.412416) (xy 369.903189 -8.443966)
			(xy 370.100996 -8.483312) (xy 370.297105 -8.530394) (xy 370.491215 -8.585139) (xy 370.683026 -8.647462)
			(xy 370.872243 -8.717267) (xy 371.058572 -8.794448) (xy 371.241729 -8.878884) (xy 371.421429 -8.970446)
			(xy 371.597395 -9.068992) (xy 371.769358 -9.17437) (xy 371.93705 -9.286419) (xy 372.100214 -9.404965)
			(xy 372.258599 -9.529825) (xy 372.411959 -9.660807) (xy 372.560059 -9.797709) (xy 372.702669 -9.940319)
			(xy 372.839571 -10.088419) (xy 372.970553 -10.241779) (xy 373.095413 -10.400164) (xy 373.213959 -10.563328)
			(xy 373.326008 -10.73102) (xy 373.431386 -10.902983) (xy 373.529932 -11.078949) (xy 373.621494 -11.258649)
			(xy 373.70593 -11.441806) (xy 373.783111 -11.628135) (xy 373.852916 -11.817352) (xy 373.915239 -12.009163)
			(xy 373.969984 -12.203273) (xy 374.017066 -12.399382) (xy 374.056412 -12.597189) (xy 374.087962 -12.796388)
			(xy 374.111667 -12.996672) (xy 374.127491 -13.197732) (xy 374.135409 -13.399259) (xy 374.135904 -13.5001)
			(xy 374.135904 -16.891) (xy 377.627872 -16.891) (xy 377.631902 -16.806397) (xy 377.643956 -16.72256)
			(xy 377.663925 -16.640248) (xy 377.691628 -16.560207) (xy 377.726813 -16.483162) (xy 377.769163 -16.409811)
			(xy 377.818294 -16.340817) (xy 377.87376 -16.276806) (xy 377.935061 -16.218357) (xy 378.001639 -16.166)
			(xy 378.072893 -16.120209) (xy 378.148177 -16.081398) (xy 378.226809 -16.04992) (xy 378.308078 -16.026058)
			(xy 378.391247 -16.01003) (xy 378.475562 -16.00198) (xy 378.517912 -16.001492) (xy 378.518166 -16.001492)
			(xy 378.559653 -16.001969) (xy 378.642261 -16.009745) (xy 378.723788 -16.025175) (xy 378.803524 -16.048126)
			(xy 378.880778 -16.078398) (xy 378.95488 -16.11573) (xy 379.025185 -16.159796) (xy 379.058424 -16.184626)
			(xy 379.067623 -16.190969) (xy 379.089412 -16.1958) (xy 379.111201 -16.190969) (xy 379.1204 -16.184626)
			(xy 379.156273 -16.157882) (xy 379.232425 -16.110894) (xy 379.31291 -16.071788) (xy 379.396914 -16.040961)
			(xy 379.483589 -16.018722) (xy 379.572059 -16.005298) (xy 379.616716 -16.002508) (xy 379.628004 -16.001328)
			(xy 379.647972 -15.9906) (xy 379.661437 -15.972365) (xy 379.664214 -15.96136) (xy 379.67239 -15.921222)
			(xy 379.695154 -15.842531) (xy 379.725057 -15.766265) (xy 379.761848 -15.693073) (xy 379.805212 -15.623575)
			(xy 379.854785 -15.558358) (xy 379.910144 -15.497976) (xy 379.970821 -15.442941) (xy 380.036302 -15.393719)
			(xy 380.106032 -15.350726) (xy 380.17942 -15.314328) (xy 380.255844 -15.284833) (xy 380.334656 -15.262491)
			(xy 380.41519 -15.24749) (xy 380.496761 -15.239959) (xy 380.53772 -15.239492) (xy 380.580622 -15.240048)
			(xy 380.666028 -15.24831) (xy 380.750242 -15.264755) (xy 380.832481 -15.289231) (xy 380.911983 -15.32151)
			(xy 380.988007 -15.361293) (xy 381.059849 -15.408209) (xy 381.126841 -15.461824) (xy 381.18836 -15.521638)
			(xy 381.243836 -15.587097) (xy 381.292752 -15.657593) (xy 381.334655 -15.73247) (xy 381.369155 -15.811033)
			(xy 381.383032 -15.851632) (xy 381.383032 -15.851886) (xy 381.386373 -15.860675) (xy 381.398326 -15.875169)
			(xy 381.414693 -15.884394) (xy 381.423926 -15.886176) (xy 381.528574 -15.901162) (xy 381.55499 -15.889732)
			(xy 381.563118 -15.877794) (xy 381.587956 -15.842673) (xy 381.643438 -15.776928) (xy 381.705006 -15.716844)
			(xy 381.772084 -15.662982) (xy 381.844047 -15.615844) (xy 381.920222 -15.575871) (xy 381.9999 -15.543435)
			(xy 382.082336 -15.518839) (xy 382.166761 -15.502313) (xy 382.252387 -15.494012) (xy 382.2954 -15.493492)
			(xy 382.337748 -15.493996) (xy 382.422062 -15.502047) (xy 382.505228 -15.518076) (xy 382.586495 -15.541937)
			(xy 382.665125 -15.573416) (xy 382.740406 -15.612227) (xy 382.811658 -15.658017) (xy 382.878234 -15.710373)
			(xy 382.939532 -15.768821) (xy 382.994997 -15.832831) (xy 383.044126 -15.901823) (xy 383.086475 -15.975173)
			(xy 383.121659 -16.052216) (xy 383.149361 -16.132255) (xy 383.169329 -16.214564) (xy 383.181382 -16.298399)
			(xy 383.185413 -16.383) (xy 383.181382 -16.467601) (xy 383.169329 -16.551436) (xy 383.149361 -16.633745)
			(xy 383.121659 -16.713784) (xy 383.086475 -16.790827) (xy 383.044126 -16.864177) (xy 382.994997 -16.933169)
			(xy 382.939532 -16.997179) (xy 382.878234 -17.055627) (xy 382.872214 -17.060361) (xy 397.255742 -17.060361)
			(xy 397.255742 -16.975639) (xy 397.263795 -16.891302) (xy 397.279829 -16.808112) (xy 397.303697 -16.726822)
			(xy 397.335185 -16.64817) (xy 397.374007 -16.572867) (xy 397.41981 -16.501595) (xy 397.472181 -16.434999)
			(xy 397.530646 -16.373684) (xy 397.594674 -16.318203) (xy 397.663686 -16.26906) (xy 397.737056 -16.2267)
			(xy 397.814121 -16.191505) (xy 397.894183 -16.163796) (xy 397.976516 -16.143822) (xy 398.060375 -16.131765)
			(xy 398.145 -16.127734) (xy 398.229625 -16.131765) (xy 398.313484 -16.143822) (xy 398.395817 -16.163796)
			(xy 398.475879 -16.191505) (xy 398.552944 -16.2267) (xy 398.626314 -16.26906) (xy 398.695326 -16.318203)
			(xy 398.759354 -16.373684) (xy 398.817819 -16.434999) (xy 398.87019 -16.501595) (xy 398.915993 -16.572867)
			(xy 398.954815 -16.64817) (xy 398.986303 -16.726822) (xy 399.010171 -16.808112) (xy 399.026205 -16.891302)
			(xy 399.034258 -16.975639) (xy 399.034762 -17.018) (xy 399.034258 -17.060361) (xy 399.026205 -17.144698)
			(xy 399.010171 -17.227888) (xy 398.986303 -17.309178) (xy 398.954815 -17.38783) (xy 398.915993 -17.463133)
			(xy 398.87019 -17.534405) (xy 398.817819 -17.601001) (xy 398.768237 -17.653) (xy 406.043892 -17.653)
			(xy 406.043892 -17.652492) (xy 406.044411 -17.608728) (xy 406.052986 -17.521622) (xy 406.070082 -17.435781)
			(xy 406.095533 -17.352035) (xy 406.129093 -17.271197) (xy 406.149302 -17.232376) (xy 406.154629 -17.221023)
			(xy 406.154629 -17.195977) (xy 406.149302 -17.184624) (xy 406.129087 -17.14575) (xy 406.095517 -17.064809)
			(xy 406.070061 -16.980962) (xy 406.052966 -16.895019) (xy 406.044396 -16.807813) (xy 406.043892 -16.764)
			(xy 406.044388 -16.720185) (xy 406.052933 -16.632974) (xy 406.07002 -16.547027) (xy 406.095481 -16.463179)
			(xy 406.129071 -16.382243) (xy 406.149302 -16.343376) (xy 406.154629 -16.332023) (xy 406.154629 -16.306977)
			(xy 406.149302 -16.295624) (xy 406.129108 -16.256796) (xy 406.095568 -16.175953) (xy 406.070123 -16.092208)
			(xy 406.053018 -16.006371) (xy 406.044419 -15.91927) (xy 406.043892 -15.875508) (xy 406.043892 -15.875)
			(xy 406.044367 -15.833898) (xy 406.051952 -15.752043) (xy 406.067057 -15.671238) (xy 406.089553 -15.592171)
			(xy 406.119249 -15.515517) (xy 406.155891 -15.44193) (xy 406.199166 -15.372038) (xy 406.248706 -15.306437)
			(xy 406.304087 -15.245687) (xy 406.364837 -15.190306) (xy 406.430438 -15.140766) (xy 406.50033 -15.097491)
			(xy 406.573917 -15.060849) (xy 406.650571 -15.031153) (xy 406.729638 -15.008657) (xy 406.810443 -14.993552)
			(xy 406.892298 -14.985967) (xy 406.9334 -14.985492) (xy 406.975715 -14.985995) (xy 407.059963 -14.994026)
			(xy 407.143066 -15.010024) (xy 407.224275 -15.033845) (xy 407.302852 -15.065272) (xy 407.378089 -15.104023)
			(xy 407.413968 -15.126462) (xy 407.422357 -15.131345) (xy 407.4414 -15.135016) (xy 407.460443 -15.131345)
			(xy 407.468832 -15.126462) (xy 407.504706 -15.104016) (xy 407.579947 -15.065273) (xy 407.658526 -15.033849)
			(xy 407.739735 -15.01003) (xy 407.822838 -14.99403) (xy 407.907085 -14.985994) (xy 407.9494 -14.985492)
			(xy 407.949908 -14.985492) (xy 407.99624 -14.986098) (xy 408.088398 -14.995769) (xy 408.179052 -15.014965)
			(xy 408.267221 -15.043477) (xy 408.309826 -15.061692) (xy 408.319768 -15.065498) (xy 408.341032 -15.065498)
			(xy 408.350974 -15.061692) (xy 408.393577 -15.04347) (xy 408.481744 -15.014952) (xy 408.5724 -14.99576)
			(xy 408.66456 -14.9861) (xy 408.710892 -14.985492) (xy 408.7114 -14.985492) (xy 408.752502 -14.985967)
			(xy 408.834357 -14.993552) (xy 408.915162 -15.008657) (xy 408.994229 -15.031153) (xy 409.070883 -15.060849)
			(xy 409.14447 -15.097491) (xy 409.214362 -15.140766) (xy 409.279963 -15.190306) (xy 409.340713 -15.245687)
			(xy 409.396094 -15.306437) (xy 409.445634 -15.372038) (xy 409.488909 -15.44193) (xy 409.525551 -15.515517)
			(xy 409.555247 -15.592171) (xy 409.577743 -15.671238) (xy 409.592848 -15.752043) (xy 409.600433 -15.833898)
			(xy 409.600908 -15.875) (xy 409.600908 -15.875508) (xy 409.600389 -15.919272) (xy 409.591814 -16.006378)
			(xy 409.574718 -16.092219) (xy 409.549267 -16.175965) (xy 409.515707 -16.256803) (xy 409.495498 -16.295624)
			(xy 409.490171 -16.306977) (xy 409.490171 -16.332023) (xy 409.495498 -16.343376) (xy 409.515713 -16.38225)
			(xy 409.549283 -16.463191) (xy 409.574739 -16.547038) (xy 409.591834 -16.632981) (xy 409.600404 -16.720187)
			(xy 409.600908 -16.764) (xy 409.600412 -16.807815) (xy 409.591867 -16.895026) (xy 409.57478 -16.980973)
			(xy 409.549319 -17.064821) (xy 409.515729 -17.145757) (xy 409.495498 -17.184624) (xy 409.490171 -17.195977)
			(xy 409.490171 -17.221023) (xy 409.495498 -17.232376) (xy 409.515692 -17.271204) (xy 409.549232 -17.352047)
			(xy 409.574677 -17.435792) (xy 409.591782 -17.521629) (xy 409.600381 -17.60873) (xy 409.600908 -17.652492)
			(xy 409.600908 -17.653) (xy 409.600433 -17.694102) (xy 409.592848 -17.775957) (xy 409.577743 -17.856762)
			(xy 409.555247 -17.935829) (xy 409.525551 -18.012483) (xy 409.488909 -18.08607) (xy 409.445634 -18.155962)
			(xy 409.396094 -18.221563) (xy 409.340713 -18.282313) (xy 409.279963 -18.337694) (xy 409.214362 -18.387234)
			(xy 409.14447 -18.430509) (xy 409.070883 -18.467151) (xy 408.994229 -18.496847) (xy 408.915162 -18.519343)
			(xy 408.834357 -18.534448) (xy 408.752502 -18.542033) (xy 408.7114 -18.542508) (xy 408.710892 -18.542508)
			(xy 408.66456 -18.541902) (xy 408.572402 -18.532231) (xy 408.481748 -18.513035) (xy 408.393579 -18.484523)
			(xy 408.350974 -18.466308) (xy 408.341032 -18.462502) (xy 408.319768 -18.462502) (xy 408.309826 -18.466308)
			(xy 408.267223 -18.48453) (xy 408.179056 -18.513048) (xy 408.0884 -18.53224) (xy 407.99624 -18.5419)
			(xy 407.949908 -18.542508) (xy 407.9494 -18.542508) (xy 407.907085 -18.542005) (xy 407.822837 -18.533974)
			(xy 407.739734 -18.517976) (xy 407.658525 -18.494155) (xy 407.579948 -18.462728) (xy 407.504711 -18.423977)
			(xy 407.468832 -18.401538) (xy 407.460443 -18.396655) (xy 407.4414 -18.392984) (xy 407.422357 -18.396655)
			(xy 407.413968 -18.401538) (xy 407.378094 -18.423984) (xy 407.302853 -18.462727) (xy 407.224274 -18.494151)
			(xy 407.143065 -18.51797) (xy 407.059962 -18.53397) (xy 406.975715 -18.542006) (xy 406.9334 -18.542508)
			(xy 406.892298 -18.542033) (xy 406.810443 -18.534448) (xy 406.729638 -18.519343) (xy 406.650571 -18.496847)
			(xy 406.573917 -18.467151) (xy 406.50033 -18.430509) (xy 406.430438 -18.387234) (xy 406.364837 -18.337694)
			(xy 406.304087 -18.282313) (xy 406.248706 -18.221563) (xy 406.199166 -18.155962) (xy 406.155891 -18.08607)
			(xy 406.119249 -18.012483) (xy 406.089553 -17.935829) (xy 406.067057 -17.856762) (xy 406.051952 -17.775957)
			(xy 406.044367 -17.694102) (xy 406.043892 -17.653) (xy 398.768237 -17.653) (xy 398.759354 -17.662316)
			(xy 398.695326 -17.717797) (xy 398.626314 -17.76694) (xy 398.552944 -17.8093) (xy 398.475879 -17.844495)
			(xy 398.395817 -17.872204) (xy 398.313484 -17.892178) (xy 398.229625 -17.904235) (xy 398.145 -17.908267)
			(xy 398.060375 -17.904235) (xy 397.976516 -17.892178) (xy 397.894183 -17.872204) (xy 397.814121 -17.844495)
			(xy 397.737056 -17.8093) (xy 397.663686 -17.76694) (xy 397.594674 -17.717797) (xy 397.530646 -17.662316)
			(xy 397.472181 -17.601001) (xy 397.41981 -17.534405) (xy 397.374007 -17.463133) (xy 397.335185 -17.38783)
			(xy 397.303697 -17.309178) (xy 397.279829 -17.227888) (xy 397.263795 -17.144698) (xy 397.255742 -17.060361)
			(xy 382.872214 -17.060361) (xy 382.811658 -17.107983) (xy 382.740406 -17.153773) (xy 382.665125 -17.192584)
			(xy 382.586495 -17.224063) (xy 382.505228 -17.247924) (xy 382.422062 -17.263953) (xy 382.337748 -17.272004)
			(xy 382.2954 -17.272508) (xy 382.252496 -17.272024) (xy 382.167088 -17.263755) (xy 382.082873 -17.247302)
			(xy 382.000632 -17.222819) (xy 381.92113 -17.190533) (xy 381.845105 -17.150744) (xy 381.773264 -17.103821)
			(xy 381.706273 -17.050201) (xy 381.644754 -16.990381) (xy 381.58928 -16.924917) (xy 381.540365 -16.854417)
			(xy 381.498463 -16.779536) (xy 381.463964 -16.700969) (xy 381.450088 -16.660368) (xy 381.450088 -16.660114)
			(xy 381.446734 -16.651332) (xy 381.434786 -16.636837) (xy 381.418425 -16.627609) (xy 381.409194 -16.625824)
			(xy 381.304546 -16.610838) (xy 381.27813 -16.622268) (xy 381.270002 -16.634206) (xy 381.24643 -16.667515)
			(xy 381.194121 -16.73015) (xy 381.136296 -16.787733) (xy 381.073442 -16.83978) (xy 381.006087 -16.885854)
			(xy 380.934796 -16.925567) (xy 380.860169 -16.958586) (xy 380.782832 -16.984634) (xy 380.703435 -17.003492)
			(xy 380.622645 -17.015001) (xy 380.581916 -17.017492) (xy 380.570631 -17.018695) (xy 380.550663 -17.029411)
			(xy 380.537196 -17.047638) (xy 380.534418 -17.05864) (xy 380.526307 -17.098792) (xy 380.50354 -17.177487)
			(xy 380.473634 -17.253755) (xy 380.43684 -17.326949) (xy 380.393471 -17.39645) (xy 380.343894 -17.461667)
			(xy 380.28853 -17.52205) (xy 380.227848 -17.577085) (xy 380.162362 -17.626306) (xy 380.092626 -17.669297)
			(xy 380.019233 -17.705692) (xy 379.942804 -17.735184) (xy 379.863986 -17.757523) (xy 379.783449 -17.772518)
			(xy 379.701873 -17.780044) (xy 379.660912 -17.780508) (xy 379.660658 -17.780508) (xy 379.619172 -17.780017)
			(xy 379.536564 -17.772244) (xy 379.455037 -17.756816) (xy 379.375301 -17.733868) (xy 379.298047 -17.703597)
			(xy 379.223945 -17.666268) (xy 379.15364 -17.622203) (xy 379.1204 -17.597374) (xy 379.111201 -17.591031)
			(xy 379.089412 -17.5862) (xy 379.067623 -17.591031) (xy 379.058424 -17.597374) (xy 379.025187 -17.622209)
			(xy 378.954892 -17.666295) (xy 378.880794 -17.703639) (xy 378.803539 -17.733915) (xy 378.723799 -17.756859)
			(xy 378.642267 -17.772273) (xy 378.559654 -17.780021) (xy 378.518166 -17.780508) (xy 378.517912 -17.780508)
			(xy 378.475562 -17.78002) (xy 378.391247 -17.77197) (xy 378.308078 -17.755942) (xy 378.226809 -17.73208)
			(xy 378.148177 -17.700602) (xy 378.072893 -17.661791) (xy 378.001639 -17.616) (xy 377.935061 -17.563643)
			(xy 377.87376 -17.505194) (xy 377.818294 -17.441183) (xy 377.769163 -17.372189) (xy 377.726813 -17.298838)
			(xy 377.691628 -17.221793) (xy 377.663925 -17.141752) (xy 377.643956 -17.05944) (xy 377.631902 -16.975603)
			(xy 377.627872 -16.891) (xy 374.135904 -16.891) (xy 374.135904 -18.50009) (xy 374.135409 -18.600931)
			(xy 374.127491 -18.802458) (xy 374.118004 -18.923) (xy 379.913872 -18.923) (xy 379.917902 -18.838397)
			(xy 379.929956 -18.75456) (xy 379.949925 -18.672248) (xy 379.977628 -18.592207) (xy 380.012813 -18.515162)
			(xy 380.055163 -18.441811) (xy 380.104294 -18.372817) (xy 380.15976 -18.308806) (xy 380.221061 -18.250357)
			(xy 380.287639 -18.198) (xy 380.358893 -18.152209) (xy 380.434177 -18.113398) (xy 380.512809 -18.08192)
			(xy 380.594078 -18.058058) (xy 380.677247 -18.04203) (xy 380.761562 -18.03398) (xy 380.803912 -18.033492)
			(xy 380.80442 -18.033492) (xy 380.845563 -18.033937) (xy 380.927497 -18.041543) (xy 381.008377 -18.056687)
			(xy 381.087512 -18.079241) (xy 381.164224 -18.109011) (xy 381.237857 -18.145742) (xy 381.307781 -18.18912)
			(xy 381.340868 -18.213578) (xy 381.350079 -18.219811) (xy 381.371782 -18.22453) (xy 381.393451 -18.219658)
			(xy 381.40259 -18.213324) (xy 381.435984 -18.188103) (xy 381.506701 -18.143345) (xy 381.581309 -18.105426)
			(xy 381.659148 -18.074681) (xy 381.73953 -18.051381) (xy 381.821745 -18.035733) (xy 381.905067 -18.027875)
			(xy 381.946912 -18.027396) (xy 381.98927 -18.027984) (xy 382.073603 -18.036038) (xy 382.156788 -18.052072)
			(xy 382.238073 -18.07594) (xy 382.316721 -18.107427) (xy 382.392019 -18.146247) (xy 382.463287 -18.192049)
			(xy 382.529878 -18.244418) (xy 382.59119 -18.302879) (xy 382.646667 -18.366904) (xy 382.695807 -18.435912)
			(xy 382.738165 -18.509279) (xy 382.773357 -18.58634) (xy 382.801065 -18.666397) (xy 382.821037 -18.748725)
			(xy 382.833094 -18.83258) (xy 382.837125 -18.9172) (xy 382.833094 -19.00182) (xy 382.821037 -19.085675)
			(xy 382.801065 -19.168003) (xy 382.773357 -19.24806) (xy 382.738165 -19.325121) (xy 382.695807 -19.398488)
			(xy 382.646667 -19.467496) (xy 382.59119 -19.531521) (xy 382.529878 -19.589982) (xy 382.463287 -19.642351)
			(xy 382.392019 -19.688153) (xy 382.316721 -19.726973) (xy 382.238073 -19.75846) (xy 382.156788 -19.782328)
			(xy 382.073603 -19.798362) (xy 381.98927 -19.806416) (xy 381.946912 -19.80692) (xy 381.905729 -19.806447)
			(xy 381.823717 -19.79882) (xy 381.74276 -19.78365) (xy 381.663551 -19.761065) (xy 381.586767 -19.731259)
			(xy 381.513065 -19.694486) (xy 381.443075 -19.651063) (xy 381.409956 -19.62658) (xy 381.400784 -19.620283)
			(xy 381.379057 -19.615589) (xy 381.357375 -19.620488) (xy 381.348234 -19.626834) (xy 381.31487 -19.651993)
			(xy 381.244237 -19.696654) (xy 381.16973 -19.7345) (xy 381.092004 -19.765194) (xy 381.011742 -19.788469)
			(xy 380.929653 -19.804118) (xy 380.846458 -19.812005) (xy 380.804674 -19.812508) (xy 380.803912 -19.812508)
			(xy 380.761562 -19.81202) (xy 380.677247 -19.80397) (xy 380.594078 -19.787942) (xy 380.512809 -19.76408)
			(xy 380.434177 -19.732602) (xy 380.358893 -19.693791) (xy 380.287639 -19.648) (xy 380.221061 -19.595643)
			(xy 380.15976 -19.537194) (xy 380.104294 -19.473183) (xy 380.055163 -19.404189) (xy 380.012813 -19.330838)
			(xy 379.977628 -19.253793) (xy 379.949925 -19.173752) (xy 379.929956 -19.09144) (xy 379.917902 -19.007603)
			(xy 379.913872 -18.923) (xy 374.118004 -18.923) (xy 374.111667 -19.003518) (xy 374.087962 -19.203802)
			(xy 374.056412 -19.403001) (xy 374.017066 -19.600808) (xy 373.969984 -19.796917) (xy 373.915239 -19.991027)
			(xy 373.852916 -20.182838) (xy 373.783111 -20.372055) (xy 373.70593 -20.558384) (xy 373.621494 -20.741541)
			(xy 373.529932 -20.921241) (xy 373.431386 -21.097207) (xy 373.326008 -21.26917) (xy 373.281353 -21.336)
			(xy 377.570492 -21.336) (xy 377.570492 -21.335492) (xy 377.571011 -21.291728) (xy 377.579586 -21.204622)
			(xy 377.596682 -21.118781) (xy 377.622133 -21.035035) (xy 377.655693 -20.954197) (xy 377.675902 -20.915376)
			(xy 377.681229 -20.904023) (xy 377.681229 -20.878977) (xy 377.675902 -20.867624) (xy 377.655708 -20.828796)
			(xy 377.622168 -20.747953) (xy 377.596723 -20.664208) (xy 377.579618 -20.578371) (xy 377.571019 -20.49127)
			(xy 377.570492 -20.447508) (xy 377.570492 -20.447) (xy 377.570967 -20.405898) (xy 377.578552 -20.324043)
			(xy 377.593657 -20.243238) (xy 377.616153 -20.164171) (xy 377.645849 -20.087517) (xy 377.682491 -20.01393)
			(xy 377.725766 -19.944038) (xy 377.775306 -19.878437) (xy 377.830687 -19.817687) (xy 377.891437 -19.762306)
			(xy 377.957038 -19.712766) (xy 378.02693 -19.669491) (xy 378.100517 -19.632849) (xy 378.177171 -19.603153)
			(xy 378.256238 -19.580657) (xy 378.337043 -19.565552) (xy 378.418898 -19.557967) (xy 378.46 -19.557492)
			(xy 378.50339 -19.55802) (xy 378.589756 -19.566478) (xy 378.674889 -19.583304) (xy 378.757979 -19.608337)
			(xy 378.838238 -19.641341) (xy 378.914902 -19.682001) (xy 378.987244 -19.729931) (xy 379.054576 -19.784676)
			(xy 379.116259 -19.845717) (xy 379.171707 -19.912472) (xy 379.220392 -19.984308) (xy 379.232923 -20.007349)
			(xy 386.042397 -20.007349) (xy 386.042397 -19.870651) (xy 386.050345 -19.734184) (xy 386.066215 -19.598411)
			(xy 386.089952 -19.463789) (xy 386.121477 -19.330776) (xy 386.160683 -19.199821) (xy 386.207436 -19.071367)
			(xy 386.261579 -18.945848) (xy 386.322929 -18.823691) (xy 386.391278 -18.705307) (xy 386.466395 -18.591097)
			(xy 386.548026 -18.481448) (xy 386.635893 -18.376732) (xy 386.729701 -18.277301) (xy 386.829132 -18.183493)
			(xy 386.933848 -18.095626) (xy 387.043497 -18.013995) (xy 387.157707 -17.938878) (xy 387.276091 -17.870529)
			(xy 387.398248 -17.809179) (xy 387.523767 -17.755036) (xy 387.652221 -17.708283) (xy 387.783176 -17.669077)
			(xy 387.916189 -17.637552) (xy 388.050811 -17.613815) (xy 388.186584 -17.597945) (xy 388.323051 -17.589997)
			(xy 388.459749 -17.589997) (xy 388.596216 -17.597945) (xy 388.731989 -17.613815) (xy 388.866611 -17.637552)
			(xy 388.999624 -17.669077) (xy 389.130579 -17.708283) (xy 389.259033 -17.755036) (xy 389.384552 -17.809179)
			(xy 389.506709 -17.870529) (xy 389.625093 -17.938878) (xy 389.739303 -18.013995) (xy 389.848952 -18.095626)
			(xy 389.953668 -18.183493) (xy 390.053099 -18.277301) (xy 390.146907 -18.376732) (xy 390.234774 -18.481448)
			(xy 390.316405 -18.591097) (xy 390.391522 -18.705307) (xy 390.459871 -18.823691) (xy 390.521221 -18.945848)
			(xy 390.575364 -19.071367) (xy 390.622117 -19.199821) (xy 390.661323 -19.330776) (xy 390.692848 -19.463789)
			(xy 390.716585 -19.598411) (xy 390.732455 -19.734184) (xy 390.740403 -19.870651) (xy 390.7409 -19.939)
			(xy 390.740403 -20.007349) (xy 390.732455 -20.143816) (xy 390.716585 -20.279589) (xy 390.692848 -20.414211)
			(xy 390.661323 -20.547224) (xy 390.622117 -20.678179) (xy 390.575364 -20.806633) (xy 390.521221 -20.932152)
			(xy 390.459871 -21.054309) (xy 390.391522 -21.172693) (xy 390.316405 -21.286903) (xy 390.234774 -21.396552)
			(xy 390.146907 -21.501268) (xy 390.053099 -21.600699) (xy 389.953668 -21.694507) (xy 389.848952 -21.782374)
			(xy 389.739303 -21.864005) (xy 389.625093 -21.939122) (xy 389.506709 -22.007471) (xy 389.384552 -22.068821)
			(xy 389.259033 -22.122964) (xy 389.130579 -22.169717) (xy 388.999624 -22.208923) (xy 388.866611 -22.240448)
			(xy 388.731989 -22.264185) (xy 388.596216 -22.280055) (xy 388.459749 -22.288003) (xy 388.323051 -22.288003)
			(xy 388.186584 -22.280055) (xy 388.050811 -22.264185) (xy 387.916189 -22.240448) (xy 387.783176 -22.208923)
			(xy 387.652221 -22.169717) (xy 387.523767 -22.122964) (xy 387.398248 -22.068821) (xy 387.276091 -22.007471)
			(xy 387.157707 -21.939122) (xy 387.043497 -21.864005) (xy 386.933848 -21.782374) (xy 386.829132 -21.694507)
			(xy 386.729701 -21.600699) (xy 386.635893 -21.501268) (xy 386.548026 -21.396552) (xy 386.466395 -21.286903)
			(xy 386.391278 -21.172693) (xy 386.322929 -21.054309) (xy 386.261579 -20.932152) (xy 386.207436 -20.806633)
			(xy 386.160683 -20.678179) (xy 386.121477 -20.547224) (xy 386.089952 -20.414211) (xy 386.066215 -20.279589)
			(xy 386.050345 -20.143816) (xy 386.042397 -20.007349) (xy 379.232923 -20.007349) (xy 379.261853 -20.060542)
			(xy 379.295695 -20.140451) (xy 379.321597 -20.223275) (xy 379.330966 -20.265644) (xy 379.332998 -20.275804)
			(xy 379.344682 -20.292822) (xy 379.415294 -20.337272) (xy 379.424035 -20.342185) (xy 379.44377 -20.345593)
			(xy 379.453648 -20.343876) (xy 379.45441 -20.343876) (xy 379.505273 -20.332478) (xy 379.608793 -20.320252)
			(xy 379.660912 -20.319492) (xy 379.70326 -20.319996) (xy 379.787573 -20.328048) (xy 379.870738 -20.344078)
			(xy 379.952004 -20.367941) (xy 380.030632 -20.39942) (xy 380.105913 -20.438231) (xy 380.177164 -20.484021)
			(xy 380.243739 -20.536378) (xy 380.305036 -20.594825) (xy 380.3605 -20.658835) (xy 380.409629 -20.727827)
			(xy 380.451976 -20.801176) (xy 380.48716 -20.878218) (xy 380.514861 -20.958257) (xy 380.534829 -21.040565)
			(xy 380.546883 -21.1244) (xy 380.550913 -21.209) (xy 380.546883 -21.2936) (xy 380.534829 -21.377435)
			(xy 380.514861 -21.459743) (xy 380.48716 -21.539782) (xy 380.451976 -21.616824) (xy 380.409629 -21.690173)
			(xy 380.3605 -21.759165) (xy 380.305036 -21.823175) (xy 380.243739 -21.881622) (xy 380.177164 -21.933979)
			(xy 380.105913 -21.979769) (xy 380.030632 -22.01858) (xy 379.952004 -22.050059) (xy 379.870738 -22.073922)
			(xy 379.787573 -22.089952) (xy 379.70326 -22.098004) (xy 379.660912 -22.098508) (xy 379.617052 -22.097989)
			(xy 379.529758 -22.089349) (xy 379.443737 -22.072163) (xy 379.359825 -22.046596) (xy 379.278836 -22.012898)
			(xy 379.201555 -21.971394) (xy 379.16485 -21.947378) (xy 379.157237 -21.942758) (xy 379.139973 -21.938457)
			(xy 379.12228 -21.940315) (xy 379.106286 -21.948109) (xy 379.099826 -21.954236) (xy 379.06843 -21.985919)
			(xy 379.00032 -22.04352) (xy 378.926788 -22.094017) (xy 378.848572 -22.136902) (xy 378.766457 -22.171745)
			(xy 378.681268 -22.198196) (xy 378.593859 -22.215989) (xy 378.505108 -22.224946) (xy 378.460508 -22.225508)
			(xy 378.46 -22.225508) (xy 378.418898 -22.225033) (xy 378.337043 -22.217448) (xy 378.256238 -22.202343)
			(xy 378.177171 -22.179847) (xy 378.100517 -22.150151) (xy 378.02693 -22.113509) (xy 377.957038 -22.070234)
			(xy 377.891437 -22.020694) (xy 377.830687 -21.965313) (xy 377.775306 -21.904563) (xy 377.725766 -21.838962)
			(xy 377.682491 -21.76907) (xy 377.645849 -21.695483) (xy 377.616153 -21.618829) (xy 377.593657 -21.539762)
			(xy 377.578552 -21.458957) (xy 377.570967 -21.377102) (xy 377.570492 -21.336) (xy 373.281353 -21.336)
			(xy 373.213959 -21.436862) (xy 373.095413 -21.600026) (xy 372.970553 -21.758411) (xy 372.839571 -21.911771)
			(xy 372.702669 -22.059871) (xy 372.560059 -22.202481) (xy 372.411959 -22.339383) (xy 372.258599 -22.470365)
			(xy 372.100214 -22.595225) (xy 372.085384 -22.606) (xy 406.043892 -22.606) (xy 406.043892 -22.605492)
			(xy 406.044411 -22.561728) (xy 406.052986 -22.474622) (xy 406.070082 -22.388781) (xy 406.095533 -22.305035)
			(xy 406.129093 -22.224197) (xy 406.149302 -22.185376) (xy 406.154629 -22.174023) (xy 406.154629 -22.148977)
			(xy 406.149302 -22.137624) (xy 406.129087 -22.09875) (xy 406.095517 -22.017809) (xy 406.070061 -21.933962)
			(xy 406.052966 -21.848019) (xy 406.044396 -21.760813) (xy 406.043892 -21.717) (xy 406.044388 -21.673185)
			(xy 406.052933 -21.585974) (xy 406.07002 -21.500027) (xy 406.095481 -21.416179) (xy 406.129071 -21.335243)
			(xy 406.149302 -21.296376) (xy 406.154629 -21.285023) (xy 406.154629 -21.259977) (xy 406.149302 -21.248624)
			(xy 406.129108 -21.209796) (xy 406.095568 -21.128953) (xy 406.070123 -21.045208) (xy 406.053018 -20.959371)
			(xy 406.044419 -20.87227) (xy 406.043892 -20.828508) (xy 406.043892 -20.828) (xy 406.044367 -20.786898)
			(xy 406.051952 -20.705043) (xy 406.067057 -20.624238) (xy 406.089553 -20.545171) (xy 406.119249 -20.468517)
			(xy 406.155891 -20.39493) (xy 406.199166 -20.325038) (xy 406.248706 -20.259437) (xy 406.304087 -20.198687)
			(xy 406.364837 -20.143306) (xy 406.430438 -20.093766) (xy 406.50033 -20.050491) (xy 406.573917 -20.013849)
			(xy 406.650571 -19.984153) (xy 406.729638 -19.961657) (xy 406.810443 -19.946552) (xy 406.892298 -19.938967)
			(xy 406.9334 -19.938492) (xy 406.975715 -19.938995) (xy 407.059963 -19.947026) (xy 407.143066 -19.963024)
			(xy 407.224275 -19.986845) (xy 407.302852 -20.018272) (xy 407.378089 -20.057023) (xy 407.413968 -20.079462)
			(xy 407.422357 -20.084345) (xy 407.4414 -20.088016) (xy 407.460443 -20.084345) (xy 407.468832 -20.079462)
			(xy 407.504706 -20.057016) (xy 407.579947 -20.018273) (xy 407.658526 -19.986849) (xy 407.739735 -19.96303)
			(xy 407.822838 -19.94703) (xy 407.907085 -19.938994) (xy 407.9494 -19.938492) (xy 407.949908 -19.938492)
			(xy 407.99624 -19.939098) (xy 408.088398 -19.948769) (xy 408.179052 -19.967965) (xy 408.267221 -19.996477)
			(xy 408.309826 -20.014692) (xy 408.319768 -20.018498) (xy 408.341032 -20.018498) (xy 408.350974 -20.014692)
			(xy 408.393577 -19.99647) (xy 408.481744 -19.967952) (xy 408.5724 -19.94876) (xy 408.66456 -19.9391)
			(xy 408.710892 -19.938492) (xy 408.7114 -19.938492) (xy 408.751279 -19.938936) (xy 408.830716 -19.946066)
			(xy 408.909197 -19.96028) (xy 408.98609 -19.981462) (xy 409.060778 -20.009442) (xy 409.132661 -20.043996)
			(xy 409.201163 -20.084846) (xy 409.265732 -20.131664) (xy 409.325851 -20.184075) (xy 409.353766 -20.212558)
			(xy 409.35402 -20.212812) (xy 409.361001 -20.219412) (xy 409.378474 -20.22735) (xy 409.397645 -20.228249)
			(xy 409.406852 -20.225512) (xy 409.494228 -20.19554) (xy 409.503263 -20.19203) (xy 409.517944 -20.179394)
			(xy 409.526881 -20.162209) (xy 409.528264 -20.152614) (xy 409.533654 -20.106286) (xy 409.552889 -20.015018)
			(xy 409.581556 -19.926259) (xy 409.599892 -19.883374) (xy 409.603698 -19.873432) (xy 409.603698 -19.852168)
			(xy 409.599892 -19.842226) (xy 409.58167 -19.799623) (xy 409.553152 -19.711456) (xy 409.53396 -19.6208)
			(xy 409.5243 -19.52864) (xy 409.523692 -19.482308) (xy 409.523692 -19.4818) (xy 409.524167 -19.440698)
			(xy 409.531752 -19.358843) (xy 409.546857 -19.278038) (xy 409.569353 -19.198971) (xy 409.599049 -19.122317)
			(xy 409.635691 -19.04873) (xy 409.678966 -18.978838) (xy 409.728506 -18.913237) (xy 409.783887 -18.852487)
			(xy 409.844637 -18.797106) (xy 409.910238 -18.747566) (xy 409.98013 -18.704291) (xy 410.053717 -18.667649)
			(xy 410.130371 -18.637953) (xy 410.209438 -18.615457) (xy 410.290243 -18.600352) (xy 410.372098 -18.592767)
			(xy 410.4132 -18.592292) (xy 410.413708 -18.592292) (xy 410.46004 -18.592898) (xy 410.552198 -18.602569)
			(xy 410.642852 -18.621765) (xy 410.731021 -18.650277) (xy 410.773626 -18.668492) (xy 410.783568 -18.672298)
			(xy 410.804832 -18.672298) (xy 410.814774 -18.668492) (xy 410.857377 -18.65027) (xy 410.945544 -18.621752)
			(xy 411.0362 -18.60256) (xy 411.12836 -18.5929) (xy 411.174692 -18.592292) (xy 411.1752 -18.592292)
			(xy 411.216302 -18.592767) (xy 411.298157 -18.600352) (xy 411.378962 -18.615457) (xy 411.458029 -18.637953)
			(xy 411.534683 -18.667649) (xy 411.60827 -18.704291) (xy 411.678162 -18.747566) (xy 411.743763 -18.797106)
			(xy 411.804513 -18.852487) (xy 411.859894 -18.913237) (xy 411.909434 -18.978838) (xy 411.952709 -19.04873)
			(xy 411.989351 -19.122317) (xy 412.019047 -19.198971) (xy 412.041543 -19.278038) (xy 412.056648 -19.358843)
			(xy 412.064233 -19.440698) (xy 412.064708 -19.4818) (xy 412.064708 -19.482308) (xy 412.064102 -19.52864)
			(xy 412.054431 -19.620798) (xy 412.035235 -19.711452) (xy 412.006723 -19.799621) (xy 411.988508 -19.842226)
			(xy 411.984702 -19.852168) (xy 411.984702 -19.873432) (xy 411.988508 -19.883374) (xy 412.006753 -19.926036)
			(xy 412.035297 -20.014329) (xy 412.05449 -20.105114) (xy 412.064123 -20.197404) (xy 412.064708 -20.2438)
			(xy 412.064125 -20.290196) (xy 412.05448 -20.382484) (xy 412.035284 -20.473268) (xy 412.006746 -20.561561)
			(xy 411.988508 -20.604226) (xy 411.984702 -20.614168) (xy 411.984702 -20.635432) (xy 411.988508 -20.645374)
			(xy 412.00673 -20.687977) (xy 412.035248 -20.776144) (xy 412.05444 -20.8668) (xy 412.0641 -20.95896)
			(xy 412.064708 -21.005292) (xy 412.064708 -21.0058) (xy 412.064233 -21.046902) (xy 412.056648 -21.128757)
			(xy 412.055892 -21.1328) (xy 417.651692 -21.1328) (xy 417.651692 -21.132292) (xy 417.652298 -21.08596)
			(xy 417.661969 -20.993802) (xy 417.681165 -20.903148) (xy 417.709677 -20.814979) (xy 417.727892 -20.772374)
			(xy 417.731698 -20.762432) (xy 417.731698 -20.741168) (xy 417.727892 -20.731226) (xy 417.709647 -20.688564)
			(xy 417.681103 -20.600271) (xy 417.66191 -20.509486) (xy 417.652277 -20.417196) (xy 417.651692 -20.3708)
			(xy 417.652275 -20.324404) (xy 417.66192 -20.232116) (xy 417.681116 -20.141332) (xy 417.709654 -20.053039)
			(xy 417.727892 -20.010374) (xy 417.731698 -20.000432) (xy 417.731698 -19.979168) (xy 417.727892 -19.969226)
			(xy 417.70967 -19.926623) (xy 417.681152 -19.838456) (xy 417.66196 -19.7478) (xy 417.6523 -19.65564)
			(xy 417.651692 -19.609308) (xy 417.651692 -19.6088) (xy 417.652196 -19.566452) (xy 417.660247 -19.482138)
			(xy 417.676276 -19.398972) (xy 417.700137 -19.317705) (xy 417.731616 -19.239075) (xy 417.770427 -19.163794)
			(xy 417.816217 -19.092542) (xy 417.868573 -19.025966) (xy 417.927021 -18.964668) (xy 417.991031 -18.909203)
			(xy 418.060023 -18.860074) (xy 418.133373 -18.817725) (xy 418.210416 -18.782541) (xy 418.290455 -18.754839)
			(xy 418.372764 -18.734871) (xy 418.456599 -18.722818) (xy 418.5412 -18.718788) (xy 418.625801 -18.722818)
			(xy 418.709636 -18.734871) (xy 418.791945 -18.754839) (xy 418.871984 -18.782541) (xy 418.949027 -18.817725)
			(xy 419.022377 -18.860074) (xy 419.091369 -18.909203) (xy 419.155379 -18.964668) (xy 419.213827 -19.025966)
			(xy 419.266183 -19.092542) (xy 419.311973 -19.163794) (xy 419.350784 -19.239075) (xy 419.382263 -19.317705)
			(xy 419.406124 -19.398972) (xy 419.415728 -19.4488) (xy 428.877968 -19.4488) (xy 428.881998 -19.364197)
			(xy 428.894052 -19.28036) (xy 428.91402 -19.198049) (xy 428.941722 -19.118008) (xy 428.976908 -19.040964)
			(xy 429.019257 -18.967612) (xy 429.068387 -18.898618) (xy 429.123853 -18.834607) (xy 429.185153 -18.776158)
			(xy 429.25173 -18.723801) (xy 429.322984 -18.678009) (xy 429.398267 -18.639198) (xy 429.476899 -18.607719)
			(xy 429.558167 -18.583856) (xy 429.641335 -18.567827) (xy 429.725651 -18.559776) (xy 429.768 -18.559272)
			(xy 429.768254 -18.559272) (xy 429.810241 -18.559752) (xy 429.893839 -18.567693) (xy 429.976318 -18.583469)
			(xy 430.056944 -18.606941) (xy 430.135003 -18.6379) (xy 430.172622 -18.656554) (xy 430.184121 -18.661717)
			(xy 430.209296 -18.661314) (xy 430.220628 -18.655792) (xy 430.260629 -18.63396) (xy 430.3442 -18.59761)
			(xy 430.431051 -18.570003) (xy 430.520272 -18.551428) (xy 430.610925 -18.542081) (xy 430.656492 -18.541492)
			(xy 430.657 -18.541492) (xy 430.699348 -18.541996) (xy 430.783662 -18.550047) (xy 430.866828 -18.566076)
			(xy 430.948095 -18.589937) (xy 431.026725 -18.621416) (xy 431.102006 -18.660227) (xy 431.173258 -18.706017)
			(xy 431.239834 -18.758373) (xy 431.301132 -18.816821) (xy 431.356597 -18.880831) (xy 431.405726 -18.949823)
			(xy 431.448075 -19.023173) (xy 431.483259 -19.100216) (xy 431.510961 -19.180255) (xy 431.530929 -19.262564)
			(xy 431.542982 -19.346399) (xy 431.547013 -19.431) (xy 431.542982 -19.515601) (xy 431.530929 -19.599436)
			(xy 431.510961 -19.681745) (xy 431.483259 -19.761784) (xy 431.448075 -19.838827) (xy 431.405726 -19.912177)
			(xy 431.356597 -19.981169) (xy 431.301132 -20.045179) (xy 431.239834 -20.103627) (xy 431.173258 -20.155983)
			(xy 431.102006 -20.201773) (xy 431.026725 -20.240584) (xy 430.948095 -20.272063) (xy 430.866828 -20.295924)
			(xy 430.783662 -20.311953) (xy 430.699348 -20.320004) (xy 430.657 -20.320508) (xy 430.656746 -20.320508)
			(xy 430.614759 -20.320019) (xy 430.531162 -20.31208) (xy 430.448684 -20.296305) (xy 430.368057 -20.272835)
			(xy 430.289997 -20.241878) (xy 430.252378 -20.223226) (xy 430.24088 -20.218057) (xy 430.215703 -20.21846)
			(xy 430.204372 -20.223988) (xy 430.164375 -20.245827) (xy 430.080803 -20.282174) (xy 429.99395 -20.30978)
			(xy 429.904729 -20.328353) (xy 429.814075 -20.337699) (xy 429.768508 -20.338288) (xy 429.768 -20.338288)
			(xy 429.725651 -20.337824) (xy 429.641335 -20.329773) (xy 429.558167 -20.313744) (xy 429.476899 -20.289881)
			(xy 429.398267 -20.258402) (xy 429.322984 -20.219591) (xy 429.25173 -20.173799) (xy 429.185153 -20.121442)
			(xy 429.123853 -20.062993) (xy 429.068387 -19.998982) (xy 429.019257 -19.929988) (xy 428.976908 -19.856636)
			(xy 428.941722 -19.779592) (xy 428.91402 -19.699551) (xy 428.894052 -19.61724) (xy 428.881998 -19.533403)
			(xy 428.877968 -19.4488) (xy 419.415728 -19.4488) (xy 419.422153 -19.482138) (xy 419.430204 -19.566452)
			(xy 419.430708 -19.6088) (xy 419.430708 -19.609308) (xy 419.430102 -19.65564) (xy 419.420431 -19.747798)
			(xy 419.401235 -19.838452) (xy 419.372723 -19.926621) (xy 419.354508 -19.969226) (xy 419.350702 -19.979168)
			(xy 419.350702 -20.000432) (xy 419.354508 -20.010374) (xy 419.372753 -20.053036) (xy 419.401297 -20.141329)
			(xy 419.42049 -20.232114) (xy 419.430123 -20.324404) (xy 419.430708 -20.3708) (xy 419.430125 -20.417196)
			(xy 419.42048 -20.509484) (xy 419.401284 -20.600268) (xy 419.372746 -20.688561) (xy 419.354508 -20.731226)
			(xy 419.350702 -20.741168) (xy 419.350702 -20.762432) (xy 419.354508 -20.772374) (xy 419.37273 -20.814977)
			(xy 419.401248 -20.903144) (xy 419.42044 -20.9938) (xy 419.4301 -21.08596) (xy 419.430708 -21.132292)
			(xy 419.430708 -21.1328) (xy 419.430204 -21.175148) (xy 419.422153 -21.259462) (xy 419.406124 -21.342628)
			(xy 419.382263 -21.423895) (xy 419.350784 -21.502525) (xy 419.311973 -21.577806) (xy 419.266183 -21.649058)
			(xy 419.213827 -21.715634) (xy 419.155379 -21.776932) (xy 419.091369 -21.832397) (xy 419.022377 -21.881526)
			(xy 418.949027 -21.923875) (xy 418.871984 -21.959059) (xy 418.791945 -21.986761) (xy 418.709636 -22.006729)
			(xy 418.625801 -22.018782) (xy 418.5412 -22.022813) (xy 418.456599 -22.018782) (xy 418.372764 -22.006729)
			(xy 418.290455 -21.986761) (xy 418.210416 -21.959059) (xy 418.133373 -21.923875) (xy 418.060023 -21.881526)
			(xy 417.991031 -21.832397) (xy 417.927021 -21.776932) (xy 417.868573 -21.715634) (xy 417.816217 -21.649058)
			(xy 417.770427 -21.577806) (xy 417.731616 -21.502525) (xy 417.700137 -21.423895) (xy 417.676276 -21.342628)
			(xy 417.660247 -21.259462) (xy 417.652196 -21.175148) (xy 417.651692 -21.1328) (xy 412.055892 -21.1328)
			(xy 412.041543 -21.209562) (xy 412.019047 -21.288629) (xy 411.989351 -21.365283) (xy 411.952709 -21.43887)
			(xy 411.909434 -21.508762) (xy 411.859894 -21.574363) (xy 411.804513 -21.635113) (xy 411.743763 -21.690494)
			(xy 411.678162 -21.740034) (xy 411.60827 -21.783309) (xy 411.534683 -21.819951) (xy 411.458029 -21.849647)
			(xy 411.378962 -21.872143) (xy 411.298157 -21.887248) (xy 411.216302 -21.894833) (xy 411.1752 -21.895308)
			(xy 411.174692 -21.895308) (xy 411.12836 -21.894702) (xy 411.036202 -21.885031) (xy 410.945548 -21.865835)
			(xy 410.857379 -21.837323) (xy 410.814774 -21.819108) (xy 410.804832 -21.815302) (xy 410.783568 -21.815302)
			(xy 410.773626 -21.819108) (xy 410.730964 -21.837353) (xy 410.642671 -21.865897) (xy 410.551886 -21.88509)
			(xy 410.459596 -21.894723) (xy 410.4132 -21.895308) (xy 410.368725 -21.894772) (xy 410.280218 -21.885915)
			(xy 410.193037 -21.868269) (xy 410.108052 -21.842011) (xy 410.026112 -21.807402) (xy 409.948035 -21.764789)
			(xy 409.8746 -21.714596) (xy 409.806541 -21.657326) (xy 409.775152 -21.625814) (xy 409.76423 -21.614638)
			(xy 409.734004 -21.608288) (xy 409.617418 -21.657056) (xy 409.600654 -21.682964) (xy 409.600908 -21.698204)
			(xy 409.600908 -21.69922) (xy 409.600908 -21.717) (xy 409.600412 -21.760815) (xy 409.591867 -21.848026)
			(xy 409.57478 -21.933973) (xy 409.549319 -22.017821) (xy 409.515729 -22.098757) (xy 409.495498 -22.137624)
			(xy 409.490171 -22.148977) (xy 409.490171 -22.174023) (xy 409.495498 -22.185376) (xy 409.515692 -22.224204)
			(xy 409.549232 -22.305047) (xy 409.574677 -22.388792) (xy 409.591782 -22.474629) (xy 409.600381 -22.56173)
			(xy 409.600908 -22.605492) (xy 409.600908 -22.606) (xy 409.600433 -22.647102) (xy 409.592848 -22.728957)
			(xy 409.577743 -22.809762) (xy 409.555247 -22.888829) (xy 409.525551 -22.965483) (xy 409.488909 -23.03907)
			(xy 409.445634 -23.108962) (xy 409.396094 -23.174563) (xy 409.340713 -23.235313) (xy 409.279963 -23.290694)
			(xy 409.214362 -23.340234) (xy 409.14447 -23.383509) (xy 409.090544 -23.410361) (xy 432.460142 -23.410361)
			(xy 432.460142 -23.325639) (xy 432.468195 -23.241302) (xy 432.484229 -23.158112) (xy 432.508097 -23.076822)
			(xy 432.539585 -22.99817) (xy 432.578407 -22.922867) (xy 432.62421 -22.851595) (xy 432.676581 -22.784999)
			(xy 432.735046 -22.723684) (xy 432.799074 -22.668203) (xy 432.868086 -22.61906) (xy 432.941456 -22.5767)
			(xy 433.018521 -22.541505) (xy 433.098583 -22.513796) (xy 433.180916 -22.493822) (xy 433.264775 -22.481765)
			(xy 433.3494 -22.477734) (xy 433.434025 -22.481765) (xy 433.517884 -22.493822) (xy 433.600217 -22.513796)
			(xy 433.680279 -22.541505) (xy 433.757344 -22.5767) (xy 433.830714 -22.61906) (xy 433.899726 -22.668203)
			(xy 433.963754 -22.723684) (xy 434.022219 -22.784999) (xy 434.07459 -22.851595) (xy 434.120393 -22.922867)
			(xy 434.159215 -22.99817) (xy 434.190703 -23.076822) (xy 434.214571 -23.158112) (xy 434.230605 -23.241302)
			(xy 434.238658 -23.325639) (xy 434.239162 -23.368) (xy 434.238658 -23.410361) (xy 434.230605 -23.494698)
			(xy 434.214571 -23.577888) (xy 434.190703 -23.659178) (xy 434.159215 -23.73783) (xy 434.120393 -23.813133)
			(xy 434.07459 -23.884405) (xy 434.022219 -23.951001) (xy 433.963754 -24.012316) (xy 433.899726 -24.067797)
			(xy 433.830714 -24.11694) (xy 433.757344 -24.1593) (xy 433.680279 -24.194495) (xy 433.600217 -24.222204)
			(xy 433.517884 -24.242178) (xy 433.434025 -24.254235) (xy 433.3494 -24.258267) (xy 433.264775 -24.254235)
			(xy 433.180916 -24.242178) (xy 433.098583 -24.222204) (xy 433.018521 -24.194495) (xy 432.941456 -24.1593)
			(xy 432.868086 -24.11694) (xy 432.799074 -24.067797) (xy 432.735046 -24.012316) (xy 432.676581 -23.951001)
			(xy 432.62421 -23.884405) (xy 432.578407 -23.813133) (xy 432.539585 -23.73783) (xy 432.508097 -23.659178)
			(xy 432.484229 -23.577888) (xy 432.468195 -23.494698) (xy 432.460142 -23.410361) (xy 409.090544 -23.410361)
			(xy 409.070883 -23.420151) (xy 408.994229 -23.449847) (xy 408.915162 -23.472343) (xy 408.834357 -23.487448)
			(xy 408.752502 -23.495033) (xy 408.7114 -23.495508) (xy 408.710892 -23.495508) (xy 408.66456 -23.494902)
			(xy 408.572402 -23.485231) (xy 408.481748 -23.466035) (xy 408.393579 -23.437523) (xy 408.350974 -23.419308)
			(xy 408.341032 -23.415502) (xy 408.319768 -23.415502) (xy 408.309826 -23.419308) (xy 408.267223 -23.43753)
			(xy 408.179056 -23.466048) (xy 408.0884 -23.48524) (xy 407.99624 -23.4949) (xy 407.949908 -23.495508)
			(xy 407.9494 -23.495508) (xy 407.907085 -23.495005) (xy 407.822837 -23.486974) (xy 407.739734 -23.470976)
			(xy 407.658525 -23.447155) (xy 407.579948 -23.415728) (xy 407.504711 -23.376977) (xy 407.468832 -23.354538)
			(xy 407.460443 -23.349655) (xy 407.4414 -23.345984) (xy 407.422357 -23.349655) (xy 407.413968 -23.354538)
			(xy 407.378094 -23.376984) (xy 407.302853 -23.415727) (xy 407.224274 -23.447151) (xy 407.143065 -23.47097)
			(xy 407.059962 -23.48697) (xy 406.975715 -23.495006) (xy 406.9334 -23.495508) (xy 406.892298 -23.495033)
			(xy 406.810443 -23.487448) (xy 406.729638 -23.472343) (xy 406.650571 -23.449847) (xy 406.573917 -23.420151)
			(xy 406.50033 -23.383509) (xy 406.430438 -23.340234) (xy 406.364837 -23.290694) (xy 406.304087 -23.235313)
			(xy 406.248706 -23.174563) (xy 406.199166 -23.108962) (xy 406.155891 -23.03907) (xy 406.119249 -22.965483)
			(xy 406.089553 -22.888829) (xy 406.067057 -22.809762) (xy 406.051952 -22.728957) (xy 406.044367 -22.647102)
			(xy 406.043892 -22.606) (xy 372.085384 -22.606) (xy 371.93705 -22.713771) (xy 371.769358 -22.82582)
			(xy 371.597395 -22.931198) (xy 371.421429 -23.029744) (xy 371.241729 -23.121306) (xy 371.058572 -23.205742)
			(xy 370.872243 -23.282923) (xy 370.683026 -23.352728) (xy 370.491215 -23.415051) (xy 370.297105 -23.469796)
			(xy 370.100996 -23.516878) (xy 369.903189 -23.556224) (xy 369.70399 -23.587774) (xy 369.503706 -23.611479)
			(xy 369.302646 -23.627303) (xy 369.101119 -23.635221) (xy 368.899437 -23.635221) (xy 368.69791 -23.627303)
			(xy 368.49685 -23.611479) (xy 368.296566 -23.587774) (xy 368.097367 -23.556224) (xy 367.89956 -23.516878)
			(xy 367.703451 -23.469796) (xy 367.509341 -23.415051) (xy 367.31753 -23.352728) (xy 367.128313 -23.282923)
			(xy 366.941984 -23.205742) (xy 366.758827 -23.121306) (xy 366.579127 -23.029744) (xy 366.403161 -22.931198)
			(xy 366.231198 -22.82582) (xy 366.063506 -22.713771) (xy 365.900342 -22.595225) (xy 365.741957 -22.470365)
			(xy 365.588597 -22.339383) (xy 365.440497 -22.202481) (xy 365.297887 -22.059871) (xy 365.160985 -21.911771)
			(xy 365.030003 -21.758411) (xy 364.905143 -21.600026) (xy 364.786597 -21.436862) (xy 364.674548 -21.26917)
			(xy 364.56917 -21.097207) (xy 364.470624 -20.921241) (xy 364.379062 -20.741541) (xy 364.294626 -20.558384)
			(xy 364.217445 -20.372055) (xy 364.14764 -20.182838) (xy 364.085317 -19.991027) (xy 364.030572 -19.796917)
			(xy 363.98349 -19.600808) (xy 363.944144 -19.403001) (xy 363.912594 -19.203802) (xy 363.888889 -19.003518)
			(xy 363.873065 -18.802458) (xy 363.865147 -18.600931) (xy 363.864652 -18.50009) (xy 357.521002 -18.50009)
			(xy 364.147812 -25.1269) (xy 386.993184 -25.1269) (xy 386.997214 -25.04228) (xy 387.009271 -24.958425)
			(xy 387.029244 -24.876097) (xy 387.056952 -24.79604) (xy 387.092144 -24.718979) (xy 387.134502 -24.645613)
			(xy 387.183643 -24.576605) (xy 387.23912 -24.51258) (xy 387.300432 -24.454119) (xy 387.367024 -24.401751)
			(xy 387.438292 -24.35595) (xy 387.513591 -24.317131) (xy 387.592239 -24.285645) (xy 387.673524 -24.261777)
			(xy 387.756709 -24.245745) (xy 387.841042 -24.237692) (xy 387.8834 -24.237188) (xy 387.929538 -24.237811)
			(xy 388.021312 -24.247437) (xy 388.111596 -24.266512) (xy 388.155688 -24.280114) (xy 388.164633 -24.282583)
			(xy 388.18315 -24.28159) (xy 388.200094 -24.274055) (xy 388.213234 -24.26097) (xy 388.21741 -24.252682)
			(xy 388.235507 -24.214416) (xy 388.277885 -24.141135) (xy 388.327034 -24.072211) (xy 388.382507 -24.008268)
			(xy 388.443803 -23.949883) (xy 388.510368 -23.897585) (xy 388.5816 -23.851846) (xy 388.656855 -23.81308)
			(xy 388.735451 -23.781639) (xy 388.816679 -23.757805) (xy 388.899804 -23.741796) (xy 388.984074 -23.733754)
			(xy 389.0264 -23.733252) (xy 389.068761 -23.733728) (xy 389.1531 -23.741781) (xy 389.236292 -23.757815)
			(xy 389.317582 -23.781684) (xy 389.396236 -23.813172) (xy 389.47154 -23.851994) (xy 389.542813 -23.897799)
			(xy 389.60941 -23.950171) (xy 389.670726 -24.008636) (xy 389.726208 -24.072665) (xy 389.775352 -24.141678)
			(xy 389.817713 -24.21505) (xy 389.852908 -24.292116) (xy 389.880618 -24.372179) (xy 389.900592 -24.454513)
			(xy 389.912649 -24.538373) (xy 389.913363 -24.553361) (xy 393.064742 -24.553361) (xy 393.064742 -24.468639)
			(xy 393.072795 -24.384302) (xy 393.088829 -24.301112) (xy 393.112697 -24.219822) (xy 393.144185 -24.14117)
			(xy 393.183007 -24.065867) (xy 393.22881 -23.994595) (xy 393.281181 -23.927999) (xy 393.339646 -23.866684)
			(xy 393.403674 -23.811203) (xy 393.472686 -23.76206) (xy 393.546056 -23.7197) (xy 393.623121 -23.684505)
			(xy 393.703183 -23.656796) (xy 393.785516 -23.636822) (xy 393.869375 -23.624765) (xy 393.954 -23.620734)
			(xy 394.038625 -23.624765) (xy 394.122484 -23.636822) (xy 394.204817 -23.656796) (xy 394.284879 -23.684505)
			(xy 394.361944 -23.7197) (xy 394.435314 -23.76206) (xy 394.504326 -23.811203) (xy 394.568354 -23.866684)
			(xy 394.626819 -23.927999) (xy 394.67919 -23.994595) (xy 394.724993 -24.065867) (xy 394.763815 -24.14117)
			(xy 394.795303 -24.219822) (xy 394.819171 -24.301112) (xy 394.835205 -24.384302) (xy 394.843258 -24.468639)
			(xy 394.843762 -24.511) (xy 394.843258 -24.553361) (xy 394.835205 -24.637698) (xy 394.819171 -24.720888)
			(xy 394.795303 -24.802178) (xy 394.763815 -24.88083) (xy 394.724993 -24.956133) (xy 394.67919 -25.027405)
			(xy 394.626819 -25.094001) (xy 394.568354 -25.155316) (xy 394.504326 -25.210797) (xy 394.435314 -25.25994)
			(xy 394.361944 -25.3023) (xy 394.284879 -25.337495) (xy 394.204817 -25.365204) (xy 394.122484 -25.385178)
			(xy 394.038625 -25.397235) (xy 393.954 -25.401267) (xy 393.869375 -25.397235) (xy 393.785516 -25.385178)
			(xy 393.703183 -25.365204) (xy 393.623121 -25.337495) (xy 393.546056 -25.3023) (xy 393.472686 -25.25994)
			(xy 393.403674 -25.210797) (xy 393.339646 -25.155316) (xy 393.281181 -25.094001) (xy 393.22881 -25.027405)
			(xy 393.183007 -24.956133) (xy 393.144185 -24.88083) (xy 393.112697 -24.802178) (xy 393.088829 -24.720888)
			(xy 393.072795 -24.637698) (xy 393.064742 -24.553361) (xy 389.913363 -24.553361) (xy 389.916681 -24.623)
			(xy 389.912649 -24.707627) (xy 389.900592 -24.791487) (xy 389.880618 -24.873821) (xy 389.852908 -24.953884)
			(xy 389.817713 -25.03095) (xy 389.775352 -25.104322) (xy 389.726208 -25.173335) (xy 389.670726 -25.237364)
			(xy 389.60941 -25.295829) (xy 389.542813 -25.348201) (xy 389.47154 -25.394006) (xy 389.396236 -25.432828)
			(xy 389.317582 -25.464316) (xy 389.236292 -25.488185) (xy 389.1531 -25.504219) (xy 389.068761 -25.512272)
			(xy 389.0264 -25.512776) (xy 388.980262 -25.51215) (xy 388.888488 -25.502525) (xy 388.798204 -25.483451)
			(xy 388.754112 -25.46985) (xy 388.745163 -25.467401) (xy 388.726651 -25.468394) (xy 388.709711 -25.475923)
			(xy 388.69657 -25.488999) (xy 388.69239 -25.497282) (xy 388.674276 -25.53554) (xy 388.6319 -25.608821)
			(xy 388.582754 -25.677746) (xy 388.527283 -25.741691) (xy 388.465989 -25.800077) (xy 388.399426 -25.852376)
			(xy 388.328195 -25.898115) (xy 388.252942 -25.936882) (xy 388.174346 -25.968324) (xy 388.093119 -25.992158)
			(xy 388.009995 -26.008168) (xy 387.925726 -26.01621) (xy 387.8834 -26.016712) (xy 387.841042 -26.016108)
			(xy 387.756709 -26.008055) (xy 387.673524 -25.992023) (xy 387.592239 -25.968155) (xy 387.513591 -25.936669)
			(xy 387.438292 -25.89785) (xy 387.367024 -25.852049) (xy 387.300432 -25.799681) (xy 387.23912 -25.74122)
			(xy 387.183643 -25.677195) (xy 387.134502 -25.608187) (xy 387.092144 -25.534821) (xy 387.056952 -25.45776)
			(xy 387.029244 -25.377703) (xy 387.009271 -25.295375) (xy 386.997214 -25.21152) (xy 386.993184 -25.1269)
			(xy 364.147812 -25.1269) (xy 367.919254 -28.898342) (xy 375.771664 -28.898342) (xy 375.772264 -28.851947)
			(xy 375.781904 -28.759659) (xy 375.801095 -28.668875) (xy 375.829629 -28.580581) (xy 375.847864 -28.537916)
			(xy 375.851646 -28.527966) (xy 375.851662 -28.50671) (xy 375.847864 -28.496768) (xy 375.829631 -28.454101)
			(xy 375.801085 -28.36581) (xy 375.781888 -28.275027) (xy 375.772251 -28.182738) (xy 375.771664 -28.136342)
			(xy 375.772264 -28.089947) (xy 375.781904 -27.997659) (xy 375.801095 -27.906875) (xy 375.829629 -27.818581)
			(xy 375.847864 -27.775916) (xy 375.851646 -27.765966) (xy 375.851662 -27.74471) (xy 375.847864 -27.734768)
			(xy 375.829631 -27.692101) (xy 375.801085 -27.60381) (xy 375.781888 -27.513027) (xy 375.772251 -27.420738)
			(xy 375.771664 -27.374342) (xy 375.772264 -27.327947) (xy 375.781904 -27.235659) (xy 375.801095 -27.144875)
			(xy 375.829629 -27.056581) (xy 375.847864 -27.013916) (xy 375.851646 -27.003966) (xy 375.851662 -26.98271)
			(xy 375.847864 -26.972768) (xy 375.829654 -26.93016) (xy 375.801134 -26.841994) (xy 375.781938 -26.751341)
			(xy 375.772274 -26.659182) (xy 375.771664 -26.61285) (xy 375.771664 -26.612342) (xy 375.772153 -26.571235)
			(xy 375.779733 -26.489372) (xy 375.794834 -26.408557) (xy 375.817327 -26.32948) (xy 375.847018 -26.252815)
			(xy 375.883656 -26.179216) (xy 375.926927 -26.109312) (xy 375.976463 -26.043697) (xy 376.031842 -25.982933)
			(xy 376.092589 -25.927536) (xy 376.158189 -25.87798) (xy 376.22808 -25.834687) (xy 376.301668 -25.798027)
			(xy 376.378324 -25.768312) (xy 376.457394 -25.745796) (xy 376.538204 -25.730671) (xy 376.620065 -25.723065)
			(xy 376.661172 -25.72258) (xy 376.707575 -25.723181) (xy 376.799873 -25.732879) (xy 376.890658 -25.75214)
			(xy 376.978943 -25.780755) (xy 377.021598 -25.799034) (xy 377.03154 -25.80284) (xy 377.052804 -25.80284)
			(xy 377.062746 -25.799034) (xy 377.105411 -25.780781) (xy 377.193697 -25.752186) (xy 377.284479 -25.732926)
			(xy 377.376771 -25.72321) (xy 377.423172 -25.72258) (xy 377.469575 -25.723181) (xy 377.561873 -25.732879)
			(xy 377.652658 -25.75214) (xy 377.740943 -25.780755) (xy 377.783598 -25.799034) (xy 377.79354 -25.80284)
			(xy 377.814804 -25.80284) (xy 377.824746 -25.799034) (xy 377.867411 -25.780781) (xy 377.955697 -25.752186)
			(xy 378.046479 -25.732926) (xy 378.138771 -25.72321) (xy 378.185172 -25.72258) (xy 378.231575 -25.723181)
			(xy 378.323873 -25.732879) (xy 378.414658 -25.75214) (xy 378.502943 -25.780755) (xy 378.545598 -25.799034)
			(xy 378.55554 -25.80284) (xy 378.576804 -25.80284) (xy 378.586746 -25.799034) (xy 378.629411 -25.780781)
			(xy 378.717697 -25.752186) (xy 378.808479 -25.732926) (xy 378.900771 -25.72321) (xy 378.947172 -25.72258)
			(xy 378.988282 -25.723079) (xy 379.070151 -25.730664) (xy 379.15097 -25.745772) (xy 379.230051 -25.768275)
			(xy 379.306717 -25.797979) (xy 379.380315 -25.834632) (xy 379.450216 -25.87792) (xy 379.515824 -25.927474)
			(xy 379.576579 -25.982872) (xy 379.631962 -26.04364) (xy 379.681501 -26.10926) (xy 379.724773 -26.179172)
			(xy 379.761408 -26.252779) (xy 379.791093 -26.329452) (xy 379.811377 -26.4008) (xy 411.953947 -26.4008)
			(xy 411.957978 -26.316196) (xy 411.970031 -26.232359) (xy 411.99 -26.150047) (xy 412.017702 -26.070005)
			(xy 412.052887 -25.99296) (xy 412.095236 -25.919607) (xy 412.144366 -25.850613) (xy 412.199832 -25.7866)
			(xy 412.261131 -25.72815) (xy 412.327709 -25.675792) (xy 412.398962 -25.629999) (xy 412.474246 -25.591186)
			(xy 412.552877 -25.559705) (xy 412.634146 -25.535841) (xy 412.717314 -25.51981) (xy 412.80163 -25.511757)
			(xy 412.84398 -25.511252) (xy 412.884281 -25.511699) (xy 412.964552 -25.518997) (xy 413.043833 -25.533527)
			(xy 413.121475 -25.555169) (xy 413.196842 -25.583746) (xy 413.269314 -25.619023) (xy 413.338298 -25.660711)
			(xy 413.37103 -25.684226) (xy 413.378907 -25.689516) (xy 413.397211 -25.694449) (xy 413.416053 -25.692356)
			(xy 413.424624 -25.68829) (xy 413.462668 -25.669069) (xy 413.541705 -25.637142) (xy 413.623437 -25.61293)
			(xy 413.707111 -25.596658) (xy 413.791959 -25.588473) (xy 413.83458 -25.58796) (xy 413.85168 -25.588086)
			(xy 413.885853 -25.589484) (xy 413.902906 -25.590754) (xy 413.911034 -25.590754) (xy 413.92973 -25.589242)
			(xy 413.967207 -25.58759) (xy 413.985964 -25.587452) (xy 413.98698 -25.587452) (xy 414.028081 -25.587986)
			(xy 414.109932 -25.595568) (xy 414.190735 -25.610671) (xy 414.2698 -25.633164) (xy 414.346452 -25.662857)
			(xy 414.420037 -25.699496) (xy 414.489928 -25.742767) (xy 414.555528 -25.792303) (xy 414.616278 -25.84768)
			(xy 414.671659 -25.908426) (xy 414.721199 -25.974023) (xy 414.764475 -26.043911) (xy 414.801119 -26.117493)
			(xy 414.830816 -26.194143) (xy 414.853315 -26.273206) (xy 414.868423 -26.354008) (xy 414.876012 -26.435859)
			(xy 414.876176 -26.450036) (xy 415.298636 -26.450036) (xy 415.299086 -26.408325) (xy 415.306888 -26.32527)
			(xy 415.322435 -26.24331) (xy 415.345591 -26.163167) (xy 415.376153 -26.085546) (xy 415.413851 -26.011128)
			(xy 415.458355 -25.940569) (xy 415.509272 -25.874489) (xy 415.566155 -25.813469) (xy 415.628503 -25.758046)
			(xy 415.661856 -25.732994) (xy 415.670399 -25.726052) (xy 415.681076 -25.706833) (xy 415.68243 -25.69591)
			(xy 415.686144 -25.654539) (xy 415.700231 -25.572675) (xy 415.721888 -25.49248) (xy 415.750926 -25.414652)
			(xy 415.787092 -25.339871) (xy 415.830071 -25.268786) (xy 415.87949 -25.202018) (xy 415.934918 -25.140146)
			(xy 415.995871 -25.083711) (xy 416.06182 -25.033204) (xy 416.132189 -24.989063) (xy 416.206367 -24.951675)
			(xy 416.283708 -24.921364) (xy 416.363536 -24.898394) (xy 416.445159 -24.882965) (xy 416.527864 -24.875213)
			(xy 416.569398 -24.874728) (xy 416.569906 -24.874728) (xy 416.61367 -24.875243) (xy 416.700776 -24.883818)
			(xy 416.786618 -24.900915) (xy 416.870363 -24.926367) (xy 416.951201 -24.959928) (xy 416.990022 -24.980138)
			(xy 417.001375 -24.985465) (xy 417.026421 -24.985465) (xy 417.037774 -24.980138) (xy 417.07665 -24.959926)
			(xy 417.15759 -24.926355) (xy 417.241437 -24.900898) (xy 417.327379 -24.883802) (xy 417.414585 -24.875232)
			(xy 417.458398 -24.874728) (xy 417.502213 -24.875221) (xy 417.589424 -24.883766) (xy 417.675371 -24.900853)
			(xy 417.75922 -24.926315) (xy 417.840155 -24.959906) (xy 417.879022 -24.980138) (xy 417.890375 -24.985465)
			(xy 417.915421 -24.985465) (xy 417.926774 -24.980138) (xy 417.96565 -24.959926) (xy 418.04659 -24.926355)
			(xy 418.130437 -24.900898) (xy 418.216379 -24.883802) (xy 418.303585 -24.875232) (xy 418.347398 -24.874728)
			(xy 418.397553 -24.875369) (xy 418.497233 -24.886577) (xy 418.54628 -24.89708) (xy 418.556796 -24.898879)
			(xy 418.577704 -24.894762) (xy 418.595164 -24.882547) (xy 418.601144 -24.873712) (xy 418.623031 -24.838312)
			(xy 418.672438 -24.771329) (xy 418.727885 -24.709253) (xy 418.788887 -24.652626) (xy 418.85491 -24.601944)
			(xy 418.925379 -24.55765) (xy 418.999676 -24.52013) (xy 419.077152 -24.489713) (xy 419.15713 -24.466664)
			(xy 419.238912 -24.451185) (xy 419.321781 -24.443412) (xy 419.363398 -24.442928) (xy 419.405357 -24.443406)
			(xy 419.488901 -24.451325) (xy 419.571328 -24.467074) (xy 419.651907 -24.490513) (xy 419.729921 -24.521434)
			(xy 419.804678 -24.559562) (xy 419.875513 -24.604559) (xy 419.941797 -24.656025) (xy 420.002941 -24.713502)
			(xy 420.058403 -24.77648) (xy 420.10769 -24.8444) (xy 420.150363 -24.916659) (xy 420.186044 -24.992614)
			(xy 420.214416 -25.071591) (xy 420.235227 -25.152888) (xy 420.242238 -25.19426) (xy 420.243856 -25.202602)
			(xy 420.25187 -25.21758) (xy 420.264317 -25.229141) (xy 420.271956 -25.232868) (xy 420.362126 -25.272746)
			(xy 420.38778 -25.27046) (xy 420.398702 -25.263348) (xy 420.435185 -25.23978) (xy 420.51189 -25.199026)
			(xy 420.592204 -25.165947) (xy 420.675362 -25.140859) (xy 420.76057 -25.124002) (xy 420.847016 -25.115535)
			(xy 420.890446 -25.115012) (xy 420.8907 -25.115012) (xy 420.933389 -25.115543) (xy 421.018375 -25.123714)
			(xy 421.102187 -25.139992) (xy 421.122484 -25.146) (xy 435.653688 -25.146) (xy 435.654241 -25.102511)
			(xy 435.662749 -25.015949) (xy 435.679663 -24.930631) (xy 435.704822 -24.84737) (xy 435.737987 -24.766962)
			(xy 435.77884 -24.690174) (xy 435.826991 -24.61774) (xy 435.881981 -24.55035) (xy 435.91226 -24.519128)
			(xy 435.912514 -24.518874) (xy 435.919089 -24.51149) (xy 435.926533 -24.493191) (xy 435.926992 -24.483314)
			(xy 435.926992 -24.411686) (xy 435.926571 -24.401803) (xy 435.919105 -24.383504) (xy 435.912514 -24.376126)
			(xy 435.91226 -24.375872) (xy 435.881999 -24.344633) (xy 435.827008 -24.277245) (xy 435.778855 -24.204813)
			(xy 435.738 -24.128028) (xy 435.704831 -24.047623) (xy 435.679666 -23.964365) (xy 435.662745 -23.879049)
			(xy 435.654229 -23.792489) (xy 435.653688 -23.749) (xy 435.654241 -23.705511) (xy 435.662749 -23.618949)
			(xy 435.679663 -23.533631) (xy 435.704822 -23.45037) (xy 435.737987 -23.369962) (xy 435.77884 -23.293174)
			(xy 435.826991 -23.22074) (xy 435.881981 -23.15335) (xy 435.91226 -23.122128) (xy 435.912514 -23.121874)
			(xy 435.919089 -23.11449) (xy 435.926533 -23.096191) (xy 435.926992 -23.086314) (xy 435.926992 -23.014686)
			(xy 435.926571 -23.004803) (xy 435.919105 -22.986504) (xy 435.912514 -22.979126) (xy 435.91226 -22.978872)
			(xy 435.881999 -22.947633) (xy 435.827008 -22.880245) (xy 435.778855 -22.807813) (xy 435.738 -22.731028)
			(xy 435.704831 -22.650623) (xy 435.679666 -22.567365) (xy 435.662745 -22.482049) (xy 435.654229 -22.395489)
			(xy 435.653688 -22.352) (xy 435.654192 -22.309639) (xy 435.662245 -22.225302) (xy 435.678279 -22.142112)
			(xy 435.702147 -22.060822) (xy 435.733635 -21.98217) (xy 435.772457 -21.906867) (xy 435.81826 -21.835595)
			(xy 435.870631 -21.768999) (xy 435.929096 -21.707684) (xy 435.993124 -21.652203) (xy 436.062136 -21.60306)
			(xy 436.135506 -21.5607) (xy 436.212571 -21.525505) (xy 436.292633 -21.497796) (xy 436.374966 -21.477822)
			(xy 436.458825 -21.465765) (xy 436.54345 -21.461734) (xy 436.628075 -21.465765) (xy 436.711934 -21.477822)
			(xy 436.794267 -21.497796) (xy 436.874329 -21.525505) (xy 436.951394 -21.5607) (xy 437.024764 -21.60306)
			(xy 437.093776 -21.652203) (xy 437.157804 -21.707684) (xy 437.216269 -21.768999) (xy 437.26864 -21.835595)
			(xy 437.314443 -21.906867) (xy 437.353265 -21.98217) (xy 437.384753 -22.060822) (xy 437.408621 -22.142112)
			(xy 437.424655 -22.225302) (xy 437.432708 -22.309639) (xy 437.433212 -22.352) (xy 437.432659 -22.395489)
			(xy 437.424151 -22.482051) (xy 437.407237 -22.567369) (xy 437.382078 -22.65063) (xy 437.348913 -22.731038)
			(xy 437.30806 -22.807826) (xy 437.259909 -22.88026) (xy 437.204919 -22.94765) (xy 437.17464 -22.978872)
			(xy 437.174386 -22.979126) (xy 437.167811 -22.98651) (xy 437.160367 -23.004809) (xy 437.159908 -23.014686)
			(xy 437.159908 -23.086314) (xy 437.160329 -23.096197) (xy 437.167795 -23.114496) (xy 437.174386 -23.121874)
			(xy 437.17464 -23.122128) (xy 437.202096 -23.150398) (xy 437.252481 -23.210999) (xy 437.297304 -23.275822)
			(xy 437.336214 -23.344358) (xy 437.368904 -23.41607) (xy 437.382412 -23.45309) (xy 437.385871 -23.461769)
			(xy 437.397984 -23.475981) (xy 437.414366 -23.484943) (xy 437.42356 -23.486618) (xy 437.46586 -23.492702)
			(xy 437.549147 -23.511861) (xy 437.630213 -23.53892) (xy 437.708311 -23.573628) (xy 437.782719 -23.615666)
			(xy 437.852753 -23.664647) (xy 437.917767 -23.720119) (xy 437.97716 -23.781571) (xy 438.030386 -23.848435)
			(xy 438.076954 -23.920096) (xy 438.116435 -23.995893) (xy 438.148464 -24.075127) (xy 438.172746 -24.157068)
			(xy 438.189058 -24.240959) (xy 438.197249 -24.326029) (xy 438.197752 -24.36876) (xy 438.197279 -24.410153)
			(xy 438.189575 -24.492579) (xy 438.174249 -24.573933) (xy 438.151432 -24.653512) (xy 438.121323 -24.730628)
			(xy 438.084182 -24.804614) (xy 438.040329 -24.87483) (xy 437.990144 -24.94067) (xy 437.934061 -25.001564)
			(xy 437.872564 -25.056986) (xy 437.806186 -25.106457) (xy 437.7355 -25.149548) (xy 437.661117 -25.185888)
			(xy 437.58368 -25.215162) (xy 437.503859 -25.237117) (xy 437.463184 -25.244806) (xy 437.452914 -25.247122)
			(xy 437.435391 -25.258751) (xy 437.423984 -25.276421) (xy 437.421782 -25.286716) (xy 437.414689 -25.327986)
			(xy 437.393721 -25.409064) (xy 437.365225 -25.487812) (xy 437.329455 -25.563534) (xy 437.286727 -25.635559)
			(xy 437.237419 -25.703249) (xy 437.181968 -25.766006) (xy 437.120864 -25.823274) (xy 437.054649 -25.874546)
			(xy 436.983908 -25.919368) (xy 436.909268 -25.957344) (xy 436.83139 -25.988136) (xy 436.750962 -26.011474)
			(xy 436.668697 -26.02715) (xy 436.585323 -26.035025) (xy 436.54345 -26.035508) (xy 436.502345 -26.03494)
			(xy 436.420486 -26.02736) (xy 436.339676 -26.012262) (xy 436.260602 -25.989773) (xy 436.183941 -25.960085)
			(xy 436.110345 -25.923451) (xy 436.040443 -25.880184) (xy 435.97483 -25.830654) (xy 435.914067 -25.775281)
			(xy 435.85867 -25.714539) (xy 435.809114 -25.648946) (xy 435.765819 -25.579061) (xy 435.729157 -25.505479)
			(xy 435.699439 -25.42883) (xy 435.676918 -25.349765) (xy 435.661788 -25.26896) (xy 435.654176 -25.187104)
			(xy 435.653688 -25.146) (xy 421.122484 -25.146) (xy 421.184054 -25.164225) (xy 421.263221 -25.196192)
			(xy 421.338961 -25.235598) (xy 421.410577 -25.28208) (xy 421.477409 -25.33521) (xy 421.538843 -25.3945)
			(xy 421.594313 -25.459404) (xy 421.643308 -25.529325) (xy 421.685377 -25.603618) (xy 421.720135 -25.681601)
			(xy 421.747259 -25.762556) (xy 421.766502 -25.845737) (xy 421.777685 -25.93038) (xy 421.7797 -25.973024)
			(xy 421.7797 -25.973278) (xy 421.780733 -25.984721) (xy 421.791565 -26.004954) (xy 421.800528 -26.01214)
			(xy 421.865044 -26.059384) (xy 421.874704 -26.065583) (xy 421.897257 -26.069674) (xy 421.908478 -26.067258)
			(xy 421.908732 -26.067258) (xy 421.94771 -26.056857) (xy 422.027062 -26.04229) (xy 422.107407 -26.03496)
			(xy 422.147746 -26.034492) (xy 422.148 -26.034492) (xy 422.190348 -26.034996) (xy 422.274662 -26.043047)
			(xy 422.357828 -26.059076) (xy 422.439095 -26.082937) (xy 422.517725 -26.114416) (xy 422.593006 -26.153227)
			(xy 422.664258 -26.199017) (xy 422.730834 -26.251373) (xy 422.792132 -26.309821) (xy 422.847597 -26.373831)
			(xy 422.896726 -26.442823) (xy 422.939075 -26.516173) (xy 422.974259 -26.593216) (xy 423.001961 -26.673255)
			(xy 423.021929 -26.755564) (xy 423.033982 -26.839399) (xy 423.038013 -26.924) (xy 423.033982 -27.008601)
			(xy 423.021929 -27.092436) (xy 423.001961 -27.174745) (xy 422.974259 -27.254784) (xy 422.939075 -27.331827)
			(xy 422.896726 -27.405177) (xy 422.847597 -27.474169) (xy 422.792132 -27.538179) (xy 422.730834 -27.596627)
			(xy 422.664258 -27.648983) (xy 422.593006 -27.694773) (xy 422.517725 -27.733584) (xy 422.439095 -27.765063)
			(xy 422.357828 -27.788924) (xy 422.274662 -27.804953) (xy 422.190348 -27.813004) (xy 422.148 -27.813508)
			(xy 422.105312 -27.812958) (xy 422.020327 -27.804787) (xy 421.936516 -27.78851) (xy 421.85465 -27.764277)
			(xy 421.775484 -27.732311) (xy 421.699744 -27.692906) (xy 421.628129 -27.646425) (xy 421.561297 -27.593296)
			(xy 421.499864 -27.534008) (xy 421.444394 -27.469105) (xy 421.395399 -27.399187) (xy 421.353328 -27.324895)
			(xy 421.31857 -27.246913) (xy 421.291445 -27.16596) (xy 421.272201 -27.082781) (xy 421.261016 -26.99814)
			(xy 421.259 -26.955496) (xy 421.259 -26.955242) (xy 421.257956 -26.943801) (xy 421.247132 -26.923568)
			(xy 421.238172 -26.91638) (xy 421.173656 -26.869136) (xy 421.163995 -26.862938) (xy 421.141442 -26.858846)
			(xy 421.130222 -26.861262) (xy 421.129968 -26.861262) (xy 421.090989 -26.871661) (xy 421.011638 -26.88623)
			(xy 420.931293 -26.89356) (xy 420.890954 -26.894028) (xy 420.8907 -26.894028) (xy 420.84874 -26.893589)
			(xy 420.765193 -26.88567) (xy 420.682764 -26.869919) (xy 420.602183 -26.846479) (xy 420.524168 -26.815556)
			(xy 420.44941 -26.777425) (xy 420.378574 -26.732425) (xy 420.312289 -26.680957) (xy 420.251144 -26.623476)
			(xy 420.195683 -26.560494) (xy 420.146397 -26.492571) (xy 420.103725 -26.420309) (xy 420.068046 -26.34435)
			(xy 420.039677 -26.26537) (xy 420.018869 -26.18407) (xy 420.01186 -26.142696) (xy 420.01021 -26.134361)
			(xy 420.002211 -26.119382) (xy 419.989776 -26.107818) (xy 419.982142 -26.104088) (xy 419.891972 -26.06421)
			(xy 419.866318 -26.066496) (xy 419.855396 -26.073608) (xy 419.8189 -26.097194) (xy 419.742154 -26.137962)
			(xy 419.661796 -26.171048) (xy 419.578593 -26.196134) (xy 419.49334 -26.212983) (xy 419.406849 -26.221433)
			(xy 419.363398 -26.221944) (xy 419.313244 -26.221288) (xy 419.213563 -26.21009) (xy 419.164516 -26.199592)
			(xy 419.153999 -26.197803) (xy 419.133095 -26.201919) (xy 419.115635 -26.214129) (xy 419.109652 -26.22296)
			(xy 419.086507 -26.260393) (xy 419.033879 -26.330942) (xy 418.974549 -26.395956) (xy 418.909094 -26.454799)
			(xy 418.87394 -26.481278) (xy 418.865367 -26.488188) (xy 418.854706 -26.507431) (xy 418.853366 -26.518362)
			(xy 418.849632 -26.559731) (xy 418.835547 -26.641595) (xy 418.813893 -26.72179) (xy 418.784857 -26.799618)
			(xy 418.748693 -26.874399) (xy 418.705715 -26.945484) (xy 418.656298 -27.012253) (xy 418.600872 -27.074125)
			(xy 418.539919 -27.13056) (xy 418.473972 -27.181068) (xy 418.403603 -27.225209) (xy 418.329426 -27.262598)
			(xy 418.252086 -27.292909) (xy 418.172258 -27.315879) (xy 418.090636 -27.331307) (xy 418.007932 -27.339059)
			(xy 417.966398 -27.339544) (xy 417.96589 -27.339544) (xy 417.922126 -27.339034) (xy 417.835019 -27.330458)
			(xy 417.749178 -27.313361) (xy 417.665432 -27.287907) (xy 417.584595 -27.254345) (xy 417.545774 -27.234134)
			(xy 417.534421 -27.228807) (xy 417.509375 -27.228807) (xy 417.498022 -27.234134) (xy 417.459145 -27.254345)
			(xy 417.378206 -27.287917) (xy 417.294359 -27.313374) (xy 417.208417 -27.33047) (xy 417.121211 -27.33904)
			(xy 417.077398 -27.339544) (xy 417.033583 -27.339044) (xy 416.946372 -27.330499) (xy 416.860426 -27.313414)
			(xy 416.776577 -27.287953) (xy 416.695642 -27.254365) (xy 416.656774 -27.234134) (xy 416.645421 -27.228807)
			(xy 416.620375 -27.228807) (xy 416.609022 -27.234134) (xy 416.570191 -27.254323) (xy 416.489349 -27.287865)
			(xy 416.405606 -27.313312) (xy 416.319769 -27.330418) (xy 416.232668 -27.339017) (xy 416.188906 -27.339544)
			(xy 416.188398 -27.339544) (xy 416.147291 -27.339089) (xy 416.065427 -27.331505) (xy 415.984611 -27.3164)
			(xy 415.905534 -27.293905) (xy 415.82887 -27.26421) (xy 415.755271 -27.227569) (xy 415.685367 -27.184295)
			(xy 415.619753 -27.134757) (xy 415.558989 -27.079377) (xy 415.503593 -27.018627) (xy 415.454037 -26.953026)
			(xy 415.410745 -26.883133) (xy 415.374085 -26.809545) (xy 415.34437 -26.732888) (xy 415.321854 -26.653816)
			(xy 415.306728 -26.573005) (xy 415.299121 -26.491143) (xy 415.298636 -26.450036) (xy 414.876176 -26.450036)
			(xy 414.876488 -26.47696) (xy 414.876488 -26.477468) (xy 414.875898 -26.52298) (xy 414.86657 -26.613525)
			(xy 414.848047 -26.702645) (xy 414.834832 -26.7462) (xy 414.831784 -26.755852) (xy 414.833308 -26.77541)
			(xy 414.87471 -26.857198) (xy 414.889696 -26.869898) (xy 414.899094 -26.8732) (xy 414.939229 -26.887382)
			(xy 415.01686 -26.922312) (xy 415.0908 -26.964498) (xy 415.160371 -27.013554) (xy 415.224939 -27.069031)
			(xy 415.283913 -27.130422) (xy 415.336752 -27.197165) (xy 415.382975 -27.26865) (xy 415.422157 -27.344224)
			(xy 415.453942 -27.423195) (xy 415.478038 -27.504841) (xy 415.494225 -27.588416) (xy 415.502355 -27.673154)
			(xy 415.502852 -27.715718) (xy 415.502852 -27.716226) (xy 415.502358 -27.759295) (xy 415.494009 -27.845028)
			(xy 415.477411 -27.929553) (xy 415.45272 -28.012077) (xy 415.420168 -28.091827) (xy 415.380058 -28.168058)
			(xy 415.332766 -28.240053) (xy 415.278737 -28.30714) (xy 415.218475 -28.36869) (xy 415.152545 -28.424126)
			(xy 415.081565 -28.472929) (xy 415.044128 -28.494228) (xy 415.034222 -28.499816) (xy 415.02076 -28.518612)
			(xy 415.003488 -28.620212) (xy 415.009838 -28.642056) (xy 415.017712 -28.650946) (xy 415.044607 -28.681516)
			(xy 415.093285 -28.746793) (xy 415.135795 -28.816245) (xy 415.171781 -28.889291) (xy 415.200942 -28.965319)
			(xy 415.223035 -29.043694) (xy 415.227966 -29.0703) (xy 415.53638 -29.0703) (xy 415.53638 -29.06903)
			(xy 415.536841 -29.030892) (xy 415.543626 -28.954917) (xy 415.557093 -28.879838) (xy 415.577137 -28.806242)
			(xy 415.589974 -28.770326) (xy 415.592737 -28.761777) (xy 415.592737 -28.743823) (xy 415.589974 -28.735274)
			(xy 415.577159 -28.699352) (xy 415.557133 -28.625752) (xy 415.543662 -28.550677) (xy 415.536848 -28.474707)
			(xy 415.53638 -28.43657) (xy 415.53638 -28.4353) (xy 415.536912 -28.392875) (xy 415.545229 -28.308434)
			(xy 415.561782 -28.225214) (xy 415.586413 -28.144018) (xy 415.618883 -28.065627) (xy 415.658881 -27.990795)
			(xy 415.706021 -27.920245) (xy 415.759848 -27.854655) (xy 415.819846 -27.794656) (xy 415.885435 -27.740828)
			(xy 415.955985 -27.693687) (xy 416.030816 -27.653688) (xy 416.109206 -27.621217) (xy 416.190402 -27.596585)
			(xy 416.273622 -27.580031) (xy 416.358063 -27.571713) (xy 416.400488 -27.571192) (xy 416.40125 -27.571192)
			(xy 416.445629 -27.571767) (xy 416.533919 -27.580881) (xy 416.620809 -27.598998) (xy 416.705384 -27.625927)
			(xy 416.786753 -27.661385) (xy 416.825684 -27.682698) (xy 416.833436 -27.686657) (xy 416.850576 -27.689617)
			(xy 416.867716 -27.686657) (xy 416.875468 -27.682698) (xy 416.914456 -27.661385) (xy 416.995923 -27.625906)
			(xy 417.080599 -27.598968) (xy 417.167591 -27.580853) (xy 417.255981 -27.571753) (xy 417.30041 -27.571192)
			(xy 417.344841 -27.571756) (xy 417.433238 -27.580824) (xy 417.520236 -27.598923) (xy 417.604915 -27.625862)
			(xy 417.686378 -27.661357) (xy 417.725352 -27.682698) (xy 417.733104 -27.686657) (xy 417.750244 -27.689617)
			(xy 417.767384 -27.686657) (xy 417.775136 -27.682698) (xy 417.814147 -27.661375) (xy 417.895661 -27.625875)
			(xy 417.980388 -27.598928) (xy 418.067433 -27.580819) (xy 418.155877 -27.571739) (xy 418.200332 -27.571192)
			(xy 418.244788 -27.571712) (xy 418.333237 -27.580784) (xy 418.420286 -27.598891) (xy 418.505015 -27.625841)
			(xy 418.586529 -27.661349) (xy 418.625528 -27.682698) (xy 418.63328 -27.686657) (xy 418.65042 -27.689617)
			(xy 418.66756 -27.686657) (xy 418.675312 -27.682698) (xy 418.714239 -27.661379) (xy 418.795612 -27.625931)
			(xy 418.880188 -27.599007) (xy 418.967078 -27.58089) (xy 419.055367 -27.57177) (xy 419.099746 -27.571192)
			(xy 419.100508 -27.571192) (xy 419.141194 -27.571638) (xy 419.222206 -27.579288) (xy 419.30214 -27.594521)
			(xy 419.380288 -27.6172) (xy 419.455958 -27.647126) (xy 419.528479 -27.684033) (xy 419.597209 -27.727594)
			(xy 419.661541 -27.777423) (xy 419.720902 -27.83308) (xy 419.774769 -27.89407) (xy 419.822663 -27.959855)
			(xy 419.864161 -28.02985) (xy 419.898895 -28.103437) (xy 419.926558 -28.179963) (xy 419.946903 -28.258751)
			(xy 419.959752 -28.339102) (xy 419.962838 -28.379674) (xy 419.962838 -28.379928) (xy 419.964167 -28.390377)
			(xy 419.973995 -28.40898) (xy 419.990414 -28.422136) (xy 420.00043 -28.425394) (xy 420.10965 -28.454604)
			(xy 420.139876 -28.44292) (xy 420.14902 -28.429204) (xy 420.173705 -28.392952) (xy 420.229109 -28.324957)
			(xy 420.290934 -28.262743) (xy 420.358582 -28.206916) (xy 420.431396 -28.158016) (xy 420.508668 -28.116519)
			(xy 420.589648 -28.082828) (xy 420.673551 -28.057269) (xy 420.759562 -28.04009) (xy 420.846845 -28.031459)
			(xy 420.8907 -28.030932) (xy 420.891462 -28.030932) (xy 420.931154 -28.031351) (xy 421.010222 -28.038429)
			(xy 421.088343 -28.052532) (xy 421.164895 -28.073547) (xy 421.239267 -28.101308) (xy 421.275256 -28.118054)
			(xy 421.285757 -28.122386) (xy 421.308443 -28.122386) (xy 421.318944 -28.118054) (xy 421.354937 -28.101321)
			(xy 421.429316 -28.073589) (xy 421.505868 -28.052586) (xy 421.583985 -28.038481) (xy 421.663048 -28.031384)
			(xy 421.702738 -28.030932) (xy 421.7035 -28.030932) (xy 421.744604 -28.031352) (xy 421.826462 -28.038938)
			(xy 421.907271 -28.054044) (xy 421.986341 -28.076542) (xy 422.062998 -28.10624) (xy 422.136588 -28.142885)
			(xy 422.206483 -28.186163) (xy 422.272086 -28.235706) (xy 422.332837 -28.291091) (xy 422.38822 -28.351845)
			(xy 422.43776 -28.41745) (xy 422.481035 -28.487347) (xy 422.517676 -28.560938) (xy 422.547371 -28.637597)
			(xy 422.569865 -28.716668) (xy 422.584968 -28.797477) (xy 422.59255 -28.879336) (xy 422.593008 -28.92044)
			(xy 422.593008 -28.920694) (xy 422.592454 -28.965433) (xy 422.583434 -29.054455) (xy 422.565525 -29.142122)
			(xy 422.538908 -29.227549) (xy 422.521888 -29.268928) (xy 422.518299 -29.278512) (xy 422.518314 -29.298961)
			(xy 422.521888 -29.308552) (xy 422.538914 -29.349928) (xy 422.565532 -29.435355) (xy 422.583435 -29.523024)
			(xy 422.592443 -29.612047) (xy 422.593008 -29.656786) (xy 422.593008 -29.65704) (xy 422.592572 -29.698143)
			(xy 422.584983 -29.779998) (xy 422.569874 -29.860804) (xy 422.547375 -29.939872) (xy 422.517676 -30.016526)
			(xy 422.481031 -30.090113) (xy 422.437753 -30.160005) (xy 422.388211 -30.225606) (xy 422.332827 -30.286355)
			(xy 422.272075 -30.341736) (xy 422.206472 -30.391275) (xy 422.136578 -30.43455) (xy 422.062989 -30.471192)
			(xy 421.986334 -30.500887) (xy 421.907266 -30.523384) (xy 421.826459 -30.538489) (xy 421.744603 -30.546073)
			(xy 421.7035 -30.546548) (xy 421.702738 -30.546548) (xy 421.663046 -30.546131) (xy 421.583978 -30.539053)
			(xy 421.505857 -30.524949) (xy 421.429305 -30.503934) (xy 421.354933 -30.476173) (xy 421.318944 -30.459426)
			(xy 421.308443 -30.455094) (xy 421.285757 -30.455094) (xy 421.275256 -30.459426) (xy 421.239262 -30.476158)
			(xy 421.164884 -30.50389) (xy 421.088332 -30.524893) (xy 421.010215 -30.538999) (xy 420.931152 -30.546096)
			(xy 420.891462 -30.546548) (xy 420.8907 -30.546548) (xy 420.849599 -30.546033) (xy 420.767747 -30.538449)
			(xy 420.686944 -30.523345) (xy 420.607879 -30.500849) (xy 420.531227 -30.471155) (xy 420.457642 -30.434515)
			(xy 420.387751 -30.391242) (xy 420.322151 -30.341705) (xy 420.261401 -30.286327) (xy 420.20602 -30.22558)
			(xy 420.15648 -30.159982) (xy 420.113204 -30.090093) (xy 420.076561 -30.01651) (xy 420.046863 -29.939859)
			(xy 420.024364 -29.860795) (xy 420.009257 -29.779993) (xy 420.001668 -29.698141) (xy 420.001192 -29.65704)
			(xy 420.001192 -29.656786) (xy 420.001773 -29.612048) (xy 420.010785 -29.523027) (xy 420.028686 -29.435359)
			(xy 420.055296 -29.349931) (xy 420.072312 -29.308552) (xy 420.075855 -29.298955) (xy 420.07587 -29.278518)
			(xy 420.072312 -29.268928) (xy 420.06628 -29.254625) (xy 420.055102 -29.225662) (xy 420.04996 -29.211016)
			(xy 420.047674 -29.205428) (xy 420.042591 -29.196362) (xy 420.026808 -29.182879) (xy 420.006979 -29.176738)
			(xy 419.986338 -29.178941) (xy 419.968251 -29.189127) (xy 419.955668 -29.205637) (xy 419.952678 -29.215588)
			(xy 419.951916 -29.21889) (xy 419.944515 -29.258485) (xy 419.923324 -29.336204) (xy 419.894993 -29.411613)
			(xy 419.859768 -29.484059) (xy 419.817955 -29.552914) (xy 419.769916 -29.617578) (xy 419.716069 -29.677493)
			(xy 419.65688 -29.732136) (xy 419.592863 -29.781035) (xy 419.524574 -29.823765) (xy 419.452605 -29.859956)
			(xy 419.377581 -29.889293) (xy 419.300153 -29.911521) (xy 419.220992 -29.926448) (xy 419.140786 -29.933945)
			(xy 419.100508 -29.934408) (xy 419.099746 -29.934408) (xy 419.055367 -29.933835) (xy 418.967077 -29.92472)
			(xy 418.880187 -29.906603) (xy 418.795612 -29.879673) (xy 418.714243 -29.844215) (xy 418.675312 -29.822902)
			(xy 418.66756 -29.818943) (xy 418.65042 -29.815983) (xy 418.63328 -29.818943) (xy 418.625528 -29.822902)
			(xy 418.586524 -29.84424) (xy 418.505008 -29.879737) (xy 418.420279 -29.906681) (xy 418.333232 -29.924786)
			(xy 418.244787 -29.933863) (xy 418.200332 -29.934408) (xy 418.155876 -29.93386) (xy 418.067429 -29.924794)
			(xy 417.98038 -29.906694) (xy 417.89565 -29.87975) (xy 417.814135 -29.844248) (xy 417.775136 -29.822902)
			(xy 417.767384 -29.818943) (xy 417.750244 -29.815983) (xy 417.733104 -29.818943) (xy 417.725352 -29.822902)
			(xy 417.686381 -29.844246) (xy 417.604909 -29.879719) (xy 417.520229 -29.906651) (xy 417.433233 -29.924759)
			(xy 417.34484 -29.933851) (xy 417.30041 -29.934408) (xy 417.255978 -29.933879) (xy 417.16758 -29.924804)
			(xy 417.080582 -29.906696) (xy 416.995903 -29.879749) (xy 416.914441 -29.844247) (xy 416.875468 -29.822902)
			(xy 416.867716 -29.818943) (xy 416.850576 -29.815983) (xy 416.833436 -29.818943) (xy 416.825684 -29.822902)
			(xy 416.786758 -29.844223) (xy 416.705385 -29.87967) (xy 416.620808 -29.906594) (xy 416.533918 -29.924711)
			(xy 416.445629 -29.93383) (xy 416.40125 -29.934408) (xy 416.400488 -29.934408) (xy 416.358062 -29.933899)
			(xy 416.27362 -29.925581) (xy 416.1904 -29.909026) (xy 416.109202 -29.884394) (xy 416.030811 -29.851923)
			(xy 415.955979 -29.811923) (xy 415.885428 -29.764782) (xy 415.819838 -29.710952) (xy 415.759839 -29.650953)
			(xy 415.706011 -29.585362) (xy 415.658871 -29.514811) (xy 415.618872 -29.439979) (xy 415.586402 -29.361586)
			(xy 415.561771 -29.280389) (xy 415.545217 -29.197168) (xy 415.5369 -29.112726) (xy 415.53638 -29.0703)
			(xy 415.227966 -29.0703) (xy 415.237875 -29.123759) (xy 415.245337 -29.204846) (xy 415.245804 -29.24556)
			(xy 415.2453 -29.287921) (xy 415.237247 -29.372258) (xy 415.221213 -29.455448) (xy 415.197345 -29.536738)
			(xy 415.165857 -29.61539) (xy 415.127035 -29.690693) (xy 415.081232 -29.761965) (xy 415.028861 -29.828561)
			(xy 414.970396 -29.889876) (xy 414.906368 -29.945357) (xy 414.837356 -29.9945) (xy 414.763986 -30.03686)
			(xy 414.686921 -30.072055) (xy 414.606859 -30.099764) (xy 414.524526 -30.119738) (xy 414.440667 -30.131795)
			(xy 414.356042 -30.135827) (xy 414.271417 -30.131795) (xy 414.187558 -30.119738) (xy 414.105225 -30.099764)
			(xy 414.025163 -30.072055) (xy 413.948098 -30.03686) (xy 413.874728 -29.9945) (xy 413.805716 -29.945357)
			(xy 413.741688 -29.889876) (xy 413.683223 -29.828561) (xy 413.630852 -29.761965) (xy 413.585049 -29.690693)
			(xy 413.546227 -29.61539) (xy 413.514739 -29.536738) (xy 413.490871 -29.455448) (xy 413.474837 -29.372258)
			(xy 413.466784 -29.287921) (xy 413.46628 -29.24556) (xy 413.466797 -29.202463) (xy 413.475136 -29.116674)
			(xy 413.49173 -29.032094) (xy 413.516426 -28.949514) (xy 413.54899 -28.869709) (xy 413.589119 -28.793427)
			(xy 413.636436 -28.721383) (xy 413.690497 -28.654251) (xy 413.750797 -28.592662) (xy 413.816769 -28.537192)
			(xy 413.887796 -28.488361) (xy 413.925258 -28.46705) (xy 413.935164 -28.461462) (xy 413.948626 -28.442666)
			(xy 413.963866 -28.352496) (xy 413.965109 -28.34115) (xy 413.958789 -28.319254) (xy 413.951674 -28.310332)
			(xy 413.924814 -28.27974) (xy 413.876171 -28.214454) (xy 413.833695 -28.144997) (xy 413.79774 -28.071951)
			(xy 413.768609 -27.995925) (xy 413.746545 -27.917557) (xy 413.731731 -27.837501) (xy 413.724292 -27.756426)
			(xy 413.723836 -27.715718) (xy 413.723836 -27.714702) (xy 413.724291 -27.674888) (xy 413.731455 -27.595582)
			(xy 413.74568 -27.517235) (xy 413.75584 -27.478736) (xy 413.75584 -27.478482) (xy 413.758071 -27.468243)
			(xy 413.755057 -27.447527) (xy 413.749998 -27.43835) (xy 413.71012 -27.37485) (xy 413.704034 -27.366119)
			(xy 413.686443 -27.354179) (xy 413.676084 -27.351736) (xy 413.636452 -27.344104) (xy 413.558658 -27.322582)
			(xy 413.483134 -27.294101) (xy 413.410502 -27.258893) (xy 413.341358 -27.21725) (xy 413.308546 -27.193748)
			(xy 413.30068 -27.18844) (xy 413.282369 -27.183514) (xy 413.263524 -27.185614) (xy 413.254952 -27.189684)
			(xy 413.216868 -27.20895) (xy 413.137733 -27.240932) (xy 413.0559 -27.265194) (xy 412.972121 -27.281512)
			(xy 412.887164 -27.289737) (xy 412.844488 -27.290268) (xy 412.84398 -27.290268) (xy 412.80163 -27.289843)
			(xy 412.717314 -27.28179) (xy 412.634146 -27.265759) (xy 412.552877 -27.241895) (xy 412.474246 -27.210414)
			(xy 412.398962 -27.171601) (xy 412.327709 -27.125808) (xy 412.261131 -27.07345) (xy 412.199832 -27.015)
			(xy 412.144366 -26.950987) (xy 412.095236 -26.881993) (xy 412.052887 -26.80864) (xy 412.017702 -26.731595)
			(xy 411.99 -26.651553) (xy 411.970031 -26.569241) (xy 411.957978 -26.485404) (xy 411.953947 -26.4008)
			(xy 379.811377 -26.4008) (xy 379.813577 -26.408538) (xy 379.828665 -26.489361) (xy 379.836231 -26.571232)
			(xy 379.83668 -26.612342) (xy 379.836079 -26.658737) (xy 379.82644 -26.751025) (xy 379.807249 -26.841809)
			(xy 379.778716 -26.930103) (xy 379.76048 -26.972768) (xy 379.756651 -26.982703) (xy 379.756667 -27.003973)
			(xy 379.76048 -27.013916) (xy 379.778737 -27.056573) (xy 379.807278 -27.144867) (xy 379.826468 -27.235654)
			(xy 379.836097 -27.327946) (xy 379.83668 -27.374342) (xy 379.836079 -27.420737) (xy 379.82644 -27.513025)
			(xy 379.807249 -27.603809) (xy 379.778716 -27.692103) (xy 379.76048 -27.734768) (xy 379.756651 -27.744703)
			(xy 379.756667 -27.765973) (xy 379.76048 -27.775916) (xy 379.778737 -27.818573) (xy 379.807278 -27.906867)
			(xy 379.826468 -27.997654) (xy 379.836097 -28.089946) (xy 379.83668 -28.136342) (xy 379.836079 -28.182737)
			(xy 379.82644 -28.275025) (xy 379.816721 -28.321) (xy 386.358892 -28.321) (xy 386.359378 -28.27822)
			(xy 386.3676 -28.193056) (xy 386.383959 -28.109075) (xy 386.408303 -28.027052) (xy 386.440408 -27.947744)
			(xy 386.479976 -27.871883) (xy 386.526644 -27.800171) (xy 386.579979 -27.73327) (xy 386.63949 -27.671797)
			(xy 386.704626 -27.616319) (xy 386.774787 -27.567351) (xy 386.849324 -27.525342) (xy 386.927549 -27.490682)
			(xy 386.967984 -27.476704) (xy 386.9768 -27.473333) (xy 386.991321 -27.461296) (xy 387.000524 -27.444833)
			(xy 387.002274 -27.435556) (xy 387.008633 -27.393572) (xy 387.028401 -27.310984) (xy 387.055948 -27.230655)
			(xy 387.091023 -27.153316) (xy 387.133307 -27.07967) (xy 387.182415 -27.010388) (xy 387.237901 -26.9461)
			(xy 387.299259 -26.88739) (xy 387.365931 -26.834794) (xy 387.437311 -26.788788) (xy 387.512749 -26.749793)
			(xy 387.59156 -26.718162) (xy 387.673025 -26.694184) (xy 387.756405 -26.678076) (xy 387.840939 -26.669985)
			(xy 387.8834 -26.669492) (xy 387.924502 -26.669967) (xy 388.006357 -26.677552) (xy 388.087162 -26.692657)
			(xy 388.166229 -26.715153) (xy 388.242883 -26.744849) (xy 388.31647 -26.781491) (xy 388.386362 -26.824766)
			(xy 388.451963 -26.874306) (xy 388.512713 -26.929687) (xy 388.568094 -26.990437) (xy 388.617634 -27.056038)
			(xy 388.660909 -27.12593) (xy 388.697551 -27.199517) (xy 388.727247 -27.276171) (xy 388.749743 -27.355238)
			(xy 388.764848 -27.436043) (xy 388.772433 -27.517898) (xy 388.772908 -27.559) (xy 388.772422 -27.60178)
			(xy 388.7642 -27.686944) (xy 388.747841 -27.770925) (xy 388.723497 -27.852948) (xy 388.691392 -27.932256)
			(xy 388.651824 -28.008117) (xy 388.605156 -28.079829) (xy 388.551821 -28.14673) (xy 388.49231 -28.208203)
			(xy 388.427174 -28.263681) (xy 388.357013 -28.312649) (xy 388.282476 -28.354658) (xy 388.204251 -28.389318)
			(xy 388.163816 -28.403296) (xy 388.155 -28.406667) (xy 388.140479 -28.418704) (xy 388.131276 -28.435167)
			(xy 388.129526 -28.444444) (xy 388.123167 -28.486428) (xy 388.103399 -28.569016) (xy 388.075852 -28.649345)
			(xy 388.040777 -28.726684) (xy 387.998493 -28.80033) (xy 387.949385 -28.869612) (xy 387.893899 -28.9339)
			(xy 387.832541 -28.99261) (xy 387.765869 -29.045206) (xy 387.694489 -29.091212) (xy 387.619051 -29.130207)
			(xy 387.54024 -29.161838) (xy 387.458775 -29.185816) (xy 387.375395 -29.201924) (xy 387.290861 -29.210015)
			(xy 387.2484 -29.210508) (xy 387.207298 -29.210033) (xy 387.125443 -29.202448) (xy 387.044638 -29.187343)
			(xy 386.965571 -29.164847) (xy 386.888917 -29.135151) (xy 386.81533 -29.098509) (xy 386.745438 -29.055234)
			(xy 386.679837 -29.005694) (xy 386.619087 -28.950313) (xy 386.563706 -28.889563) (xy 386.514166 -28.823962)
			(xy 386.470891 -28.75407) (xy 386.434249 -28.680483) (xy 386.404553 -28.603829) (xy 386.382057 -28.524762)
			(xy 386.366952 -28.443957) (xy 386.359367 -28.362102) (xy 386.358892 -28.321) (xy 379.816721 -28.321)
			(xy 379.807249 -28.365809) (xy 379.778716 -28.454103) (xy 379.76048 -28.496768) (xy 379.756651 -28.506703)
			(xy 379.756667 -28.527973) (xy 379.76048 -28.537916) (xy 379.778714 -28.580514) (xy 379.807229 -28.668683)
			(xy 379.826418 -28.75934) (xy 379.836074 -28.851501) (xy 379.83668 -28.897834) (xy 379.83668 -28.898342)
			(xy 379.836228 -28.939449) (xy 379.82864 -29.021312) (xy 379.813532 -29.102126) (xy 379.791035 -29.181202)
			(xy 379.76347 -29.252361) (xy 404.222962 -29.252361) (xy 404.222962 -29.167639) (xy 404.231015 -29.083302)
			(xy 404.247049 -29.000112) (xy 404.270917 -28.918822) (xy 404.302405 -28.84017) (xy 404.341227 -28.764867)
			(xy 404.38703 -28.693595) (xy 404.439401 -28.626999) (xy 404.497866 -28.565684) (xy 404.561894 -28.510203)
			(xy 404.630906 -28.46106) (xy 404.704276 -28.4187) (xy 404.781341 -28.383505) (xy 404.861403 -28.355796)
			(xy 404.943736 -28.335822) (xy 405.027595 -28.323765) (xy 405.11222 -28.319734) (xy 405.196845 -28.323765)
			(xy 405.280704 -28.335822) (xy 405.363037 -28.355796) (xy 405.443099 -28.383505) (xy 405.520164 -28.4187)
			(xy 405.593534 -28.46106) (xy 405.662546 -28.510203) (xy 405.726574 -28.565684) (xy 405.785039 -28.626999)
			(xy 405.83741 -28.693595) (xy 405.883213 -28.764867) (xy 405.922035 -28.84017) (xy 405.953523 -28.918822)
			(xy 405.977391 -29.000112) (xy 405.993425 -29.083302) (xy 406.001478 -29.167639) (xy 406.001982 -29.21)
			(xy 406.001478 -29.252361) (xy 405.993425 -29.336698) (xy 405.977391 -29.419888) (xy 405.953523 -29.501178)
			(xy 405.922035 -29.57983) (xy 405.883213 -29.655133) (xy 405.83741 -29.726405) (xy 405.785039 -29.793001)
			(xy 405.726574 -29.854316) (xy 405.662546 -29.909797) (xy 405.593534 -29.95894) (xy 405.520164 -30.0013)
			(xy 405.443099 -30.036495) (xy 405.363037 -30.064204) (xy 405.280704 -30.084178) (xy 405.196845 -30.096235)
			(xy 405.11222 -30.100267) (xy 405.027595 -30.096235) (xy 404.943736 -30.084178) (xy 404.861403 -30.064204)
			(xy 404.781341 -30.036495) (xy 404.704276 -30.0013) (xy 404.630906 -29.95894) (xy 404.561894 -29.909797)
			(xy 404.497866 -29.854316) (xy 404.439401 -29.793001) (xy 404.38703 -29.726405) (xy 404.341227 -29.655133)
			(xy 404.302405 -29.57983) (xy 404.270917 -29.501178) (xy 404.247049 -29.419888) (xy 404.231015 -29.336698)
			(xy 404.222962 -29.252361) (xy 379.76347 -29.252361) (xy 379.761338 -29.257865) (xy 379.724697 -29.331462)
			(xy 379.681422 -29.401365) (xy 379.631884 -29.466978) (xy 379.576504 -29.527741) (xy 379.515755 -29.583137)
			(xy 379.450155 -29.632692) (xy 379.380263 -29.675985) (xy 379.306675 -29.712645) (xy 379.23002 -29.742362)
			(xy 379.15095 -29.76488) (xy 379.07014 -29.780008) (xy 378.988279 -29.787617) (xy 378.947172 -29.788104)
			(xy 378.90077 -29.787489) (xy 378.808472 -29.777796) (xy 378.717686 -29.758539) (xy 378.629402 -29.729927)
			(xy 378.586746 -29.71165) (xy 378.576804 -29.707844) (xy 378.55554 -29.707844) (xy 378.545598 -29.71165)
			(xy 378.502941 -29.72992) (xy 378.414651 -29.758512) (xy 378.323867 -29.777767) (xy 378.231573 -29.787476)
			(xy 378.185172 -29.788104) (xy 378.13877 -29.787489) (xy 378.046472 -29.777796) (xy 377.955686 -29.758539)
			(xy 377.867402 -29.729927) (xy 377.824746 -29.71165) (xy 377.814804 -29.707844) (xy 377.79354 -29.707844)
			(xy 377.783598 -29.71165) (xy 377.740941 -29.72992) (xy 377.652651 -29.758512) (xy 377.561867 -29.777767)
			(xy 377.469573 -29.787476) (xy 377.423172 -29.788104) (xy 377.37677 -29.787489) (xy 377.284472 -29.777796)
			(xy 377.193686 -29.758539) (xy 377.105402 -29.729927) (xy 377.062746 -29.71165) (xy 377.052804 -29.707844)
			(xy 377.03154 -29.707844) (xy 377.021598 -29.71165) (xy 376.978941 -29.72992) (xy 376.890651 -29.758512)
			(xy 376.799867 -29.777767) (xy 376.707573 -29.787476) (xy 376.661172 -29.788104) (xy 376.620061 -29.787674)
			(xy 376.538189 -29.780084) (xy 376.457368 -29.764971) (xy 376.378286 -29.742463) (xy 376.301619 -29.712754)
			(xy 376.22802 -29.676096) (xy 376.158118 -29.632803) (xy 376.09251 -29.583244) (xy 376.031756 -29.527842)
			(xy 375.976373 -29.467069) (xy 375.926835 -29.401445) (xy 375.883564 -29.33153) (xy 375.84693 -29.25792)
			(xy 375.817246 -29.181243) (xy 375.794764 -29.102153) (xy 375.779677 -29.021327) (xy 375.772113 -28.939453)
			(xy 375.771664 -28.898342) (xy 367.919254 -28.898342) (xy 370.501926 -31.481014) (xy 370.502434 -31.481522)
			(xy 370.509813 -31.488111) (xy 370.528112 -31.495573) (xy 370.537994 -31.496) (xy 389.560308 -31.496)
			(xy 389.593568 -31.496522) (xy 389.659518 -31.50521) (xy 389.723768 -31.522436) (xy 389.785218 -31.547906)
			(xy 389.842816 -31.581183) (xy 389.895575 -31.621696) (xy 389.919464 -31.644844) (xy 390.320981 -32.046361)
			(xy 404.774142 -32.046361) (xy 404.774142 -31.961639) (xy 404.782195 -31.877302) (xy 404.798229 -31.794112)
			(xy 404.822097 -31.712822) (xy 404.853585 -31.63417) (xy 404.892407 -31.558867) (xy 404.93821 -31.487595)
			(xy 404.990581 -31.420999) (xy 405.049046 -31.359684) (xy 405.113074 -31.304203) (xy 405.182086 -31.25506)
			(xy 405.255456 -31.2127) (xy 405.332521 -31.177505) (xy 405.412583 -31.149796) (xy 405.494916 -31.129822)
			(xy 405.578775 -31.117765) (xy 405.6634 -31.113734) (xy 405.748025 -31.117765) (xy 405.831884 -31.129822)
			(xy 405.914217 -31.149796) (xy 405.994279 -31.177505) (xy 406.071344 -31.2127) (xy 406.144714 -31.25506)
			(xy 406.213726 -31.304203) (xy 406.277754 -31.359684) (xy 406.336219 -31.420999) (xy 406.38859 -31.487595)
			(xy 406.434393 -31.558867) (xy 406.473215 -31.63417) (xy 406.504703 -31.712822) (xy 406.515619 -31.75)
			(xy 409.091273 -31.75) (xy 409.095372 -31.664659) (xy 409.107631 -31.580104) (xy 409.127938 -31.497113)
			(xy 409.156106 -31.416451) (xy 409.191875 -31.33886) (xy 409.234915 -31.265053) (xy 409.284832 -31.195712)
			(xy 409.312618 -31.16326) (xy 409.318383 -31.156171) (xy 409.324895 -31.139114) (xy 409.325318 -31.129986)
			(xy 409.325318 -31.100014) (xy 409.324884 -31.090891) (xy 409.318364 -31.073841) (xy 409.312618 -31.06674)
			(xy 409.284832 -31.034288) (xy 409.234915 -30.964947) (xy 409.191875 -30.89114) (xy 409.156106 -30.813549)
			(xy 409.127938 -30.732887) (xy 409.107631 -30.649896) (xy 409.095372 -30.565341) (xy 409.091273 -30.48)
			(xy 409.095372 -30.394659) (xy 409.107631 -30.310104) (xy 409.127938 -30.227113) (xy 409.156106 -30.146451)
			(xy 409.191875 -30.06886) (xy 409.234915 -29.995053) (xy 409.284832 -29.925712) (xy 409.312618 -29.89326)
			(xy 409.318383 -29.886171) (xy 409.324895 -29.869114) (xy 409.325318 -29.859986) (xy 409.325318 -29.830014)
			(xy 409.324884 -29.820891) (xy 409.318364 -29.803841) (xy 409.312618 -29.79674) (xy 409.284832 -29.764288)
			(xy 409.234915 -29.694947) (xy 409.191875 -29.62114) (xy 409.156106 -29.543549) (xy 409.127938 -29.462887)
			(xy 409.107631 -29.379896) (xy 409.095372 -29.295341) (xy 409.091273 -29.21) (xy 409.095372 -29.124659)
			(xy 409.107631 -29.040104) (xy 409.127938 -28.957113) (xy 409.156106 -28.876451) (xy 409.191875 -28.79886)
			(xy 409.234915 -28.725053) (xy 409.284832 -28.655712) (xy 409.312618 -28.62326) (xy 409.318383 -28.616171)
			(xy 409.324895 -28.599114) (xy 409.325318 -28.589986) (xy 409.325318 -28.560014) (xy 409.324884 -28.550891)
			(xy 409.318364 -28.533841) (xy 409.312618 -28.52674) (xy 409.28656 -28.496326) (xy 409.239374 -28.431608)
			(xy 409.198198 -28.362908) (xy 409.163367 -28.290784) (xy 409.135163 -28.21582) (xy 409.113814 -28.138623)
			(xy 409.099494 -28.059819) (xy 409.092319 -27.980047) (xy 409.091892 -27.94) (xy 409.092396 -27.897652)
			(xy 409.100447 -27.813338) (xy 409.116476 -27.730172) (xy 409.140337 -27.648905) (xy 409.171816 -27.570275)
			(xy 409.210627 -27.494994) (xy 409.256417 -27.423742) (xy 409.308773 -27.357166) (xy 409.367221 -27.295868)
			(xy 409.431231 -27.240403) (xy 409.500223 -27.191274) (xy 409.573573 -27.148925) (xy 409.650616 -27.113741)
			(xy 409.730655 -27.086039) (xy 409.812964 -27.066071) (xy 409.896799 -27.054018) (xy 409.9814 -27.049988)
			(xy 410.066001 -27.054018) (xy 410.149836 -27.066071) (xy 410.232145 -27.086039) (xy 410.312184 -27.113741)
			(xy 410.389227 -27.148925) (xy 410.462577 -27.191274) (xy 410.531569 -27.240403) (xy 410.595579 -27.295868)
			(xy 410.654027 -27.357166) (xy 410.706383 -27.423742) (xy 410.752173 -27.494994) (xy 410.790984 -27.570275)
			(xy 410.822463 -27.648905) (xy 410.846324 -27.730172) (xy 410.862353 -27.813338) (xy 410.870404 -27.897652)
			(xy 410.870908 -27.94) (xy 410.870493 -27.980047) (xy 410.863298 -28.059816) (xy 410.848964 -28.138616)
			(xy 410.82761 -28.21581) (xy 410.799406 -28.290773) (xy 410.764582 -28.3629) (xy 410.723418 -28.431605)
			(xy 410.676249 -28.496335) (xy 410.650182 -28.52674) (xy 410.644417 -28.533829) (xy 410.637905 -28.550886)
			(xy 410.637482 -28.560014) (xy 410.637482 -28.589986) (xy 410.637916 -28.599109) (xy 410.644436 -28.616159)
			(xy 410.650182 -28.62326) (xy 410.677968 -28.655712) (xy 410.727885 -28.725053) (xy 410.770925 -28.79886)
			(xy 410.806694 -28.876451) (xy 410.834862 -28.957113) (xy 410.855169 -29.040104) (xy 410.867428 -29.124659)
			(xy 410.871527 -29.21) (xy 410.867428 -29.295341) (xy 410.855169 -29.379896) (xy 410.834862 -29.462887)
			(xy 410.806694 -29.543549) (xy 410.770925 -29.62114) (xy 410.727885 -29.694947) (xy 410.677968 -29.764288)
			(xy 410.650182 -29.79674) (xy 410.644417 -29.803829) (xy 410.637905 -29.820886) (xy 410.637482 -29.830014)
			(xy 410.637482 -29.859986) (xy 410.637916 -29.869109) (xy 410.644436 -29.886159) (xy 410.650182 -29.89326)
			(xy 410.677968 -29.925712) (xy 410.727885 -29.995053) (xy 410.770925 -30.06886) (xy 410.806694 -30.146451)
			(xy 410.829151 -30.21076) (xy 411.173168 -30.21076) (xy 411.173672 -30.168439) (xy 411.181747 -30.084182)
			(xy 411.19779 -30.001073) (xy 411.221657 -29.919865) (xy 411.253132 -29.841292) (xy 411.29193 -29.766064)
			(xy 411.314392 -29.730192) (xy 411.319291 -29.721815) (xy 411.322935 -29.702766) (xy 411.319266 -29.683722)
			(xy 411.314392 -29.675328) (xy 411.291934 -29.639455) (xy 411.253155 -29.564221) (xy 411.221693 -29.485645)
			(xy 411.19783 -29.404438) (xy 411.181783 -29.321333) (xy 411.173696 -29.23708) (xy 411.173168 -29.19476)
			(xy 411.173672 -29.152399) (xy 411.181725 -29.068062) (xy 411.197759 -28.984872) (xy 411.221627 -28.903582)
			(xy 411.253115 -28.82493) (xy 411.291937 -28.749627) (xy 411.33774 -28.678355) (xy 411.390111 -28.611759)
			(xy 411.448576 -28.550444) (xy 411.512604 -28.494963) (xy 411.581616 -28.44582) (xy 411.654986 -28.40346)
			(xy 411.732051 -28.368265) (xy 411.812113 -28.340556) (xy 411.894446 -28.320582) (xy 411.978305 -28.308525)
			(xy 412.06293 -28.304494) (xy 412.147555 -28.308525) (xy 412.231414 -28.320582) (xy 412.313747 -28.340556)
			(xy 412.393809 -28.368265) (xy 412.470874 -28.40346) (xy 412.544244 -28.44582) (xy 412.613256 -28.494963)
			(xy 412.677284 -28.550444) (xy 412.735749 -28.611759) (xy 412.78812 -28.678355) (xy 412.833923 -28.749627)
			(xy 412.872745 -28.82493) (xy 412.904233 -28.903582) (xy 412.928101 -28.984872) (xy 412.944135 -29.068062)
			(xy 412.952188 -29.152399) (xy 412.952692 -29.19476) (xy 412.952189 -29.237081) (xy 412.944113 -29.321338)
			(xy 412.928069 -29.404446) (xy 412.904202 -29.485655) (xy 412.872727 -29.564228) (xy 412.83393 -29.639456)
			(xy 412.811468 -29.675328) (xy 412.806638 -29.683739) (xy 412.802975 -29.702766) (xy 412.806613 -29.721798)
			(xy 412.811468 -29.730192) (xy 412.83393 -29.766063) (xy 412.872709 -29.841297) (xy 412.904171 -29.919873)
			(xy 412.928034 -30.001081) (xy 412.94408 -30.084186) (xy 412.952165 -30.16844) (xy 412.952692 -30.21076)
			(xy 412.952188 -30.253121) (xy 412.944135 -30.337458) (xy 412.928101 -30.420648) (xy 412.904233 -30.501938)
			(xy 412.872745 -30.58059) (xy 412.833923 -30.655893) (xy 412.78812 -30.727165) (xy 412.735749 -30.793761)
			(xy 412.677284 -30.855076) (xy 412.613256 -30.910557) (xy 412.544244 -30.9597) (xy 412.470874 -31.00206)
			(xy 412.393809 -31.037255) (xy 412.313747 -31.064964) (xy 412.231414 -31.084938) (xy 412.147555 -31.096995)
			(xy 412.06293 -31.101027) (xy 411.978305 -31.096995) (xy 411.894446 -31.084938) (xy 411.812113 -31.064964)
			(xy 411.732051 -31.037255) (xy 411.654986 -31.00206) (xy 411.581616 -30.9597) (xy 411.512604 -30.910557)
			(xy 411.448576 -30.855076) (xy 411.390111 -30.793761) (xy 411.33774 -30.727165) (xy 411.291937 -30.655893)
			(xy 411.253115 -30.58059) (xy 411.221627 -30.501938) (xy 411.197759 -30.420648) (xy 411.181725 -30.337458)
			(xy 411.173672 -30.253121) (xy 411.173168 -30.21076) (xy 410.829151 -30.21076) (xy 410.834862 -30.227113)
			(xy 410.855169 -30.310104) (xy 410.867428 -30.394659) (xy 410.871527 -30.48) (xy 410.867428 -30.565341)
			(xy 410.855169 -30.649896) (xy 410.834862 -30.732887) (xy 410.806694 -30.813549) (xy 410.770925 -30.89114)
			(xy 410.727885 -30.964947) (xy 410.677968 -31.034288) (xy 410.650182 -31.06674) (xy 410.644417 -31.073829)
			(xy 410.637905 -31.090886) (xy 410.637482 -31.100014) (xy 410.637482 -31.129986) (xy 410.637916 -31.139109)
			(xy 410.644436 -31.156159) (xy 410.650182 -31.16326) (xy 410.677968 -31.195712) (xy 410.705621 -31.234126)
			(xy 416.160966 -31.234126) (xy 416.161423 -31.193011) (xy 416.169008 -31.111131) (xy 416.184116 -31.0303)
			(xy 416.206618 -30.951208) (xy 416.236322 -30.87453) (xy 416.272975 -30.80092) (xy 416.316263 -30.731006)
			(xy 416.365818 -30.665384) (xy 416.421216 -30.604615) (xy 416.481985 -30.549217) (xy 416.547607 -30.499662)
			(xy 416.617521 -30.456374) (xy 416.691132 -30.419722) (xy 416.76781 -30.390018) (xy 416.846902 -30.367516)
			(xy 416.927733 -30.352408) (xy 417.009613 -30.344823) (xy 417.050728 -30.344364) (xy 417.094389 -30.344901)
			(xy 417.181287 -30.353487) (xy 417.266927 -30.370543) (xy 417.350484 -30.395906) (xy 417.431156 -30.429332)
			(xy 417.508164 -30.470499) (xy 417.58077 -30.519012) (xy 417.614862 -30.546294) (xy 417.623928 -30.552903)
			(xy 417.64567 -30.558316) (xy 417.656772 -30.556708) (xy 417.73348 -30.541722) (xy 417.744442 -30.539007)
			(xy 417.762647 -30.525704) (xy 417.768532 -30.516068) (xy 417.789672 -30.478128) (xy 417.838358 -30.406195)
			(xy 417.89382 -30.339348) (xy 417.955531 -30.278222) (xy 418.022903 -30.2234) (xy 418.095296 -30.175401)
			(xy 418.172021 -30.134684) (xy 418.252347 -30.101635) (xy 418.335511 -30.07657) (xy 418.420722 -30.059726)
			(xy 418.507168 -30.051263) (xy 418.550598 -30.05074) (xy 418.551106 -30.05074) (xy 418.596551 -30.051316)
			(xy 418.686967 -30.060585) (xy 418.775967 -30.079026) (xy 418.862623 -30.106446) (xy 418.94603 -30.14256)
			(xy 418.985954 -30.164278) (xy 418.996045 -30.169238) (xy 419.018447 -30.17082) (xy 419.029134 -30.167326)
			(xy 419.067652 -30.152877) (xy 419.146773 -30.130325) (xy 419.227641 -30.115185) (xy 419.309562 -30.107587)
			(xy 419.350698 -30.107128) (xy 419.35146 -30.107128) (xy 419.392564 -30.10759) (xy 419.47442 -30.115172)
			(xy 419.555228 -30.130275) (xy 419.634298 -30.15277) (xy 419.710954 -30.182464) (xy 419.784544 -30.219106)
			(xy 419.854438 -30.262381) (xy 419.920042 -30.311921) (xy 419.980794 -30.367304) (xy 420.036176 -30.428055)
			(xy 420.085717 -30.493658) (xy 420.128992 -30.563553) (xy 420.137978 -30.5816) (xy 423.239188 -30.5816)
			(xy 423.243218 -30.496999) (xy 423.255271 -30.413164) (xy 423.275239 -30.330855) (xy 423.302941 -30.250816)
			(xy 423.338125 -30.173773) (xy 423.380474 -30.100423) (xy 423.429603 -30.031431) (xy 423.485068 -29.967421)
			(xy 423.546366 -29.908973) (xy 423.612942 -29.856617) (xy 423.684194 -29.810827) (xy 423.759475 -29.772016)
			(xy 423.838105 -29.740537) (xy 423.919372 -29.716676) (xy 424.002538 -29.700647) (xy 424.086852 -29.692596)
			(xy 424.1292 -29.692092) (xy 424.129708 -29.692092) (xy 424.17604 -29.692698) (xy 424.268198 -29.702369)
			(xy 424.358852 -29.721565) (xy 424.447021 -29.750077) (xy 424.489626 -29.768292) (xy 424.499568 -29.772098)
			(xy 424.520832 -29.772098) (xy 424.530774 -29.768292) (xy 424.573436 -29.750047) (xy 424.661729 -29.721503)
			(xy 424.752514 -29.70231) (xy 424.844804 -29.692677) (xy 424.8912 -29.692092) (xy 424.937596 -29.692675)
			(xy 425.029884 -29.70232) (xy 425.120668 -29.721516) (xy 425.208961 -29.750054) (xy 425.251626 -29.768292)
			(xy 425.261568 -29.772098) (xy 425.282832 -29.772098) (xy 425.292774 -29.768292) (xy 425.335377 -29.75007)
			(xy 425.423544 -29.721552) (xy 425.5142 -29.70236) (xy 425.60636 -29.6927) (xy 425.652692 -29.692092)
			(xy 425.6532 -29.692092) (xy 425.697015 -29.692659) (xy 425.784221 -29.701274) (xy 425.870158 -29.71842)
			(xy 425.953993 -29.743931) (xy 426.034914 -29.77756) (xy 426.112137 -29.818981) (xy 426.184915 -29.867793)
			(xy 426.252541 -29.923524) (xy 426.31436 -29.985632) (xy 426.369775 -30.053517) (xy 426.418248 -30.12652)
			(xy 426.459309 -30.203935) (xy 426.492561 -30.285012) (xy 426.505624 -30.326838) (xy 426.508551 -30.335482)
			(xy 426.51951 -30.350061) (xy 426.534884 -30.359873) (xy 426.543724 -30.362144) (xy 426.6311 -30.380686)
			(xy 426.64001 -30.382162) (xy 426.657857 -30.379449) (xy 426.673675 -30.370752) (xy 426.679868 -30.364176)
			(xy 426.680122 -30.363922) (xy 426.708239 -30.33195) (xy 426.769631 -30.27295) (xy 426.836377 -30.220083)
			(xy 426.907867 -30.173832) (xy 426.983447 -30.134619) (xy 427.062427 -30.102805) (xy 427.144084 -30.078678)
			(xy 427.227672 -30.062461) (xy 427.312427 -30.0543) (xy 427.355 -30.053788) (xy 427.396111 -30.054252)
			(xy 427.477981 -30.06184) (xy 427.558801 -30.076951) (xy 427.637882 -30.099456) (xy 427.714549 -30.129162)
			(xy 427.788147 -30.165818) (xy 427.858049 -30.209108) (xy 427.861904 -30.21202) (xy 430.046497 -30.21202)
			(xy 430.051762 -30.128335) (xy 430.064879 -30.045517) (xy 430.085732 -29.9643) (xy 430.114136 -29.885407)
			(xy 430.149838 -29.809537) (xy 430.192521 -29.737363) (xy 430.241807 -29.669526) (xy 430.297259 -29.606629)
			(xy 430.358383 -29.549229) (xy 430.424638 -29.497837) (xy 430.495436 -29.452907) (xy 430.570147 -29.41484)
			(xy 430.648109 -29.383972) (xy 430.728631 -29.360579) (xy 430.810996 -29.344867) (xy 430.894475 -29.336976)
			(xy 430.9364 -29.336492) (xy 430.973664 -29.336847) (xy 431.047936 -29.342996) (xy 431.121433 -29.355335)
			(xy 431.157634 -29.364178) (xy 431.170588 -29.36748) (xy 431.196496 -29.360622) (xy 431.277522 -29.279596)
			(xy 431.28438 -29.253688) (xy 431.281078 -29.240734) (xy 431.272238 -29.204532) (xy 431.259893 -29.131036)
			(xy 431.25374 -29.056764) (xy 431.253392 -29.0195) (xy 431.253876 -28.977575) (xy 431.261767 -28.894096)
			(xy 431.277479 -28.811731) (xy 431.300872 -28.731209) (xy 431.33174 -28.653247) (xy 431.369807 -28.578536)
			(xy 431.414737 -28.507738) (xy 431.466129 -28.441483) (xy 431.523529 -28.380359) (xy 431.586426 -28.324907)
			(xy 431.654263 -28.275621) (xy 431.726437 -28.232938) (xy 431.802307 -28.197236) (xy 431.8812 -28.168832)
			(xy 431.962417 -28.147979) (xy 432.045235 -28.134862) (xy 432.12892 -28.129597) (xy 432.21273 -28.132231)
			(xy 432.295919 -28.14274) (xy 432.37775 -28.161032) (xy 432.457497 -28.186943) (xy 432.534451 -28.220244)
			(xy 432.60793 -28.26064) (xy 432.677282 -28.307771) (xy 432.74189 -28.361219) (xy 432.801181 -28.42051)
			(xy 432.854629 -28.485118) (xy 432.90176 -28.55447) (xy 432.942156 -28.627949) (xy 432.975457 -28.704903)
			(xy 433.001368 -28.78465) (xy 433.01966 -28.866481) (xy 433.030169 -28.94967) (xy 433.032803 -29.03348)
			(xy 433.029687 -29.083) (xy 434.34497 -29.083) (xy 434.349069 -28.997659) (xy 434.361328 -28.913104)
			(xy 434.381635 -28.830114) (xy 434.409803 -28.749451) (xy 434.445571 -28.67186) (xy 434.488612 -28.598054)
			(xy 434.538528 -28.528712) (xy 434.566314 -28.49626) (xy 434.572079 -28.489171) (xy 434.578591 -28.472113)
			(xy 434.579014 -28.462986) (xy 434.579014 -28.433014) (xy 434.578581 -28.423891) (xy 434.572061 -28.406841)
			(xy 434.566314 -28.39974) (xy 434.540256 -28.369327) (xy 434.493069 -28.304608) (xy 434.451894 -28.235908)
			(xy 434.417063 -28.163784) (xy 434.388859 -28.08882) (xy 434.36751 -28.011623) (xy 434.35319 -27.932819)
			(xy 434.346015 -27.853047) (xy 434.345588 -27.813) (xy 434.346067 -27.771898) (xy 434.353652 -27.690044)
			(xy 434.368757 -27.609238) (xy 434.391253 -27.530172) (xy 434.420949 -27.453518) (xy 434.45759 -27.379931)
			(xy 434.500865 -27.310039) (xy 434.550405 -27.244439) (xy 434.605786 -27.183688) (xy 434.666535 -27.128307)
			(xy 434.732136 -27.078768) (xy 434.802028 -27.035492) (xy 434.875614 -26.99885) (xy 434.952268 -26.969154)
			(xy 435.031335 -26.946657) (xy 435.11214 -26.931552) (xy 435.193994 -26.923967) (xy 435.235096 -26.923492)
			(xy 435.235858 -26.923492) (xy 435.27782 -26.924001) (xy 435.36137 -26.931921) (xy 435.443801 -26.947686)
			(xy 435.524378 -26.971154) (xy 435.602382 -27.002117) (xy 435.639972 -27.020774) (xy 435.640226 -27.020774)
			(xy 435.650658 -27.025444) (xy 435.673477 -27.026091) (xy 435.684168 -27.022044) (xy 435.766718 -26.984706)
			(xy 435.781704 -26.967434) (xy 435.784498 -26.956258) (xy 435.795522 -26.915975) (xy 435.82422 -26.837536)
			(xy 435.860142 -26.762133) (xy 435.902973 -26.690427) (xy 435.952336 -26.623051) (xy 436.007796 -26.560598)
			(xy 436.068865 -26.503617) (xy 436.135005 -26.45261) (xy 436.205634 -26.408026) (xy 436.28013 -26.370258)
			(xy 436.357838 -26.339637) (xy 436.438074 -26.316434) (xy 436.520132 -26.300852) (xy 436.603288 -26.293029)
			(xy 436.64505 -26.292556) (xy 436.686156 -26.29306) (xy 436.768019 -26.30064) (xy 436.848833 -26.31574)
			(xy 436.92791 -26.338232) (xy 437.004574 -26.367922) (xy 437.078173 -26.404559) (xy 437.148077 -26.447829)
			(xy 437.213691 -26.497364) (xy 437.274456 -26.552742) (xy 437.304203 -26.585361) (xy 437.819542 -26.585361)
			(xy 437.819542 -26.500639) (xy 437.827595 -26.416302) (xy 437.843629 -26.333112) (xy 437.867497 -26.251822)
			(xy 437.898985 -26.17317) (xy 437.937807 -26.097867) (xy 437.98361 -26.026595) (xy 438.035981 -25.959999)
			(xy 438.094446 -25.898684) (xy 438.158474 -25.843203) (xy 438.227486 -25.79406) (xy 438.300856 -25.7517)
			(xy 438.377921 -25.716505) (xy 438.457983 -25.688796) (xy 438.540316 -25.668822) (xy 438.624175 -25.656765)
			(xy 438.7088 -25.652734) (xy 438.793425 -25.656765) (xy 438.877284 -25.668822) (xy 438.959617 -25.688796)
			(xy 439.039679 -25.716505) (xy 439.116744 -25.7517) (xy 439.190114 -25.79406) (xy 439.259126 -25.843203)
			(xy 439.323154 -25.898684) (xy 439.381619 -25.959999) (xy 439.43399 -26.026595) (xy 439.479793 -26.097867)
			(xy 439.518615 -26.17317) (xy 439.550103 -26.251822) (xy 439.573971 -26.333112) (xy 439.590005 -26.416302)
			(xy 439.598058 -26.500639) (xy 439.598562 -26.543) (xy 439.598058 -26.585361) (xy 439.590005 -26.669698)
			(xy 439.573971 -26.752888) (xy 439.550103 -26.834178) (xy 439.518615 -26.91283) (xy 439.479793 -26.988133)
			(xy 439.43399 -27.059405) (xy 439.381619 -27.126001) (xy 439.323154 -27.187316) (xy 439.259126 -27.242797)
			(xy 439.190114 -27.29194) (xy 439.116744 -27.3343) (xy 439.039679 -27.369495) (xy 438.959617 -27.397204)
			(xy 438.877284 -27.417178) (xy 438.793425 -27.429235) (xy 438.7088 -27.433267) (xy 438.624175 -27.429235)
			(xy 438.540316 -27.417178) (xy 438.457983 -27.397204) (xy 438.377921 -27.369495) (xy 438.300856 -27.3343)
			(xy 438.227486 -27.29194) (xy 438.158474 -27.242797) (xy 438.094446 -27.187316) (xy 438.035981 -27.126001)
			(xy 437.98361 -27.059405) (xy 437.937807 -26.988133) (xy 437.898985 -26.91283) (xy 437.867497 -26.834178)
			(xy 437.843629 -26.752888) (xy 437.827595 -26.669698) (xy 437.819542 -26.585361) (xy 437.304203 -26.585361)
			(xy 437.329853 -26.613488) (xy 437.379409 -26.679087) (xy 437.422702 -26.748977) (xy 437.459362 -26.822564)
			(xy 437.489077 -26.899219) (xy 437.511594 -26.978288) (xy 437.52672 -27.059097) (xy 437.534326 -27.140958)
			(xy 437.534812 -27.182064) (xy 437.534317 -27.223122) (xy 437.526695 -27.304884) (xy 437.511577 -27.385597)
			(xy 437.489092 -27.464576) (xy 437.45943 -27.541148) (xy 437.422844 -27.614664) (xy 437.379644 -27.684499)
			(xy 437.330198 -27.75006) (xy 437.30291 -27.780742) (xy 437.296792 -27.787951) (xy 437.289971 -27.805575)
			(xy 437.28998 -27.824472) (xy 437.296818 -27.84209) (xy 437.30291 -27.849322) (xy 437.330222 -27.879986)
			(xy 437.379701 -27.94553) (xy 437.422924 -28.015358) (xy 437.459523 -28.088875) (xy 437.489185 -28.165454)
			(xy 437.511658 -28.244442) (xy 437.526751 -28.325166) (xy 437.534334 -28.406939) (xy 437.534812 -28.448)
			(xy 437.534348 -28.489111) (xy 437.52676 -28.570981) (xy 437.511649 -28.651801) (xy 437.489144 -28.730882)
			(xy 437.459438 -28.807549) (xy 437.422782 -28.881147) (xy 437.379492 -28.951049) (xy 437.329935 -29.016657)
			(xy 437.274535 -29.077412) (xy 437.213765 -29.132795) (xy 437.148143 -29.182333) (xy 437.078229 -29.225604)
			(xy 437.00462 -29.262239) (xy 436.927945 -29.291924) (xy 436.848858 -29.314406) (xy 436.768033 -29.329494)
			(xy 436.686161 -29.337059) (xy 436.64505 -29.337508) (xy 436.603093 -29.337049) (xy 436.51955 -29.32917)
			(xy 436.437122 -29.31345) (xy 436.356543 -29.290028) (xy 436.278532 -29.259113) (xy 436.240936 -29.24048)
			(xy 436.230776 -29.2354) (xy 436.207662 -29.234892) (xy 436.124858 -29.27223) (xy 436.114709 -29.277484)
			(xy 436.099942 -29.294889) (xy 436.09641 -29.305758) (xy 436.085538 -29.345875) (xy 436.057322 -29.424062)
			(xy 436.021932 -29.499275) (xy 435.979677 -29.570856) (xy 435.930926 -29.638181) (xy 435.903878 -29.66974)
			(xy 435.898079 -29.676884) (xy 435.891567 -29.694075) (xy 435.891178 -29.703268) (xy 435.891178 -29.732986)
			(xy 435.891613 -29.742109) (xy 435.898132 -29.759159) (xy 435.903878 -29.76626) (xy 435.929935 -29.796674)
			(xy 435.977122 -29.861393) (xy 436.018298 -29.930092) (xy 436.053129 -30.002216) (xy 436.081333 -30.07718)
			(xy 436.102682 -30.154377) (xy 436.117002 -30.233181) (xy 436.124177 -30.312953) (xy 436.124604 -30.353)
			(xy 436.1241 -30.395348) (xy 436.116049 -30.479662) (xy 436.10002 -30.562828) (xy 436.076159 -30.644095)
			(xy 436.04468 -30.722725) (xy 436.005869 -30.798006) (xy 435.960079 -30.869258) (xy 435.907723 -30.935834)
			(xy 435.849275 -30.997132) (xy 435.785265 -31.052597) (xy 435.716273 -31.101726) (xy 435.642923 -31.144075)
			(xy 435.56588 -31.179259) (xy 435.485841 -31.206961) (xy 435.403532 -31.226929) (xy 435.319697 -31.238982)
			(xy 435.235096 -31.243013) (xy 435.150495 -31.238982) (xy 435.06666 -31.226929) (xy 434.984351 -31.206961)
			(xy 434.904312 -31.179259) (xy 434.827269 -31.144075) (xy 434.753919 -31.101726) (xy 434.684927 -31.052597)
			(xy 434.620917 -30.997132) (xy 434.562469 -30.935834) (xy 434.510113 -30.869258) (xy 434.464323 -30.798006)
			(xy 434.425512 -30.722725) (xy 434.394033 -30.644095) (xy 434.370172 -30.562828) (xy 434.354143 -30.479662)
			(xy 434.346092 -30.395348) (xy 434.345588 -30.353) (xy 434.346004 -30.312953) (xy 434.353199 -30.233184)
			(xy 434.367532 -30.154384) (xy 434.388887 -30.07719) (xy 434.417091 -30.002227) (xy 434.451915 -29.930101)
			(xy 434.493078 -29.861395) (xy 434.540247 -29.796665) (xy 434.566314 -29.76626) (xy 434.572079 -29.759171)
			(xy 434.578591 -29.742113) (xy 434.579014 -29.732986) (xy 434.579014 -29.703014) (xy 434.578581 -29.693891)
			(xy 434.572061 -29.676841) (xy 434.566314 -29.66974) (xy 434.538528 -29.637288) (xy 434.488612 -29.567946)
			(xy 434.445571 -29.49414) (xy 434.409803 -29.416549) (xy 434.381635 -29.335886) (xy 434.361328 -29.252896)
			(xy 434.349069 -29.168341) (xy 434.34497 -29.083) (xy 433.029687 -29.083) (xy 433.027538 -29.117165)
			(xy 433.014421 -29.199983) (xy 432.993568 -29.2812) (xy 432.965164 -29.360093) (xy 432.929462 -29.435963)
			(xy 432.886779 -29.508137) (xy 432.837493 -29.575974) (xy 432.782041 -29.638871) (xy 432.720917 -29.696271)
			(xy 432.654662 -29.747663) (xy 432.583864 -29.792593) (xy 432.509153 -29.83066) (xy 432.431191 -29.861528)
			(xy 432.350669 -29.884921) (xy 432.268304 -29.900633) (xy 432.184825 -29.908524) (xy 432.1429 -29.909008)
			(xy 432.105636 -29.908653) (xy 432.031364 -29.902504) (xy 431.957867 -29.890165) (xy 431.921666 -29.881322)
			(xy 431.908712 -29.87802) (xy 431.882804 -29.884878) (xy 431.801778 -29.965904) (xy 431.79492 -29.991812)
			(xy 431.798222 -30.004766) (xy 431.807062 -30.040968) (xy 431.819407 -30.114464) (xy 431.82556 -30.188736)
			(xy 431.825908 -30.226) (xy 431.825424 -30.267925) (xy 431.817533 -30.351404) (xy 431.801821 -30.433769)
			(xy 431.778428 -30.514291) (xy 431.74756 -30.592253) (xy 431.709493 -30.666964) (xy 431.664563 -30.737762)
			(xy 431.613171 -30.804017) (xy 431.555771 -30.865141) (xy 431.492874 -30.920593) (xy 431.425037 -30.969879)
			(xy 431.352863 -31.012562) (xy 431.276993 -31.048264) (xy 431.1981 -31.076668) (xy 431.116883 -31.097521)
			(xy 431.034065 -31.110638) (xy 430.95038 -31.115903) (xy 430.86657 -31.113269) (xy 430.783381 -31.10276)
			(xy 430.70155 -31.084468) (xy 430.621803 -31.058557) (xy 430.544849 -31.025256) (xy 430.47137 -30.98486)
			(xy 430.402018 -30.937729) (xy 430.33741 -30.884281) (xy 430.278119 -30.82499) (xy 430.224671 -30.760382)
			(xy 430.17754 -30.69103) (xy 430.137144 -30.617551) (xy 430.103843 -30.540597) (xy 430.077932 -30.46085)
			(xy 430.05964 -30.379019) (xy 430.049131 -30.29583) (xy 430.046497 -30.21202) (xy 427.861904 -30.21202)
			(xy 427.923657 -30.258665) (xy 427.984412 -30.314065) (xy 428.039795 -30.374835) (xy 428.089333 -30.440457)
			(xy 428.132604 -30.510371) (xy 428.169239 -30.58398) (xy 428.198924 -30.660655) (xy 428.221406 -30.739742)
			(xy 428.236494 -30.820567) (xy 428.244059 -30.902439) (xy 428.244508 -30.94355) (xy 428.243952 -30.987801)
			(xy 428.235174 -31.075868) (xy 428.217698 -31.162628) (xy 428.191698 -31.247226) (xy 428.15743 -31.328826)
			(xy 428.136812 -31.367984) (xy 428.136812 -31.368238) (xy 428.131832 -31.378857) (xy 428.131028 -31.40227)
			(xy 428.135288 -31.413196) (xy 428.169324 -31.487364) (xy 428.174744 -31.497823) (xy 428.193028 -31.512641)
			(xy 428.204376 -31.515812) (xy 428.204884 -31.515812) (xy 428.246543 -31.525444) (xy 428.327941 -31.55164)
			(xy 428.406454 -31.585517) (xy 428.481359 -31.626761) (xy 428.551968 -31.674994) (xy 428.585122 -31.701994)
			(xy 428.592489 -31.707555) (xy 428.609929 -31.713552) (xy 428.619158 -31.713678) (xy 428.648876 -31.712916)
			(xy 428.658005 -31.712302) (xy 428.674932 -31.705389) (xy 428.681896 -31.699454) (xy 428.712689 -31.671687)
			(xy 428.778586 -31.621354) (xy 428.848881 -31.577371) (xy 428.922964 -31.54012) (xy 429.000191 -31.509924)
			(xy 429.079893 -31.487044) (xy 429.161378 -31.47168) (xy 429.24394 -31.463965) (xy 429.2854 -31.463488)
			(xy 429.327763 -31.463892) (xy 429.412105 -31.471946) (xy 429.4953 -31.48798) (xy 429.576594 -31.51185)
			(xy 429.655251 -31.54334) (xy 429.730558 -31.582163) (xy 429.801834 -31.62797) (xy 429.849381 -31.665361)
			(xy 440.562742 -31.665361) (xy 440.562742 -31.580639) (xy 440.570795 -31.496302) (xy 440.586829 -31.413112)
			(xy 440.610697 -31.331822) (xy 440.642185 -31.25317) (xy 440.681007 -31.177867) (xy 440.72681 -31.106595)
			(xy 440.779181 -31.039999) (xy 440.837646 -30.978684) (xy 440.901674 -30.923203) (xy 440.970686 -30.87406)
			(xy 441.044056 -30.8317) (xy 441.121121 -30.796505) (xy 441.201183 -30.768796) (xy 441.283516 -30.748822)
			(xy 441.367375 -30.736765) (xy 441.452 -30.732734) (xy 441.536625 -30.736765) (xy 441.620484 -30.748822)
			(xy 441.702817 -30.768796) (xy 441.782879 -30.796505) (xy 441.859944 -30.8317) (xy 441.933314 -30.87406)
			(xy 442.002326 -30.923203) (xy 442.066354 -30.978684) (xy 442.124819 -31.039999) (xy 442.17719 -31.106595)
			(xy 442.222993 -31.177867) (xy 442.261815 -31.25317) (xy 442.293303 -31.331822) (xy 442.317171 -31.413112)
			(xy 442.333205 -31.496302) (xy 442.341258 -31.580639) (xy 442.341762 -31.623) (xy 442.341258 -31.665361)
			(xy 442.333205 -31.749698) (xy 442.317171 -31.832888) (xy 442.293303 -31.914178) (xy 442.261815 -31.99283)
			(xy 442.222993 -32.068133) (xy 442.17719 -32.139405) (xy 442.124819 -32.206001) (xy 442.066354 -32.267316)
			(xy 442.002326 -32.322797) (xy 441.933314 -32.37194) (xy 441.859944 -32.4143) (xy 441.782879 -32.449495)
			(xy 441.702817 -32.477204) (xy 441.620484 -32.497178) (xy 441.536625 -32.509235) (xy 441.452 -32.513267)
			(xy 441.367375 -32.509235) (xy 441.283516 -32.497178) (xy 441.201183 -32.477204) (xy 441.121121 -32.449495)
			(xy 441.044056 -32.4143) (xy 440.970686 -32.37194) (xy 440.901674 -32.322797) (xy 440.837646 -32.267316)
			(xy 440.779181 -32.206001) (xy 440.72681 -32.139405) (xy 440.681007 -32.068133) (xy 440.642185 -31.99283)
			(xy 440.610697 -31.914178) (xy 440.586829 -31.832888) (xy 440.570795 -31.749698) (xy 440.562742 -31.665361)
			(xy 429.849381 -31.665361) (xy 429.868433 -31.680344) (xy 429.929752 -31.738811) (xy 429.985236 -31.802843)
			(xy 430.034382 -31.871859) (xy 430.076745 -31.945233) (xy 430.111941 -32.022303) (xy 430.139652 -32.102369)
			(xy 430.159627 -32.184706) (xy 430.171685 -32.26857) (xy 430.175717 -32.3532) (xy 430.171685 -32.43783)
			(xy 430.159627 -32.521694) (xy 430.139652 -32.604031) (xy 430.111941 -32.684097) (xy 430.076745 -32.761167)
			(xy 430.034382 -32.834541) (xy 429.985236 -32.903557) (xy 429.957678 -32.935361) (xy 431.552092 -32.935361)
			(xy 431.552092 -32.850639) (xy 431.560145 -32.766302) (xy 431.576179 -32.683112) (xy 431.600047 -32.601822)
			(xy 431.631535 -32.52317) (xy 431.670357 -32.447867) (xy 431.71616 -32.376595) (xy 431.768531 -32.309999)
			(xy 431.826996 -32.248684) (xy 431.891024 -32.193203) (xy 431.960036 -32.14406) (xy 432.033406 -32.1017)
			(xy 432.110471 -32.066505) (xy 432.190533 -32.038796) (xy 432.272866 -32.018822) (xy 432.356725 -32.006765)
			(xy 432.44135 -32.002734) (xy 432.525975 -32.006765) (xy 432.609834 -32.018822) (xy 432.692167 -32.038796)
			(xy 432.772229 -32.066505) (xy 432.849294 -32.1017) (xy 432.922664 -32.14406) (xy 432.991676 -32.193203)
			(xy 433.055704 -32.248684) (xy 433.114169 -32.309999) (xy 433.16654 -32.376595) (xy 433.212343 -32.447867)
			(xy 433.251165 -32.52317) (xy 433.282653 -32.601822) (xy 433.306521 -32.683112) (xy 433.322555 -32.766302)
			(xy 433.330608 -32.850639) (xy 433.331112 -32.893) (xy 433.330608 -32.935361) (xy 433.322555 -33.019698)
			(xy 433.306521 -33.102888) (xy 433.282653 -33.184178) (xy 433.251165 -33.26283) (xy 433.212343 -33.338133)
			(xy 433.16654 -33.409405) (xy 433.114169 -33.476001) (xy 433.055704 -33.537316) (xy 432.991676 -33.592797)
			(xy 432.922664 -33.64194) (xy 432.849294 -33.6843) (xy 432.772229 -33.719495) (xy 432.692167 -33.747204)
			(xy 432.609834 -33.767178) (xy 432.525975 -33.779235) (xy 432.44135 -33.783267) (xy 432.356725 -33.779235)
			(xy 432.272866 -33.767178) (xy 432.190533 -33.747204) (xy 432.110471 -33.719495) (xy 432.033406 -33.6843)
			(xy 431.960036 -33.64194) (xy 431.891024 -33.592797) (xy 431.826996 -33.537316) (xy 431.768531 -33.476001)
			(xy 431.71616 -33.409405) (xy 431.670357 -33.338133) (xy 431.631535 -33.26283) (xy 431.600047 -33.184178)
			(xy 431.576179 -33.102888) (xy 431.560145 -33.019698) (xy 431.552092 -32.935361) (xy 429.957678 -32.935361)
			(xy 429.929752 -32.967589) (xy 429.868433 -33.026056) (xy 429.801834 -33.07843) (xy 429.730558 -33.124237)
			(xy 429.655251 -33.16306) (xy 429.576594 -33.19455) (xy 429.4953 -33.21842) (xy 429.412105 -33.234454)
			(xy 429.327763 -33.242508) (xy 429.2854 -33.243012) (xy 429.241214 -33.242461) (xy 429.153281 -33.233664)
			(xy 429.066654 -33.216187) (xy 428.982188 -33.190201) (xy 428.900718 -33.155965) (xy 428.823045 -33.113814)
			(xy 428.749938 -33.064166) (xy 428.715678 -33.036256) (xy 428.708315 -33.03069) (xy 428.690871 -33.024697)
			(xy 428.681642 -33.024572) (xy 428.651924 -33.025334) (xy 428.642794 -33.025936) (xy 428.625866 -33.032856)
			(xy 428.618904 -33.038796) (xy 428.615094 -33.042098) (xy 428.607775 -33.049523) (xy 428.599247 -33.068524)
			(xy 428.598584 -33.078928) (xy 428.597822 -33.109916) (xy 428.598158 -33.120269) (xy 428.606012 -33.139413)
			(xy 428.613062 -33.147) (xy 428.644198 -33.178338) (xy 428.700815 -33.246156) (xy 428.750427 -33.319254)
			(xy 428.792545 -33.396913) (xy 428.826753 -33.478366) (xy 428.852714 -33.56281) (xy 428.870171 -33.649413)
			(xy 428.878954 -33.73732) (xy 428.879508 -33.781492) (xy 428.879508 -33.782) (xy 428.879004 -33.824348)
			(xy 428.870953 -33.908662) (xy 428.854924 -33.991828) (xy 428.831063 -34.073095) (xy 428.799584 -34.151725)
			(xy 428.760773 -34.227006) (xy 428.714983 -34.298258) (xy 428.662627 -34.364834) (xy 428.604179 -34.426132)
			(xy 428.540169 -34.481597) (xy 428.471177 -34.530726) (xy 428.397827 -34.573075) (xy 428.382639 -34.580011)
			(xy 429.031142 -34.580011) (xy 429.031142 -34.495289) (xy 429.039195 -34.410952) (xy 429.055229 -34.327762)
			(xy 429.079097 -34.246472) (xy 429.110585 -34.16782) (xy 429.149407 -34.092517) (xy 429.19521 -34.021245)
			(xy 429.247581 -33.954649) (xy 429.306046 -33.893334) (xy 429.370074 -33.837853) (xy 429.439086 -33.78871)
			(xy 429.512456 -33.74635) (xy 429.589521 -33.711155) (xy 429.669583 -33.683446) (xy 429.751916 -33.663472)
			(xy 429.835775 -33.651415) (xy 429.9204 -33.647384) (xy 430.005025 -33.651415) (xy 430.088884 -33.663472)
			(xy 430.171217 -33.683446) (xy 430.251279 -33.711155) (xy 430.328344 -33.74635) (xy 430.401714 -33.78871)
			(xy 430.470726 -33.837853) (xy 430.534754 -33.893334) (xy 430.593219 -33.954649) (xy 430.64559 -34.021245)
			(xy 430.691393 -34.092517) (xy 430.72773 -34.163) (xy 434.345588 -34.163) (xy 434.34606 -34.122949)
			(xy 434.353283 -34.043173) (xy 434.367643 -33.964368) (xy 434.389025 -33.887172) (xy 434.417255 -33.812209)
			(xy 434.452106 -33.740085) (xy 434.493295 -33.671384) (xy 434.540489 -33.60666) (xy 434.566568 -33.57626)
			(xy 434.572372 -33.569121) (xy 434.57888 -33.551925) (xy 434.579268 -33.542732) (xy 434.579268 -33.513268)
			(xy 434.578858 -33.504081) (xy 434.572343 -33.486897) (xy 434.566568 -33.47974) (xy 434.540484 -33.449341)
			(xy 434.493259 -33.384634) (xy 434.452047 -33.31594) (xy 434.417181 -33.243818) (xy 434.388945 -33.168852)
			(xy 434.367568 -33.09165) (xy 434.353222 -33.012837) (xy 434.346025 -32.933054) (xy 434.345588 -32.893)
			(xy 434.346092 -32.850639) (xy 434.354145 -32.766302) (xy 434.370179 -32.683112) (xy 434.394047 -32.601822)
			(xy 434.425535 -32.52317) (xy 434.464357 -32.447867) (xy 434.51016 -32.376595) (xy 434.562531 -32.309999)
			(xy 434.620996 -32.248684) (xy 434.685024 -32.193203) (xy 434.754036 -32.14406) (xy 434.827406 -32.1017)
			(xy 434.904471 -32.066505) (xy 434.984533 -32.038796) (xy 435.066866 -32.018822) (xy 435.150725 -32.006765)
			(xy 435.23535 -32.002734) (xy 435.319975 -32.006765) (xy 435.403834 -32.018822) (xy 435.486167 -32.038796)
			(xy 435.566229 -32.066505) (xy 435.643294 -32.1017) (xy 435.716664 -32.14406) (xy 435.785676 -32.193203)
			(xy 435.849704 -32.248684) (xy 435.908169 -32.309999) (xy 435.96054 -32.376595) (xy 436.006343 -32.447867)
			(xy 436.045165 -32.52317) (xy 436.076653 -32.601822) (xy 436.100521 -32.683112) (xy 436.116555 -32.766302)
			(xy 436.124608 -32.850639) (xy 436.125112 -32.893) (xy 436.12464 -32.933051) (xy 436.117417 -33.012827)
			(xy 436.103057 -33.091632) (xy 436.081675 -33.168828) (xy 436.053445 -33.243791) (xy 436.018594 -33.315915)
			(xy 435.977405 -33.384616) (xy 435.930211 -33.44934) (xy 435.904132 -33.47974) (xy 435.898328 -33.486879)
			(xy 435.89182 -33.504075) (xy 435.891432 -33.513268) (xy 435.891432 -33.542732) (xy 435.891842 -33.551919)
			(xy 435.898357 -33.569103) (xy 435.904132 -33.57626) (xy 435.930216 -33.606659) (xy 435.977441 -33.671366)
			(xy 436.018653 -33.74006) (xy 436.053519 -33.812182) (xy 436.081755 -33.887148) (xy 436.103132 -33.96435)
			(xy 436.117478 -34.043163) (xy 436.124675 -34.122946) (xy 436.125112 -34.163) (xy 436.124608 -34.205361)
			(xy 436.116555 -34.289698) (xy 436.100521 -34.372888) (xy 436.076653 -34.454178) (xy 436.045165 -34.53283)
			(xy 436.006343 -34.608133) (xy 435.96054 -34.679405) (xy 435.908169 -34.746001) (xy 435.849704 -34.807316)
			(xy 435.785676 -34.862797) (xy 435.716664 -34.91194) (xy 435.643294 -34.9543) (xy 435.566229 -34.989495)
			(xy 435.486167 -35.017204) (xy 435.403834 -35.037178) (xy 435.319975 -35.049235) (xy 435.23535 -35.053267)
			(xy 435.150725 -35.049235) (xy 435.066866 -35.037178) (xy 434.984533 -35.017204) (xy 434.904471 -34.989495)
			(xy 434.827406 -34.9543) (xy 434.754036 -34.91194) (xy 434.685024 -34.862797) (xy 434.620996 -34.807316)
			(xy 434.562531 -34.746001) (xy 434.51016 -34.679405) (xy 434.464357 -34.608133) (xy 434.425535 -34.53283)
			(xy 434.394047 -34.454178) (xy 434.370179 -34.372888) (xy 434.354145 -34.289698) (xy 434.346092 -34.205361)
			(xy 434.345588 -34.163) (xy 430.72773 -34.163) (xy 430.730215 -34.16782) (xy 430.761703 -34.246472)
			(xy 430.785571 -34.327762) (xy 430.801605 -34.410952) (xy 430.809658 -34.495289) (xy 430.810162 -34.53765)
			(xy 430.809658 -34.580011) (xy 430.801605 -34.664348) (xy 430.785571 -34.747538) (xy 430.761703 -34.828828)
			(xy 430.730215 -34.90748) (xy 430.691393 -34.982783) (xy 430.64559 -35.054055) (xy 430.593219 -35.120651)
			(xy 430.534754 -35.181966) (xy 430.470726 -35.237447) (xy 430.401714 -35.28659) (xy 430.328344 -35.32895)
			(xy 430.251279 -35.364145) (xy 430.171217 -35.391854) (xy 430.088884 -35.411828) (xy 430.005025 -35.423885)
			(xy 429.9204 -35.427917) (xy 429.835775 -35.423885) (xy 429.751916 -35.411828) (xy 429.669583 -35.391854)
			(xy 429.589521 -35.364145) (xy 429.512456 -35.32895) (xy 429.439086 -35.28659) (xy 429.370074 -35.237447)
			(xy 429.306046 -35.181966) (xy 429.247581 -35.120651) (xy 429.19521 -35.054055) (xy 429.149407 -34.982783)
			(xy 429.110585 -34.90748) (xy 429.079097 -34.828828) (xy 429.055229 -34.747538) (xy 429.039195 -34.664348)
			(xy 429.031142 -34.580011) (xy 428.382639 -34.580011) (xy 428.320784 -34.608259) (xy 428.240745 -34.635961)
			(xy 428.158436 -34.655929) (xy 428.074601 -34.667982) (xy 427.99 -34.672013) (xy 427.905399 -34.667982)
			(xy 427.821564 -34.655929) (xy 427.739255 -34.635961) (xy 427.659216 -34.608259) (xy 427.582173 -34.573075)
			(xy 427.508823 -34.530726) (xy 427.439831 -34.481597) (xy 427.375821 -34.426132) (xy 427.317373 -34.364834)
			(xy 427.265017 -34.298258) (xy 427.219227 -34.227006) (xy 427.180416 -34.151725) (xy 427.148937 -34.073095)
			(xy 427.125076 -33.991828) (xy 427.109047 -33.908662) (xy 427.100996 -33.824348) (xy 427.100492 -33.782)
			(xy 427.101038 -33.737496) (xy 427.109928 -33.648933) (xy 427.127618 -33.5617) (xy 427.153933 -33.476671)
			(xy 427.188608 -33.394694) (xy 427.231298 -33.316591) (xy 427.281574 -33.243142) (xy 427.338935 -33.175082)
			(xy 427.370494 -33.143698) (xy 427.370748 -33.143444) (xy 427.377394 -33.136141) (xy 427.385117 -33.117991)
			(xy 427.385734 -33.108138) (xy 427.387258 -33.03651) (xy 427.386965 -33.026611) (xy 427.379775 -33.008179)
			(xy 427.373288 -33.000696) (xy 427.373034 -33.000442) (xy 427.343996 -32.969428) (xy 427.291358 -32.902728)
			(xy 427.245315 -32.831317) (xy 427.206286 -32.755843) (xy 427.174626 -32.676994) (xy 427.150623 -32.595487)
			(xy 427.134495 -32.512064) (xy 427.12639 -32.427484) (xy 427.125892 -32.385) (xy 427.126426 -32.340748)
			(xy 427.13521 -32.252681) (xy 427.15269 -32.16592) (xy 427.178695 -32.081323) (xy 427.212967 -31.999724)
			(xy 427.233588 -31.960566) (xy 427.233588 -31.960312) (xy 427.2386 -31.949705) (xy 427.239384 -31.926281)
			(xy 427.235112 -31.915354) (xy 427.201076 -31.841186) (xy 427.19564 -31.830736) (xy 427.177368 -31.815912)
			(xy 427.166024 -31.812738) (xy 427.165516 -31.812738) (xy 427.123497 -31.803099) (xy 427.041428 -31.776686)
			(xy 426.9623 -31.742456) (xy 426.886854 -31.70073) (xy 426.815801 -31.6519) (xy 426.749805 -31.596424)
			(xy 426.689487 -31.534823) (xy 426.635412 -31.467674) (xy 426.588088 -31.395608) (xy 426.54796 -31.319301)
			(xy 426.515403 -31.23947) (xy 426.502576 -31.198312) (xy 426.499674 -31.189658) (xy 426.488702 -31.175083)
			(xy 426.473319 -31.165275) (xy 426.464476 -31.163006) (xy 426.3771 -31.144464) (xy 426.368191 -31.142971)
			(xy 426.350341 -31.145687) (xy 426.334522 -31.154393) (xy 426.328332 -31.160974) (xy 426.328078 -31.161228)
			(xy 426.299973 -31.193202) (xy 426.238569 -31.252174) (xy 426.171813 -31.305011) (xy 426.100317 -31.351232)
			(xy 426.024733 -31.390413) (xy 425.945752 -31.422197) (xy 425.864097 -31.446292) (xy 425.780515 -31.462479)
			(xy 425.695768 -31.47061) (xy 425.6532 -31.471108) (xy 425.652692 -31.471108) (xy 425.60636 -31.470502)
			(xy 425.514202 -31.460831) (xy 425.423548 -31.441635) (xy 425.335379 -31.413123) (xy 425.292774 -31.394908)
			(xy 425.282832 -31.391102) (xy 425.261568 -31.391102) (xy 425.251626 -31.394908) (xy 425.208964 -31.413153)
			(xy 425.120671 -31.441697) (xy 425.029886 -31.46089) (xy 424.937596 -31.470523) (xy 424.8912 -31.471108)
			(xy 424.844804 -31.470525) (xy 424.752516 -31.46088) (xy 424.661732 -31.441684) (xy 424.573439 -31.413146)
			(xy 424.530774 -31.394908) (xy 424.520832 -31.391102) (xy 424.499568 -31.391102) (xy 424.489626 -31.394908)
			(xy 424.447023 -31.41313) (xy 424.358856 -31.441648) (xy 424.2682 -31.46084) (xy 424.17604 -31.4705)
			(xy 424.129708 -31.471108) (xy 424.1292 -31.471108) (xy 424.086852 -31.470604) (xy 424.002538 -31.462553)
			(xy 423.919372 -31.446524) (xy 423.838105 -31.422663) (xy 423.759475 -31.391184) (xy 423.684194 -31.352373)
			(xy 423.612942 -31.306583) (xy 423.546366 -31.254227) (xy 423.485068 -31.195779) (xy 423.429603 -31.131769)
			(xy 423.380474 -31.062777) (xy 423.338125 -30.989427) (xy 423.302941 -30.912384) (xy 423.275239 -30.832345)
			(xy 423.255271 -30.750036) (xy 423.243218 -30.666201) (xy 423.239188 -30.5816) (xy 420.137978 -30.5816)
			(xy 420.165634 -30.637142) (xy 420.195329 -30.713798) (xy 420.217824 -30.792868) (xy 420.232927 -30.873676)
			(xy 420.240509 -30.955532) (xy 420.240968 -30.996636) (xy 420.240968 -30.997144) (xy 420.240385 -31.043988)
			(xy 420.230558 -31.137158) (xy 420.210995 -31.22878) (xy 420.197026 -31.273496) (xy 420.194123 -31.283971)
			(xy 420.196492 -31.305556) (xy 420.201598 -31.315152) (xy 420.224785 -31.35539) (xy 420.263597 -31.439766)
			(xy 420.279068 -31.483554) (xy 420.28237 -31.493714) (xy 420.296848 -31.509462) (xy 420.386256 -31.547816)
			(xy 420.4081 -31.547562) (xy 420.417752 -31.54299) (xy 420.452884 -31.527213) (xy 420.525332 -31.501071)
			(xy 420.599769 -31.48129) (xy 420.675637 -31.46802) (xy 420.752368 -31.461359) (xy 420.790878 -31.460948)
			(xy 420.83324 -31.461415) (xy 420.917582 -31.469467) (xy 421.000776 -31.4855) (xy 421.08207 -31.509368)
			(xy 421.160726 -31.540855) (xy 421.236033 -31.579677) (xy 421.307309 -31.625482) (xy 421.373908 -31.677854)
			(xy 421.435227 -31.73632) (xy 421.490711 -31.800351) (xy 421.539857 -31.869365) (xy 421.58222 -31.942739)
			(xy 421.617417 -32.019807) (xy 421.645128 -32.099872) (xy 421.665103 -32.182209) (xy 421.677161 -32.266071)
			(xy 421.681192 -32.3507) (xy 421.677161 -32.435329) (xy 421.665103 -32.519191) (xy 421.645128 -32.601528)
			(xy 421.617417 -32.681593) (xy 421.58222 -32.758661) (xy 421.539857 -32.832035) (xy 421.490711 -32.901049)
			(xy 421.435227 -32.96508) (xy 421.373908 -33.023546) (xy 421.307309 -33.075918) (xy 421.236033 -33.121723)
			(xy 421.160726 -33.160545) (xy 421.08207 -33.192032) (xy 421.000776 -33.2159) (xy 420.917582 -33.231933)
			(xy 420.83324 -33.239985) (xy 420.790878 -33.240472) (xy 420.748304 -33.239973) (xy 420.663545 -33.231852)
			(xy 420.57995 -33.215667) (xy 420.498285 -33.191568) (xy 420.419297 -33.159773) (xy 420.343709 -33.120575)
			(xy 420.272213 -33.074332) (xy 420.205465 -33.021467) (xy 420.144074 -32.962465) (xy 420.088604 -32.897866)
			(xy 420.039561 -32.828261) (xy 419.997395 -32.754287) (xy 419.962493 -32.676622) (xy 419.94836 -32.63646)
			(xy 419.945058 -32.6263) (xy 419.93058 -32.610552) (xy 419.841172 -32.572198) (xy 419.819328 -32.572452)
			(xy 419.809676 -32.577024) (xy 419.774632 -32.592735) (xy 419.702373 -32.618768) (xy 419.62814 -32.638477)
			(xy 419.552484 -32.651715) (xy 419.475968 -32.658383) (xy 419.437566 -32.658812) (xy 419.43655 -32.658812)
			(xy 419.394299 -32.658317) (xy 419.310177 -32.650318) (xy 419.227193 -32.634379) (xy 419.146094 -32.610642)
			(xy 419.067612 -32.579322) (xy 418.992453 -32.5407) (xy 418.921295 -32.495126) (xy 418.854779 -32.44301)
			(xy 418.793506 -32.38482) (xy 418.738026 -32.321083) (xy 418.68884 -32.252372) (xy 418.667184 -32.21609)
			(xy 418.661088 -32.205422) (xy 418.639752 -32.19196) (xy 418.531294 -32.183578) (xy 418.508434 -32.193484)
			(xy 418.50056 -32.203136) (xy 418.472442 -32.237022) (xy 418.410581 -32.299691) (xy 418.342829 -32.35594)
			(xy 418.269851 -32.405218) (xy 418.19236 -32.447044) (xy 418.111115 -32.481007) (xy 418.026912 -32.506774)
			(xy 417.940574 -32.524095) (xy 417.852947 -32.532799) (xy 417.808918 -32.533336) (xy 417.768434 -32.532849)
			(xy 417.687801 -32.5255) (xy 417.60817 -32.510852) (xy 417.530199 -32.489028) (xy 417.454535 -32.460206)
			(xy 417.381804 -32.424626) (xy 417.312608 -32.382583) (xy 417.24752 -32.334424) (xy 417.187079 -32.280549)
			(xy 417.131785 -32.221403) (xy 417.082096 -32.157476) (xy 417.059872 -32.123634) (xy 417.051236 -32.123888)
			(xy 417.05022 -32.123888) (xy 417.009122 -32.123338) (xy 416.927281 -32.115712) (xy 416.846491 -32.10057)
			(xy 416.767443 -32.078042) (xy 416.690809 -32.048318) (xy 416.617244 -32.011652) (xy 416.547374 -31.968358)
			(xy 416.481795 -31.918804) (xy 416.421067 -31.863412) (xy 416.365706 -31.802655) (xy 416.316185 -31.737051)
			(xy 416.272926 -31.667159) (xy 416.236299 -31.593575) (xy 416.206614 -31.516927) (xy 416.184126 -31.437867)
			(xy 416.169025 -31.35707) (xy 416.161441 -31.275224) (xy 416.160966 -31.234126) (xy 410.705621 -31.234126)
			(xy 410.727885 -31.265053) (xy 410.770925 -31.33886) (xy 410.806694 -31.416451) (xy 410.834862 -31.497113)
			(xy 410.855169 -31.580104) (xy 410.867428 -31.664659) (xy 410.871527 -31.75) (xy 410.867428 -31.835341)
			(xy 410.855169 -31.919896) (xy 410.834862 -32.002887) (xy 410.806694 -32.083549) (xy 410.770925 -32.16114)
			(xy 410.727885 -32.234947) (xy 410.677968 -32.304288) (xy 410.650182 -32.33674) (xy 410.644417 -32.343829)
			(xy 410.637905 -32.360886) (xy 410.637482 -32.370014) (xy 410.637482 -32.399986) (xy 410.637916 -32.409109)
			(xy 410.644436 -32.426159) (xy 410.650182 -32.43326) (xy 410.67624 -32.463674) (xy 410.723426 -32.528392)
			(xy 410.764602 -32.597092) (xy 410.799433 -32.669216) (xy 410.827637 -32.74418) (xy 410.848986 -32.821377)
			(xy 410.863306 -32.900181) (xy 410.870481 -32.979953) (xy 410.870908 -33.02) (xy 410.870404 -33.062348)
			(xy 410.862353 -33.146662) (xy 410.846324 -33.229828) (xy 410.822463 -33.311095) (xy 410.790984 -33.389725)
			(xy 410.752173 -33.465006) (xy 410.706383 -33.536258) (xy 410.654027 -33.602834) (xy 410.595579 -33.664132)
			(xy 410.531569 -33.719597) (xy 410.462577 -33.768726) (xy 410.389227 -33.811075) (xy 410.385719 -33.812677)
			(xy 415.34232 -33.812677) (xy 415.34232 -33.727955) (xy 415.350373 -33.643618) (xy 415.366407 -33.560428)
			(xy 415.390275 -33.479138) (xy 415.421763 -33.400486) (xy 415.460585 -33.325183) (xy 415.506388 -33.253911)
			(xy 415.558759 -33.187315) (xy 415.617224 -33.126) (xy 415.681252 -33.070519) (xy 415.750264 -33.021376)
			(xy 415.823634 -32.979016) (xy 415.900699 -32.943821) (xy 415.980761 -32.916112) (xy 416.063094 -32.896138)
			(xy 416.146953 -32.884081) (xy 416.231578 -32.88005) (xy 416.316203 -32.884081) (xy 416.400062 -32.896138)
			(xy 416.482395 -32.916112) (xy 416.562457 -32.943821) (xy 416.639522 -32.979016) (xy 416.712892 -33.021376)
			(xy 416.781904 -33.070519) (xy 416.845932 -33.126) (xy 416.904397 -33.187315) (xy 416.956768 -33.253911)
			(xy 417.002571 -33.325183) (xy 417.041393 -33.400486) (xy 417.072881 -33.479138) (xy 417.096749 -33.560428)
			(xy 417.112783 -33.643618) (xy 417.120836 -33.727955) (xy 417.12134 -33.770316) (xy 417.120954 -33.802771)
			(xy 418.00678 -33.802771) (xy 418.00678 -33.718049) (xy 418.014833 -33.633712) (xy 418.030867 -33.550522)
			(xy 418.054735 -33.469232) (xy 418.086223 -33.39058) (xy 418.125045 -33.315277) (xy 418.170848 -33.244005)
			(xy 418.223219 -33.177409) (xy 418.281684 -33.116094) (xy 418.345712 -33.060613) (xy 418.414724 -33.01147)
			(xy 418.488094 -32.96911) (xy 418.565159 -32.933915) (xy 418.645221 -32.906206) (xy 418.727554 -32.886232)
			(xy 418.811413 -32.874175) (xy 418.896038 -32.870144) (xy 418.980663 -32.874175) (xy 419.064522 -32.886232)
			(xy 419.146855 -32.906206) (xy 419.226917 -32.933915) (xy 419.303982 -32.96911) (xy 419.377352 -33.01147)
			(xy 419.446364 -33.060613) (xy 419.510392 -33.116094) (xy 419.568857 -33.177409) (xy 419.621228 -33.244005)
			(xy 419.667031 -33.315277) (xy 419.705853 -33.39058) (xy 419.737341 -33.469232) (xy 419.761209 -33.550522)
			(xy 419.777243 -33.633712) (xy 419.785296 -33.718049) (xy 419.7858 -33.76041) (xy 419.785296 -33.802771)
			(xy 419.777243 -33.887108) (xy 419.761209 -33.970298) (xy 419.737341 -34.051588) (xy 419.705853 -34.13024)
			(xy 419.667031 -34.205543) (xy 419.621228 -34.276815) (xy 419.568857 -34.343411) (xy 419.510392 -34.404726)
			(xy 419.446364 -34.460207) (xy 419.377352 -34.50935) (xy 419.303982 -34.55171) (xy 419.226917 -34.586905)
			(xy 419.146855 -34.614614) (xy 419.064522 -34.634588) (xy 418.980663 -34.646645) (xy 418.896038 -34.650677)
			(xy 418.811413 -34.646645) (xy 418.727554 -34.634588) (xy 418.645221 -34.614614) (xy 418.565159 -34.586905)
			(xy 418.488094 -34.55171) (xy 418.414724 -34.50935) (xy 418.345712 -34.460207) (xy 418.281684 -34.404726)
			(xy 418.223219 -34.343411) (xy 418.170848 -34.276815) (xy 418.125045 -34.205543) (xy 418.086223 -34.13024)
			(xy 418.054735 -34.051588) (xy 418.030867 -33.970298) (xy 418.014833 -33.887108) (xy 418.00678 -33.802771)
			(xy 417.120954 -33.802771) (xy 417.120836 -33.812677) (xy 417.112783 -33.897014) (xy 417.096749 -33.980204)
			(xy 417.072881 -34.061494) (xy 417.041393 -34.140146) (xy 417.002571 -34.215449) (xy 416.956768 -34.286721)
			(xy 416.904397 -34.353317) (xy 416.845932 -34.414632) (xy 416.781904 -34.470113) (xy 416.712892 -34.519256)
			(xy 416.639522 -34.561616) (xy 416.562457 -34.596811) (xy 416.482395 -34.62452) (xy 416.400062 -34.644494)
			(xy 416.316203 -34.656551) (xy 416.231578 -34.660583) (xy 416.146953 -34.656551) (xy 416.063094 -34.644494)
			(xy 415.980761 -34.62452) (xy 415.900699 -34.596811) (xy 415.823634 -34.561616) (xy 415.750264 -34.519256)
			(xy 415.681252 -34.470113) (xy 415.617224 -34.414632) (xy 415.558759 -34.353317) (xy 415.506388 -34.286721)
			(xy 415.460585 -34.215449) (xy 415.421763 -34.140146) (xy 415.390275 -34.061494) (xy 415.366407 -33.980204)
			(xy 415.350373 -33.897014) (xy 415.34232 -33.812677) (xy 410.385719 -33.812677) (xy 410.312184 -33.846259)
			(xy 410.232145 -33.873961) (xy 410.149836 -33.893929) (xy 410.066001 -33.905982) (xy 409.9814 -33.910013)
			(xy 409.896799 -33.905982) (xy 409.812964 -33.893929) (xy 409.730655 -33.873961) (xy 409.650616 -33.846259)
			(xy 409.573573 -33.811075) (xy 409.500223 -33.768726) (xy 409.431231 -33.719597) (xy 409.367221 -33.664132)
			(xy 409.308773 -33.602834) (xy 409.256417 -33.536258) (xy 409.210627 -33.465006) (xy 409.171816 -33.389725)
			(xy 409.140337 -33.311095) (xy 409.116476 -33.229828) (xy 409.100447 -33.146662) (xy 409.092396 -33.062348)
			(xy 409.091892 -33.02) (xy 409.092307 -32.979953) (xy 409.099502 -32.900184) (xy 409.113836 -32.821384)
			(xy 409.13519 -32.74419) (xy 409.163394 -32.669227) (xy 409.198218 -32.5971) (xy 409.239382 -32.528395)
			(xy 409.286551 -32.463665) (xy 409.312618 -32.43326) (xy 409.318383 -32.426171) (xy 409.324895 -32.409114)
			(xy 409.325318 -32.399986) (xy 409.325318 -32.370014) (xy 409.324884 -32.360891) (xy 409.318364 -32.343841)
			(xy 409.312618 -32.33674) (xy 409.284832 -32.304288) (xy 409.234915 -32.234947) (xy 409.191875 -32.16114)
			(xy 409.156106 -32.083549) (xy 409.127938 -32.002887) (xy 409.107631 -31.919896) (xy 409.095372 -31.835341)
			(xy 409.091273 -31.75) (xy 406.515619 -31.75) (xy 406.528571 -31.794112) (xy 406.544605 -31.877302)
			(xy 406.552658 -31.961639) (xy 406.553162 -32.004) (xy 406.552658 -32.046361) (xy 406.544605 -32.130698)
			(xy 406.528571 -32.213888) (xy 406.504703 -32.295178) (xy 406.473215 -32.37383) (xy 406.434393 -32.449133)
			(xy 406.38859 -32.520405) (xy 406.336219 -32.587001) (xy 406.277754 -32.648316) (xy 406.213726 -32.703797)
			(xy 406.144714 -32.75294) (xy 406.071344 -32.7953) (xy 405.994279 -32.830495) (xy 405.914217 -32.858204)
			(xy 405.831884 -32.878178) (xy 405.748025 -32.890235) (xy 405.6634 -32.894267) (xy 405.578775 -32.890235)
			(xy 405.494916 -32.878178) (xy 405.412583 -32.858204) (xy 405.332521 -32.830495) (xy 405.255456 -32.7953)
			(xy 405.182086 -32.75294) (xy 405.113074 -32.703797) (xy 405.049046 -32.648316) (xy 404.990581 -32.587001)
			(xy 404.93821 -32.520405) (xy 404.892407 -32.449133) (xy 404.853585 -32.37383) (xy 404.822097 -32.295178)
			(xy 404.798229 -32.213888) (xy 404.782195 -32.130698) (xy 404.774142 -32.046361) (xy 390.320981 -32.046361)
			(xy 393.368981 -35.094361) (xy 420.369742 -35.094361) (xy 420.369742 -35.009639) (xy 420.377795 -34.925302)
			(xy 420.393829 -34.842112) (xy 420.417697 -34.760822) (xy 420.449185 -34.68217) (xy 420.488007 -34.606867)
			(xy 420.53381 -34.535595) (xy 420.586181 -34.468999) (xy 420.644646 -34.407684) (xy 420.708674 -34.352203)
			(xy 420.777686 -34.30306) (xy 420.851056 -34.2607) (xy 420.928121 -34.225505) (xy 421.008183 -34.197796)
			(xy 421.090516 -34.177822) (xy 421.174375 -34.165765) (xy 421.259 -34.161734) (xy 421.343625 -34.165765)
			(xy 421.427484 -34.177822) (xy 421.509817 -34.197796) (xy 421.589879 -34.225505) (xy 421.666944 -34.2607)
			(xy 421.740314 -34.30306) (xy 421.809326 -34.352203) (xy 421.873354 -34.407684) (xy 421.931819 -34.468999)
			(xy 421.98419 -34.535595) (xy 422.029993 -34.606867) (xy 422.068815 -34.68217) (xy 422.100303 -34.760822)
			(xy 422.124171 -34.842112) (xy 422.140205 -34.925302) (xy 422.148258 -35.009639) (xy 422.148762 -35.052)
			(xy 422.148258 -35.094361) (xy 422.528742 -35.094361) (xy 422.528742 -35.009639) (xy 422.536795 -34.925302)
			(xy 422.552829 -34.842112) (xy 422.576697 -34.760822) (xy 422.608185 -34.68217) (xy 422.647007 -34.606867)
			(xy 422.69281 -34.535595) (xy 422.745181 -34.468999) (xy 422.803646 -34.407684) (xy 422.867674 -34.352203)
			(xy 422.936686 -34.30306) (xy 423.010056 -34.2607) (xy 423.087121 -34.225505) (xy 423.167183 -34.197796)
			(xy 423.249516 -34.177822) (xy 423.333375 -34.165765) (xy 423.418 -34.161734) (xy 423.502625 -34.165765)
			(xy 423.586484 -34.177822) (xy 423.668817 -34.197796) (xy 423.748879 -34.225505) (xy 423.825944 -34.2607)
			(xy 423.899314 -34.30306) (xy 423.968326 -34.352203) (xy 424.032354 -34.407684) (xy 424.090819 -34.468999)
			(xy 424.14319 -34.535595) (xy 424.188993 -34.606867) (xy 424.227815 -34.68217) (xy 424.259303 -34.760822)
			(xy 424.283171 -34.842112) (xy 424.299205 -34.925302) (xy 424.307258 -35.009639) (xy 424.307762 -35.052)
			(xy 424.307258 -35.094361) (xy 424.299205 -35.178698) (xy 424.283171 -35.261888) (xy 424.259303 -35.343178)
			(xy 424.227815 -35.42183) (xy 424.188993 -35.497133) (xy 424.14319 -35.568405) (xy 424.090819 -35.635001)
			(xy 424.041237 -35.687) (xy 432.205892 -35.687) (xy 432.206367 -35.645898) (xy 432.213952 -35.564043)
			(xy 432.229057 -35.483238) (xy 432.251553 -35.404171) (xy 432.281249 -35.327517) (xy 432.317891 -35.25393)
			(xy 432.361166 -35.184038) (xy 432.410706 -35.118437) (xy 432.466087 -35.057687) (xy 432.526837 -35.002306)
			(xy 432.592438 -34.952766) (xy 432.66233 -34.909491) (xy 432.735917 -34.872849) (xy 432.812571 -34.843153)
			(xy 432.891638 -34.820657) (xy 432.972443 -34.805552) (xy 433.054298 -34.797967) (xy 433.0954 -34.797492)
			(xy 433.139048 -34.797973) (xy 433.225923 -34.806522) (xy 433.311544 -34.823538) (xy 433.395087 -34.848858)
			(xy 433.475748 -34.882237) (xy 433.552753 -34.923356) (xy 433.625361 -34.971818) (xy 433.692873 -35.027158)
			(xy 433.754642 -35.088844) (xy 433.810072 -35.156282) (xy 433.858632 -35.228825) (xy 433.899853 -35.305775)
			(xy 433.91709 -35.345878) (xy 433.921371 -35.35491) (xy 433.93549 -35.369029) (xy 433.944522 -35.37331)
			(xy 433.984626 -35.390543) (xy 434.061569 -35.43177) (xy 434.134105 -35.480334) (xy 434.201536 -35.535768)
			(xy 434.263216 -35.597538) (xy 434.31855 -35.665052) (xy 434.367006 -35.737659) (xy 434.40812 -35.814663)
			(xy 434.441495 -35.895323) (xy 434.466812 -35.978863) (xy 434.483826 -36.064481) (xy 434.492374 -36.151354)
			(xy 434.492908 -36.195) (xy 434.492433 -36.236102) (xy 434.484848 -36.317957) (xy 434.469743 -36.398762)
			(xy 434.447247 -36.477829) (xy 434.417551 -36.554483) (xy 434.380909 -36.62807) (xy 434.337634 -36.697962)
			(xy 434.288094 -36.763563) (xy 434.244941 -36.8109) (xy 434.491184 -36.8109) (xy 434.495214 -36.72628)
			(xy 434.507271 -36.642425) (xy 434.527244 -36.560097) (xy 434.554952 -36.48004) (xy 434.590144 -36.402979)
			(xy 434.632502 -36.329613) (xy 434.681643 -36.260605) (xy 434.73712 -36.19658) (xy 434.798432 -36.138119)
			(xy 434.865024 -36.085751) (xy 434.936292 -36.03995) (xy 435.011591 -36.001131) (xy 435.090239 -35.969645)
			(xy 435.171524 -35.945777) (xy 435.254709 -35.929745) (xy 435.339042 -35.921692) (xy 435.3814 -35.921188)
			(xy 435.424724 -35.921707) (xy 435.51096 -35.930152) (xy 435.595966 -35.946944) (xy 435.678936 -35.971923)
			(xy 435.759084 -36.004852) (xy 435.835649 -36.045419) (xy 435.907907 -36.09324) (xy 435.975171 -36.14786)
			(xy 436.036806 -36.208764) (xy 436.064914 -36.241736) (xy 436.074039 -36.251976) (xy 436.096545 -36.267631)
			(xy 436.122405 -36.276738) (xy 436.149754 -36.278639) (xy 436.176625 -36.273198) (xy 436.201081 -36.260808)
			(xy 436.221361 -36.242359) (xy 436.236004 -36.219182) (xy 436.243956 -36.192944) (xy 436.244746 -36.179252)
			(xy 436.246331 -36.136289) (xy 436.256726 -36.050941) (xy 436.275308 -35.966994) (xy 436.301904 -35.885232)
			(xy 436.336264 -35.806417) (xy 436.378069 -35.731286) (xy 436.426928 -35.660539) (xy 436.482386 -35.594836)
			(xy 436.543924 -35.534791) (xy 436.610969 -35.480964) (xy 436.682894 -35.433858) (xy 436.75903 -35.393911)
			(xy 436.838664 -35.361497) (xy 436.921055 -35.336917) (xy 437.005433 -35.320403) (xy 437.091011 -35.312107)
			(xy 437.134 -35.311588) (xy 437.176363 -35.311992) (xy 437.260705 -35.320046) (xy 437.3439 -35.33608)
			(xy 437.425194 -35.35995) (xy 437.503851 -35.39144) (xy 437.579158 -35.430263) (xy 437.650434 -35.47607)
			(xy 437.717033 -35.528444) (xy 437.778352 -35.586911) (xy 437.833836 -35.650943) (xy 437.882982 -35.719959)
			(xy 437.925345 -35.793333) (xy 437.960541 -35.870403) (xy 437.988252 -35.950469) (xy 438.008227 -36.032806)
			(xy 438.020285 -36.11667) (xy 438.024317 -36.2013) (xy 438.020285 -36.28593) (xy 438.008227 -36.369794)
			(xy 437.988252 -36.452131) (xy 437.960541 -36.532197) (xy 437.960515 -36.532255) (xy 438.381136 -36.532255)
			(xy 438.381136 -36.447533) (xy 438.389189 -36.363196) (xy 438.405223 -36.280006) (xy 438.429091 -36.198716)
			(xy 438.460579 -36.120064) (xy 438.499401 -36.044761) (xy 438.545204 -35.973489) (xy 438.597575 -35.906893)
			(xy 438.65604 -35.845578) (xy 438.720068 -35.790097) (xy 438.78908 -35.740954) (xy 438.86245 -35.698594)
			(xy 438.939515 -35.663399) (xy 439.019577 -35.63569) (xy 439.10191 -35.615716) (xy 439.185769 -35.603659)
			(xy 439.270394 -35.599628) (xy 439.355019 -35.603659) (xy 439.438878 -35.615716) (xy 439.521211 -35.63569)
			(xy 439.601273 -35.663399) (xy 439.678338 -35.698594) (xy 439.751708 -35.740954) (xy 439.82072 -35.790097)
			(xy 439.884748 -35.845578) (xy 439.943213 -35.906893) (xy 439.995584 -35.973489) (xy 440.041387 -36.044761)
			(xy 440.080209 -36.120064) (xy 440.111697 -36.198716) (xy 440.11262 -36.201858) (xy 447.166492 -36.201858)
			(xy 447.166492 -36.20135) (xy 447.167051 -36.158558) (xy 447.175274 -36.073369) (xy 447.191638 -35.989363)
			(xy 447.215994 -35.907317) (xy 447.248115 -35.827989) (xy 447.287705 -35.752111) (xy 447.334397 -35.680386)
			(xy 447.387761 -35.613475) (xy 447.447304 -35.551998) (xy 447.512474 -35.496522) (xy 447.58267 -35.44756)
			(xy 447.657243 -35.405565) (xy 447.735504 -35.370925) (xy 447.81673 -35.343959) (xy 447.900169 -35.324917)
			(xy 447.985052 -35.313975) (xy 448.027806 -35.312096) (xy 448.040474 -35.311086) (xy 448.062464 -35.298405)
			(xy 448.069716 -35.287966) (xy 448.12077 -35.205162) (xy 448.122294 -35.179762) (xy 448.11696 -35.168332)
			(xy 448.101419 -35.133431) (xy 448.075676 -35.061492) (xy 448.056202 -34.987609) (xy 448.043142 -34.912328)
			(xy 448.036593 -34.836203) (xy 448.036188 -34.798) (xy 448.036666 -34.756905) (xy 448.044248 -34.675066)
			(xy 448.059348 -34.594275) (xy 448.081836 -34.515221) (xy 448.111521 -34.43858) (xy 448.14815 -34.365003)
			(xy 448.19141 -34.29512) (xy 448.240933 -34.229525) (xy 448.296296 -34.168778) (xy 448.357026 -34.113398)
			(xy 448.422607 -34.063856) (xy 448.492478 -34.020576) (xy 448.566044 -33.983926) (xy 448.642677 -33.954218)
			(xy 448.721724 -33.931707) (xy 448.80251 -33.916584) (xy 448.884347 -33.908978) (xy 448.925442 -33.908492)
			(xy 448.92595 -33.908492) (xy 448.965051 -33.908898) (xy 449.04295 -33.915772) (xy 449.119944 -33.929461)
			(xy 449.195439 -33.949859) (xy 449.268849 -33.976811) (xy 449.30441 -33.993074) (xy 449.314797 -33.997309)
			(xy 449.337203 -33.997309) (xy 449.34759 -33.993074) (xy 449.383157 -33.976829) (xy 449.456572 -33.949898)
			(xy 449.532066 -33.929508) (xy 449.609056 -33.915817) (xy 449.686951 -33.90893) (xy 449.72605 -33.908492)
			(xy 449.767155 -33.90906) (xy 449.849014 -33.91664) (xy 449.929824 -33.931738) (xy 450.008898 -33.954227)
			(xy 450.085559 -33.983915) (xy 450.159155 -34.020549) (xy 450.229057 -34.063816) (xy 450.29467 -34.113346)
			(xy 450.355433 -34.168719) (xy 450.41083 -34.229461) (xy 450.460386 -34.295054) (xy 450.503681 -34.364939)
			(xy 450.540343 -34.438521) (xy 450.570061 -34.51517) (xy 450.592582 -34.594235) (xy 450.607712 -34.67504)
			(xy 450.615324 -34.756896) (xy 450.615812 -34.798) (xy 450.615332 -34.839817) (xy 450.607471 -34.92308)
			(xy 450.591827 -35.005238) (xy 450.568539 -35.085564) (xy 450.537812 -35.163349) (xy 450.519292 -35.200844)
			(xy 450.519292 -35.201098) (xy 450.514704 -35.211349) (xy 450.514055 -35.23377) (xy 450.518022 -35.244278)
			(xy 450.549518 -35.316414) (xy 450.554546 -35.326449) (xy 450.571416 -35.341212) (xy 450.58203 -35.344862)
			(xy 450.582284 -35.344862) (xy 450.621839 -35.356469) (xy 450.698811 -35.385993) (xy 450.772722 -35.422512)
			(xy 450.842936 -35.465712) (xy 450.908853 -35.515224) (xy 450.969906 -35.570621) (xy 451.025572 -35.63143)
			(xy 451.075373 -35.697128) (xy 451.118882 -35.767151) (xy 451.155726 -35.8409) (xy 451.185589 -35.917741)
			(xy 451.208214 -35.997016) (xy 451.223408 -36.078044) (xy 451.23104 -36.16013) (xy 451.231508 -36.20135)
			(xy 451.23094 -36.242455) (xy 451.22336 -36.324314) (xy 451.208262 -36.405124) (xy 451.185773 -36.484198)
			(xy 451.156085 -36.560859) (xy 451.119451 -36.634455) (xy 451.076184 -36.704357) (xy 451.026654 -36.76997)
			(xy 450.971281 -36.830733) (xy 450.910539 -36.88613) (xy 450.844946 -36.935686) (xy 450.775061 -36.978981)
			(xy 450.701479 -37.015643) (xy 450.62483 -37.045361) (xy 450.545765 -37.067882) (xy 450.46496 -37.083012)
			(xy 450.383104 -37.090624) (xy 450.342 -37.091112) (xy 450.300488 -37.09062) (xy 450.217828 -37.082852)
			(xy 450.136252 -37.067412) (xy 450.056471 -37.044434) (xy 449.979179 -37.014119) (xy 449.90505 -36.97673)
			(xy 449.83473 -36.932593) (xy 449.801488 -36.907724) (xy 449.792289 -36.901381) (xy 449.7705 -36.89655)
			(xy 449.748711 -36.901381) (xy 449.739512 -36.907724) (xy 449.706254 -36.932568) (xy 449.635928 -36.97669)
			(xy 449.561799 -37.014069) (xy 449.48451 -37.044382) (xy 449.404734 -37.067365) (xy 449.323164 -37.082817)
			(xy 449.24051 -37.090605) (xy 449.199 -37.091112) (xy 449.157488 -37.09062) (xy 449.074828 -37.082852)
			(xy 448.993252 -37.067412) (xy 448.913471 -37.044434) (xy 448.836179 -37.014119) (xy 448.76205 -36.97673)
			(xy 448.69173 -36.932593) (xy 448.658488 -36.907724) (xy 448.649289 -36.901381) (xy 448.6275 -36.89655)
			(xy 448.605711 -36.901381) (xy 448.596512 -36.907724) (xy 448.563254 -36.932568) (xy 448.492928 -36.97669)
			(xy 448.418799 -37.014069) (xy 448.34151 -37.044382) (xy 448.261734 -37.067365) (xy 448.180164 -37.082817)
			(xy 448.09751 -37.090605) (xy 448.056 -37.091112) (xy 448.014905 -37.090634) (xy 447.933066 -37.083052)
			(xy 447.852275 -37.067952) (xy 447.773221 -37.045464) (xy 447.69658 -37.015779) (xy 447.623003 -36.97915)
			(xy 447.55312 -36.93589) (xy 447.487525 -36.886367) (xy 447.426778 -36.831004) (xy 447.371398 -36.770274)
			(xy 447.321856 -36.704693) (xy 447.278576 -36.634822) (xy 447.241926 -36.561256) (xy 447.212218 -36.484623)
			(xy 447.189707 -36.405576) (xy 447.174584 -36.32479) (xy 447.166978 -36.242953) (xy 447.166492 -36.201858)
			(xy 440.11262 -36.201858) (xy 440.135565 -36.280006) (xy 440.151599 -36.363196) (xy 440.159652 -36.447533)
			(xy 440.160156 -36.489894) (xy 440.159652 -36.532255) (xy 440.151599 -36.616592) (xy 440.135565 -36.699782)
			(xy 440.111697 -36.781072) (xy 440.080209 -36.859724) (xy 440.041387 -36.935027) (xy 439.995584 -37.006299)
			(xy 439.943213 -37.072895) (xy 439.884748 -37.13421) (xy 439.82072 -37.189691) (xy 439.751708 -37.238834)
			(xy 439.678338 -37.281194) (xy 439.601273 -37.316389) (xy 439.521211 -37.344098) (xy 439.438878 -37.364072)
			(xy 439.355019 -37.376129) (xy 439.270394 -37.380161) (xy 439.185769 -37.376129) (xy 439.10191 -37.364072)
			(xy 439.019577 -37.344098) (xy 438.939515 -37.316389) (xy 438.86245 -37.281194) (xy 438.78908 -37.238834)
			(xy 438.720068 -37.189691) (xy 438.65604 -37.13421) (xy 438.597575 -37.072895) (xy 438.545204 -37.006299)
			(xy 438.499401 -36.935027) (xy 438.460579 -36.859724) (xy 438.429091 -36.781072) (xy 438.405223 -36.699782)
			(xy 438.389189 -36.616592) (xy 438.381136 -36.532255) (xy 437.960515 -36.532255) (xy 437.925345 -36.609267)
			(xy 437.882982 -36.682641) (xy 437.833836 -36.751657) (xy 437.778352 -36.815689) (xy 437.717033 -36.874156)
			(xy 437.650434 -36.92653) (xy 437.579158 -36.972337) (xy 437.503851 -37.01116) (xy 437.425194 -37.04265)
			(xy 437.3439 -37.06652) (xy 437.260705 -37.082554) (xy 437.176363 -37.090608) (xy 437.134 -37.091112)
			(xy 437.090676 -37.090593) (xy 437.00444 -37.082148) (xy 436.919434 -37.065356) (xy 436.836464 -37.040377)
			(xy 436.756316 -37.007448) (xy 436.679751 -36.966881) (xy 436.607493 -36.91906) (xy 436.540229 -36.86444)
			(xy 436.478594 -36.803536) (xy 436.450486 -36.770564) (xy 436.441361 -36.760324) (xy 436.418855 -36.744669)
			(xy 436.392995 -36.735562) (xy 436.365646 -36.733661) (xy 436.338775 -36.739102) (xy 436.314319 -36.751492)
			(xy 436.294039 -36.769941) (xy 436.279396 -36.793118) (xy 436.271444 -36.819356) (xy 436.270654 -36.833048)
			(xy 436.269069 -36.876011) (xy 436.258674 -36.961359) (xy 436.240092 -37.045306) (xy 436.213496 -37.127068)
			(xy 436.179136 -37.205883) (xy 436.137331 -37.281014) (xy 436.088472 -37.351761) (xy 436.033014 -37.417464)
			(xy 435.971476 -37.477509) (xy 435.904431 -37.531336) (xy 435.832506 -37.578442) (xy 435.75637 -37.618389)
			(xy 435.676736 -37.650803) (xy 435.594345 -37.675383) (xy 435.509967 -37.691897) (xy 435.424389 -37.700193)
			(xy 435.3814 -37.700712) (xy 435.339042 -37.700108) (xy 435.254709 -37.692055) (xy 435.171524 -37.676023)
			(xy 435.090239 -37.652155) (xy 435.011591 -37.620669) (xy 434.936292 -37.58185) (xy 434.865024 -37.536049)
			(xy 434.798432 -37.483681) (xy 434.73712 -37.42522) (xy 434.681643 -37.361195) (xy 434.632502 -37.292187)
			(xy 434.590144 -37.218821) (xy 434.554952 -37.14176) (xy 434.527244 -37.061703) (xy 434.507271 -36.979375)
			(xy 434.495214 -36.89552) (xy 434.491184 -36.8109) (xy 434.244941 -36.8109) (xy 434.232713 -36.824313)
			(xy 434.171963 -36.879694) (xy 434.106362 -36.929234) (xy 434.03647 -36.972509) (xy 433.962883 -37.009151)
			(xy 433.886229 -37.038847) (xy 433.807162 -37.061343) (xy 433.726357 -37.076448) (xy 433.644502 -37.084033)
			(xy 433.6034 -37.084508) (xy 433.559752 -37.084027) (xy 433.472877 -37.075478) (xy 433.387256 -37.058462)
			(xy 433.303713 -37.033142) (xy 433.223052 -36.999763) (xy 433.146047 -36.958644) (xy 433.073439 -36.910182)
			(xy 433.005927 -36.854842) (xy 432.944158 -36.793156) (xy 432.888728 -36.725718) (xy 432.840168 -36.653175)
			(xy 432.798947 -36.576225) (xy 432.78171 -36.536122) (xy 432.777429 -36.52709) (xy 432.76331 -36.512971)
			(xy 432.754278 -36.50869) (xy 432.714174 -36.491457) (xy 432.637231 -36.45023) (xy 432.564695 -36.401666)
			(xy 432.497264 -36.346232) (xy 432.435584 -36.284462) (xy 432.38025 -36.216948) (xy 432.331794 -36.144341)
			(xy 432.29068 -36.067337) (xy 432.257305 -35.986677) (xy 432.231988 -35.903137) (xy 432.214974 -35.817519)
			(xy 432.206426 -35.730646) (xy 432.205892 -35.687) (xy 424.041237 -35.687) (xy 424.032354 -35.696316)
			(xy 423.968326 -35.751797) (xy 423.899314 -35.80094) (xy 423.825944 -35.8433) (xy 423.748879 -35.878495)
			(xy 423.668817 -35.906204) (xy 423.586484 -35.926178) (xy 423.502625 -35.938235) (xy 423.418 -35.942267)
			(xy 423.333375 -35.938235) (xy 423.249516 -35.926178) (xy 423.167183 -35.906204) (xy 423.087121 -35.878495)
			(xy 423.010056 -35.8433) (xy 422.936686 -35.80094) (xy 422.867674 -35.751797) (xy 422.803646 -35.696316)
			(xy 422.745181 -35.635001) (xy 422.69281 -35.568405) (xy 422.647007 -35.497133) (xy 422.608185 -35.42183)
			(xy 422.576697 -35.343178) (xy 422.552829 -35.261888) (xy 422.536795 -35.178698) (xy 422.528742 -35.094361)
			(xy 422.148258 -35.094361) (xy 422.140205 -35.178698) (xy 422.124171 -35.261888) (xy 422.100303 -35.343178)
			(xy 422.068815 -35.42183) (xy 422.029993 -35.497133) (xy 421.98419 -35.568405) (xy 421.931819 -35.635001)
			(xy 421.873354 -35.696316) (xy 421.809326 -35.751797) (xy 421.740314 -35.80094) (xy 421.666944 -35.8433)
			(xy 421.589879 -35.878495) (xy 421.509817 -35.906204) (xy 421.427484 -35.926178) (xy 421.343625 -35.938235)
			(xy 421.259 -35.942267) (xy 421.174375 -35.938235) (xy 421.090516 -35.926178) (xy 421.008183 -35.906204)
			(xy 420.928121 -35.878495) (xy 420.851056 -35.8433) (xy 420.777686 -35.80094) (xy 420.708674 -35.751797)
			(xy 420.644646 -35.696316) (xy 420.586181 -35.635001) (xy 420.53381 -35.568405) (xy 420.488007 -35.497133)
			(xy 420.449185 -35.42183) (xy 420.417697 -35.343178) (xy 420.393829 -35.261888) (xy 420.377795 -35.178698)
			(xy 420.369742 -35.094361) (xy 393.368981 -35.094361) (xy 395.146981 -36.872361) (xy 404.774142 -36.872361)
			(xy 404.774142 -36.787639) (xy 404.782195 -36.703302) (xy 404.798229 -36.620112) (xy 404.822097 -36.538822)
			(xy 404.853585 -36.46017) (xy 404.892407 -36.384867) (xy 404.93821 -36.313595) (xy 404.990581 -36.246999)
			(xy 405.049046 -36.185684) (xy 405.113074 -36.130203) (xy 405.182086 -36.08106) (xy 405.255456 -36.0387)
			(xy 405.332521 -36.003505) (xy 405.412583 -35.975796) (xy 405.494916 -35.955822) (xy 405.578775 -35.943765)
			(xy 405.6634 -35.939734) (xy 405.748025 -35.943765) (xy 405.831884 -35.955822) (xy 405.914217 -35.975796)
			(xy 405.994279 -36.003505) (xy 406.071344 -36.0387) (xy 406.144714 -36.08106) (xy 406.213726 -36.130203)
			(xy 406.277754 -36.185684) (xy 406.336219 -36.246999) (xy 406.38859 -36.313595) (xy 406.434393 -36.384867)
			(xy 406.473215 -36.46017) (xy 406.504703 -36.538822) (xy 406.528571 -36.620112) (xy 406.544605 -36.703302)
			(xy 406.552658 -36.787639) (xy 406.553162 -36.83) (xy 406.552658 -36.872361) (xy 406.544605 -36.956698)
			(xy 406.528571 -37.039888) (xy 406.504703 -37.121178) (xy 406.473215 -37.19983) (xy 406.434393 -37.275133)
			(xy 406.38859 -37.346405) (xy 406.336219 -37.413001) (xy 406.277754 -37.474316) (xy 406.213726 -37.529797)
			(xy 406.144714 -37.57894) (xy 406.071344 -37.6213) (xy 405.994279 -37.656495) (xy 405.914217 -37.684204)
			(xy 405.831884 -37.704178) (xy 405.748025 -37.716235) (xy 405.6634 -37.720267) (xy 405.578775 -37.716235)
			(xy 405.494916 -37.704178) (xy 405.412583 -37.684204) (xy 405.332521 -37.656495) (xy 405.255456 -37.6213)
			(xy 405.182086 -37.57894) (xy 405.113074 -37.529797) (xy 405.049046 -37.474316) (xy 404.990581 -37.413001)
			(xy 404.93821 -37.346405) (xy 404.892407 -37.275133) (xy 404.853585 -37.19983) (xy 404.822097 -37.121178)
			(xy 404.798229 -37.039888) (xy 404.782195 -36.956698) (xy 404.774142 -36.872361) (xy 395.146981 -36.872361)
			(xy 396.101824 -37.827204) (xy 410.107892 -37.827204) (xy 410.107892 -37.82695) (xy 410.10846 -37.785845)
			(xy 410.11604 -37.703986) (xy 410.131138 -37.623176) (xy 410.153627 -37.544102) (xy 410.183315 -37.467441)
			(xy 410.219949 -37.393845) (xy 410.263216 -37.323943) (xy 410.312746 -37.25833) (xy 410.368119 -37.197567)
			(xy 410.428861 -37.14217) (xy 410.494454 -37.092614) (xy 410.564339 -37.049319) (xy 410.637921 -37.012657)
			(xy 410.71457 -36.982939) (xy 410.793635 -36.960418) (xy 410.87444 -36.945288) (xy 410.956296 -36.937676)
			(xy 410.9974 -36.937188) (xy 411.041554 -36.937734) (xy 411.129428 -36.946487) (xy 411.216001 -36.963906)
			(xy 411.300421 -36.98982) (xy 411.381857 -37.023974) (xy 411.459507 -37.066032) (xy 411.532606 -37.115579)
			(xy 411.566868 -37.143436) (xy 411.574458 -37.149318) (xy 411.592654 -37.155417) (xy 411.611818 -37.154415)
			(xy 411.620716 -37.150802) (xy 411.717236 -37.106352) (xy 411.733238 -37.081968) (xy 411.733492 -37.067236)
			(xy 411.734787 -37.025139) (xy 411.744319 -36.941451) (xy 411.76172 -36.85904) (xy 411.786834 -36.778642)
			(xy 411.819437 -36.700979) (xy 411.838902 -36.66363) (xy 411.84432 -36.652164) (xy 411.84432 -36.626836)
			(xy 411.838902 -36.61537) (xy 411.818699 -36.576575) (xy 411.785177 -36.495778) (xy 411.759741 -36.412082)
			(xy 411.742637 -36.326296) (xy 411.734027 -36.239245) (xy 411.733492 -36.195508) (xy 411.733492 -36.195)
			(xy 411.733996 -36.152652) (xy 411.742047 -36.068338) (xy 411.758076 -35.985172) (xy 411.781937 -35.903905)
			(xy 411.813416 -35.825275) (xy 411.852227 -35.749994) (xy 411.898017 -35.678742) (xy 411.950373 -35.612166)
			(xy 412.008821 -35.550868) (xy 412.072831 -35.495403) (xy 412.141823 -35.446274) (xy 412.215173 -35.403925)
			(xy 412.292216 -35.368741) (xy 412.372255 -35.341039) (xy 412.454564 -35.321071) (xy 412.538399 -35.309018)
			(xy 412.623 -35.304988) (xy 412.707601 -35.309018) (xy 412.791436 -35.321071) (xy 412.873745 -35.341039)
			(xy 412.953784 -35.368741) (xy 413.030827 -35.403925) (xy 413.104177 -35.446274) (xy 413.173169 -35.495403)
			(xy 413.237179 -35.550868) (xy 413.295627 -35.612166) (xy 413.347983 -35.678742) (xy 413.393773 -35.749994)
			(xy 413.432584 -35.825275) (xy 413.464063 -35.903905) (xy 413.487924 -35.985172) (xy 413.503953 -36.068338)
			(xy 413.512004 -36.152652) (xy 413.512508 -36.195) (xy 413.512508 -36.195508) (xy 413.511989 -36.239272)
			(xy 413.503414 -36.326378) (xy 413.486318 -36.412219) (xy 413.460867 -36.495965) (xy 413.427307 -36.576803)
			(xy 413.407098 -36.615624) (xy 413.401771 -36.626977) (xy 413.401771 -36.652023) (xy 413.407098 -36.663376)
			(xy 413.427292 -36.702204) (xy 413.460832 -36.783047) (xy 413.486277 -36.866792) (xy 413.503382 -36.952629)
			(xy 413.511981 -37.03973) (xy 413.512508 -37.083492) (xy 413.512508 -37.084) (xy 413.512033 -37.125102)
			(xy 413.504448 -37.206957) (xy 413.489343 -37.287762) (xy 413.466847 -37.366829) (xy 413.437151 -37.443483)
			(xy 413.400509 -37.51707) (xy 413.357234 -37.586962) (xy 413.307694 -37.652563) (xy 413.252313 -37.713313)
			(xy 413.191563 -37.768694) (xy 413.125962 -37.818234) (xy 413.05607 -37.861509) (xy 412.982483 -37.898151)
			(xy 412.905829 -37.927847) (xy 412.826762 -37.950343) (xy 412.745957 -37.965448) (xy 412.664102 -37.973033)
			(xy 412.623 -37.973508) (xy 412.622492 -37.973508) (xy 412.578382 -37.972948) (xy 412.490596 -37.964185)
			(xy 412.40411 -37.946775) (xy 412.319772 -37.92089) (xy 412.238409 -37.886784) (xy 412.160823 -37.844792)
			(xy 412.087774 -37.795326) (xy 412.053532 -37.767514) (xy 412.045943 -37.76163) (xy 412.027747 -37.755537)
			(xy 412.008583 -37.756538) (xy 411.999684 -37.760148) (xy 411.903164 -37.804598) (xy 411.887162 -37.828982)
			(xy 411.886908 -37.843714) (xy 411.885587 -37.886923) (xy 411.875568 -37.972794) (xy 411.85727 -38.057289)
			(xy 411.830864 -38.13961) (xy 411.796598 -38.218983) (xy 411.754797 -38.294659) (xy 411.705854 -38.365924)
			(xy 411.650231 -38.432107) (xy 411.6197 -38.462712) (xy 411.612773 -38.470152) (xy 411.604912 -38.488879)
			(xy 411.60446 -38.499034) (xy 411.604206 -38.581838) (xy 411.612334 -38.600888) (xy 411.6197 -38.608)
			(xy 411.647813 -38.636158) (xy 411.699451 -38.696703) (xy 411.722824 -38.728904) (xy 411.729221 -38.737098)
			(xy 411.746974 -38.747878) (xy 411.767545 -38.750744) (xy 411.777688 -38.748462) (xy 411.816148 -38.738345)
			(xy 411.894416 -38.724213) (xy 411.973633 -38.717137) (xy 412.0134 -38.716712) (xy 412.053666 -38.717185)
			(xy 412.133867 -38.724466) (xy 412.213082 -38.738968) (xy 412.290661 -38.760572) (xy 412.365969 -38.789102)
			(xy 412.43839 -38.824324) (xy 412.507329 -38.865949) (xy 412.572223 -38.913636) (xy 412.60268 -38.939978)
			(xy 412.609686 -38.945736) (xy 412.626579 -38.9523) (xy 412.6447 -38.952573) (xy 412.661784 -38.946521)
			(xy 412.668974 -38.940994) (xy 412.703274 -38.913119) (xy 412.776431 -38.863511) (xy 412.854146 -38.821399)
			(xy 412.935652 -38.787201) (xy 413.020148 -38.761251) (xy 413.1068 -38.743806) (xy 413.194755 -38.735038)
			(xy 413.23895 -38.734492) (xy 413.281301 -38.734978) (xy 413.365619 -38.743025) (xy 413.448791 -38.75905)
			(xy 413.530062 -38.78291) (xy 413.608698 -38.814387) (xy 413.683985 -38.853196) (xy 413.73396 -38.885311)
			(xy 414.400742 -38.885311) (xy 414.400742 -38.800589) (xy 414.408795 -38.716252) (xy 414.424829 -38.633062)
			(xy 414.448697 -38.551772) (xy 414.480185 -38.47312) (xy 414.519007 -38.397817) (xy 414.56481 -38.326545)
			(xy 414.617181 -38.259949) (xy 414.675646 -38.198634) (xy 414.739674 -38.143153) (xy 414.808686 -38.09401)
			(xy 414.882056 -38.05165) (xy 414.959121 -38.016455) (xy 415.039183 -37.988746) (xy 415.121516 -37.968772)
			(xy 415.205375 -37.956715) (xy 415.29 -37.952684) (xy 415.374625 -37.956715) (xy 415.458484 -37.968772)
			(xy 415.540817 -37.988746) (xy 415.620879 -38.016455) (xy 415.697944 -38.05165) (xy 415.771314 -38.09401)
			(xy 415.840326 -38.143153) (xy 415.904354 -38.198634) (xy 415.962819 -38.259949) (xy 416.01519 -38.326545)
			(xy 416.060993 -38.397817) (xy 416.099815 -38.47312) (xy 416.131303 -38.551772) (xy 416.155171 -38.633062)
			(xy 416.171205 -38.716252) (xy 416.179258 -38.800589) (xy 416.179762 -38.84295) (xy 416.179258 -38.885311)
			(xy 416.171205 -38.969648) (xy 416.155171 -39.052838) (xy 416.131303 -39.134128) (xy 416.099815 -39.21278)
			(xy 416.060993 -39.288083) (xy 416.01519 -39.359355) (xy 415.962819 -39.425951) (xy 415.904354 -39.487266)
			(xy 415.840326 -39.542747) (xy 415.771314 -39.59189) (xy 415.697944 -39.63425) (xy 415.620879 -39.669445)
			(xy 415.540817 -39.697154) (xy 415.458484 -39.717128) (xy 415.374625 -39.729185) (xy 415.29 -39.733217)
			(xy 415.205375 -39.729185) (xy 415.121516 -39.717128) (xy 415.039183 -39.697154) (xy 414.959121 -39.669445)
			(xy 414.882056 -39.63425) (xy 414.808686 -39.59189) (xy 414.739674 -39.542747) (xy 414.675646 -39.487266)
			(xy 414.617181 -39.425951) (xy 414.56481 -39.359355) (xy 414.519007 -39.288083) (xy 414.480185 -39.21278)
			(xy 414.448697 -39.134128) (xy 414.424829 -39.052838) (xy 414.408795 -38.969648) (xy 414.400742 -38.885311)
			(xy 413.73396 -38.885311) (xy 413.755242 -38.898987) (xy 413.821824 -38.951344) (xy 413.883127 -39.009793)
			(xy 413.938596 -39.073805) (xy 413.987729 -39.142799) (xy 414.030081 -39.216152) (xy 414.065269 -39.293199)
			(xy 414.092973 -39.373241) (xy 414.112943 -39.455555) (xy 414.124998 -39.539394) (xy 414.129028 -39.624)
			(xy 414.124998 -39.708606) (xy 414.112943 -39.792445) (xy 414.092973 -39.874759) (xy 414.065269 -39.954801)
			(xy 414.030081 -40.031848) (xy 413.987729 -40.105201) (xy 413.938596 -40.174195) (xy 413.883127 -40.238207)
			(xy 413.821824 -40.296656) (xy 413.755242 -40.349013) (xy 413.683985 -40.394804) (xy 413.608698 -40.433613)
			(xy 413.530062 -40.46509) (xy 413.448791 -40.48895) (xy 413.365619 -40.504975) (xy 413.281301 -40.513022)
			(xy 413.23895 -40.513508) (xy 413.238696 -40.513508) (xy 413.198453 -40.513042) (xy 413.118296 -40.505763)
			(xy 413.039124 -40.491273) (xy 412.961585 -40.469691) (xy 412.886312 -40.441193) (xy 412.813921 -40.406013)
			(xy 412.745004 -40.364438) (xy 412.680124 -40.316808) (xy 412.64967 -40.290496) (xy 412.642629 -40.284787)
			(xy 412.625752 -40.278219) (xy 412.607643 -40.277932) (xy 412.590567 -40.283964) (xy 412.583376 -40.28948)
			(xy 412.549106 -40.317404) (xy 412.475958 -40.367055) (xy 412.398247 -40.409206) (xy 412.316738 -40.443441)
			(xy 412.232235 -40.469422) (xy 412.145572 -40.486893) (xy 412.057603 -40.495681) (xy 412.0134 -40.496236)
			(xy 411.970907 -40.495762) (xy 411.886307 -40.487662) (xy 411.802867 -40.471527) (xy 411.721347 -40.447505)
			(xy 411.64249 -40.415813) (xy 411.567018 -40.376742) (xy 411.495618 -40.330648) (xy 411.428941 -40.277951)
			(xy 411.367597 -40.219133) (xy 411.312145 -40.15473) (xy 411.287214 -40.120316) (xy 411.280772 -40.112151)
			(xy 411.263065 -40.101292) (xy 411.24251 -40.098297) (xy 411.23235 -40.100504) (xy 411.19409 -40.110528)
			(xy 411.116242 -40.12454) (xy 411.037457 -40.131571) (xy 410.997908 -40.132) (xy 410.9974 -40.132)
			(xy 410.956321 -40.131526) (xy 410.874513 -40.123945) (xy 410.793754 -40.108849) (xy 410.714732 -40.086365)
			(xy 410.638122 -40.056686) (xy 410.564577 -40.020065) (xy 410.494725 -39.976815) (xy 410.429162 -39.927303)
			(xy 410.368446 -39.871954) (xy 410.313097 -39.811238) (xy 410.263585 -39.745675) (xy 410.220335 -39.675823)
			(xy 410.183714 -39.602278) (xy 410.154035 -39.525668) (xy 410.131551 -39.446646) (xy 410.116455 -39.365887)
			(xy 410.108874 -39.284079) (xy 410.1084 -39.243) (xy 410.108974 -39.198782) (xy 410.117757 -39.110783)
			(xy 410.135237 -39.024091) (xy 410.161241 -38.939564) (xy 410.195511 -38.858038) (xy 410.237709 -38.780319)
			(xy 410.287417 -38.707174) (xy 410.344144 -38.639329) (xy 410.375354 -38.608) (xy 410.382269 -38.600551)
			(xy 410.390138 -38.581831) (xy 410.390594 -38.571678) (xy 410.39034 -38.499034) (xy 410.389898 -38.488875)
			(xy 410.382045 -38.470139) (xy 410.3751 -38.462712) (xy 410.343853 -38.431366) (xy 410.287061 -38.363475)
			(xy 410.237296 -38.290277) (xy 410.195051 -38.212496) (xy 410.160744 -38.130902) (xy 410.134715 -38.046303)
			(xy 410.117221 -37.959536) (xy 410.108435 -37.87146) (xy 410.107892 -37.827204) (xy 396.101824 -37.827204)
			(xy 402.466556 -44.191936) (xy 402.489712 -44.215816) (xy 402.53022 -44.268579) (xy 402.563491 -44.32618)
			(xy 402.588956 -44.387632) (xy 402.606179 -44.451883) (xy 402.614866 -44.517832) (xy 402.6154 -44.551092)
			(xy 402.6154 -45.212) (xy 411.377892 -45.212) (xy 411.378395 -45.168516) (xy 411.38688 -45.081963)
			(xy 411.40377 -44.996652) (xy 411.428903 -44.913395) (xy 411.46204 -44.832988) (xy 411.502864 -44.756197)
			(xy 411.550986 -44.683756) (xy 411.605946 -44.616357) (xy 411.63621 -44.585128) (xy 411.636464 -44.584874)
			(xy 411.643046 -44.577496) (xy 411.650484 -44.559192) (xy 411.650942 -44.549314) (xy 411.650942 -44.477686)
			(xy 411.650508 -44.467805) (xy 411.643049 -44.449506) (xy 411.636464 -44.442126) (xy 411.63621 -44.441872)
			(xy 411.605945 -44.410646) (xy 411.55099 -44.343243) (xy 411.502874 -44.2708) (xy 411.462054 -44.194009)
			(xy 411.428921 -44.113602) (xy 411.40379 -44.030345) (xy 411.386902 -43.945035) (xy 411.378418 -43.858483)
			(xy 411.377892 -43.815) (xy 411.378407 -43.7718) (xy 411.386773 -43.685806) (xy 411.403435 -43.601028)
			(xy 411.428238 -43.518264) (xy 411.460946 -43.438295) (xy 411.501253 -43.361873) (xy 411.548778 -43.289718)
			(xy 411.603073 -43.22251) (xy 411.663628 -43.160881) (xy 411.729872 -43.105414) (xy 411.801181 -43.056629)
			(xy 411.876884 -43.014986) (xy 411.956266 -42.980878) (xy 412.038581 -42.954625) (xy 412.08071 -42.94505)
			(xy 412.091378 -42.942764) (xy 412.10865 -42.930318) (xy 412.157418 -42.846498) (xy 412.159704 -42.825162)
			(xy 412.156402 -42.815002) (xy 412.143099 -42.771289) (xy 412.124447 -42.681837) (xy 412.115074 -42.590942)
			(xy 412.114492 -42.545254) (xy 412.114492 -42.545) (xy 412.114995 -42.502685) (xy 412.123026 -42.418437)
			(xy 412.139024 -42.335334) (xy 412.162845 -42.254125) (xy 412.194272 -42.175548) (xy 412.233023 -42.100311)
			(xy 412.255462 -42.064432) (xy 412.260345 -42.056043) (xy 412.264017 -42.037) (xy 412.260345 -42.017957)
			(xy 412.255462 -42.009568) (xy 412.233016 -41.973694) (xy 412.194273 -41.898453) (xy 412.162849 -41.819874)
			(xy 412.13903 -41.738665) (xy 412.12303 -41.655562) (xy 412.114994 -41.571315) (xy 412.114492 -41.529)
			(xy 412.114996 -41.486652) (xy 412.123047 -41.402338) (xy 412.139076 -41.319172) (xy 412.162937 -41.237905)
			(xy 412.194416 -41.159275) (xy 412.233227 -41.083994) (xy 412.279017 -41.012742) (xy 412.331373 -40.946166)
			(xy 412.389821 -40.884868) (xy 412.453831 -40.829403) (xy 412.522823 -40.780274) (xy 412.596173 -40.737925)
			(xy 412.673216 -40.702741) (xy 412.753255 -40.675039) (xy 412.835564 -40.655071) (xy 412.919399 -40.643018)
			(xy 413.004 -40.638988) (xy 413.088601 -40.643018) (xy 413.172436 -40.655071) (xy 413.254745 -40.675039)
			(xy 413.334784 -40.702741) (xy 413.337002 -40.703754) (xy 424.903392 -40.703754) (xy 424.903849 -40.661101)
			(xy 424.912002 -40.576186) (xy 424.928247 -40.492441) (xy 424.952436 -40.410636) (xy 424.984346 -40.331523)
			(xy 425.023683 -40.255829) (xy 425.070087 -40.184248) (xy 425.123132 -40.11744) (xy 425.182329 -40.056017)
			(xy 425.247135 -40.000543) (xy 425.316954 -39.951529) (xy 425.391145 -39.909426) (xy 425.469027 -39.874618)
			(xy 425.549883 -39.847428) (xy 425.632972 -39.828103) (xy 425.717528 -39.816823) (xy 425.760134 -39.814754)
			(xy 425.76984 -39.813914) (xy 425.787603 -39.805957) (xy 425.794678 -39.79926) (xy 425.816014 -39.77767)
			(xy 425.822523 -39.770396) (xy 425.829961 -39.752365) (xy 425.830492 -39.742618) (xy 425.831369 -39.699212)
			(xy 425.840651 -39.612885) (xy 425.8583 -39.527873) (xy 425.884147 -39.444984) (xy 425.917946 -39.365008)
			(xy 425.959376 -39.288706) (xy 426.008043 -39.216802) (xy 426.063483 -39.149982) (xy 426.125169 -39.088881)
			(xy 426.192515 -39.034081) (xy 426.264879 -38.986102) (xy 426.341574 -38.945401) (xy 426.421868 -38.912366)
			(xy 426.504999 -38.887311) (xy 426.590176 -38.870474) (xy 426.676588 -38.862015) (xy 426.72 -38.861492)
			(xy 426.76125 -38.86197) (xy 426.843397 -38.8696) (xy 426.924485 -38.884802) (xy 427.003816 -38.907447)
			(xy 427.080711 -38.93734) (xy 427.154507 -38.974224) (xy 427.224571 -39.017783) (xy 427.257718 -39.04234)
			(xy 427.26686 -39.048574) (xy 427.288452 -39.053308) (xy 427.310044 -39.048574) (xy 427.319186 -39.04234)
			(xy 427.327822 -39.03599) (xy 427.337039 -39.028283) (xy 427.347787 -39.006838) (xy 427.348396 -38.994842)
			(xy 427.348396 -38.989) (xy 427.348898 -38.945516) (xy 427.357383 -38.858963) (xy 427.374273 -38.773652)
			(xy 427.399407 -38.690395) (xy 427.432544 -38.609987) (xy 427.473368 -38.533197) (xy 427.52149 -38.460756)
			(xy 427.57645 -38.393357) (xy 427.606714 -38.362128) (xy 427.613826 -38.354762) (xy 427.621446 -38.336474)
			(xy 427.621446 -38.244526) (xy 427.613826 -38.226238) (xy 427.606714 -38.218872) (xy 427.57645 -38.187645)
			(xy 427.521495 -38.120242) (xy 427.473378 -38.0478) (xy 427.432558 -37.971009) (xy 427.399425 -37.890602)
			(xy 427.374295 -37.807345) (xy 427.357406 -37.722035) (xy 427.348922 -37.635483) (xy 427.348396 -37.592)
			(xy 427.348865 -37.548682) (xy 427.357268 -37.462454) (xy 427.374014 -37.377452) (xy 427.398946 -37.294481)
			(xy 427.431825 -37.214327) (xy 427.472341 -37.137748) (xy 427.520111 -37.065472) (xy 427.57468 -36.998182)
			(xy 427.635533 -36.936516) (xy 427.702093 -36.881058) (xy 427.77373 -36.832334) (xy 427.849763 -36.790805)
			(xy 427.889416 -36.773358) (xy 427.899858 -36.768323) (xy 427.915071 -36.750864) (xy 427.918626 -36.73983)
			(xy 427.92998 -36.699895) (xy 427.959056 -36.622123) (xy 427.995253 -36.547399) (xy 428.038254 -36.476372)
			(xy 428.087686 -36.409661) (xy 428.143119 -36.347846) (xy 428.20407 -36.291465) (xy 428.270009 -36.241008)
			(xy 428.340363 -36.196914) (xy 428.414519 -36.159567) (xy 428.491832 -36.129292) (xy 428.571629 -36.106352)
			(xy 428.653217 -36.090947) (xy 428.735885 -36.083211) (xy 428.7774 -36.082732) (xy 428.818504 -36.083152)
			(xy 428.900362 -36.090738) (xy 428.981171 -36.105844) (xy 429.060241 -36.128342) (xy 429.136898 -36.15804)
			(xy 429.210488 -36.194685) (xy 429.280383 -36.237963) (xy 429.345986 -36.287506) (xy 429.406737 -36.342891)
			(xy 429.46212 -36.403645) (xy 429.51166 -36.46925) (xy 429.554935 -36.539147) (xy 429.591576 -36.612738)
			(xy 429.621271 -36.689397) (xy 429.643765 -36.768468) (xy 429.658868 -36.849277) (xy 429.66645 -36.931136)
			(xy 429.666908 -36.97224) (xy 429.666385 -37.015557) (xy 429.657987 -37.101782) (xy 429.641246 -37.186783)
			(xy 429.616321 -37.269754) (xy 429.583447 -37.349908) (xy 429.542936 -37.426486) (xy 429.495171 -37.498762)
			(xy 429.440606 -37.566053) (xy 429.379757 -37.62772) (xy 429.313202 -37.683179) (xy 429.241569 -37.731904)
			(xy 429.165539 -37.773434) (xy 429.125888 -37.790882) (xy 429.115436 -37.7959) (xy 429.100227 -37.813371)
			(xy 429.096678 -37.82441) (xy 429.084062 -37.868717) (xy 429.050928 -37.95468) (xy 429.009085 -38.036758)
			(xy 428.958979 -38.114069) (xy 428.901148 -38.185785) (xy 428.869094 -38.218872) (xy 428.861982 -38.226238)
			(xy 428.854362 -38.244526) (xy 428.854362 -38.336474) (xy 428.861982 -38.354762) (xy 428.869094 -38.362128)
			(xy 428.899358 -38.393357) (xy 428.954318 -38.460757) (xy 429.002439 -38.533197) (xy 429.043263 -38.609988)
			(xy 429.0764 -38.690395) (xy 429.101533 -38.773652) (xy 429.118423 -38.858964) (xy 429.126908 -38.945516)
			(xy 429.126908 -39.032484) (xy 429.118423 -39.119036) (xy 429.101533 -39.204348) (xy 429.0764 -39.287605)
			(xy 429.043263 -39.368012) (xy 429.002439 -39.444803) (xy 428.954318 -39.517243) (xy 428.899358 -39.584643)
			(xy 428.869094 -39.615872) (xy 428.861982 -39.623238) (xy 428.854362 -39.641526) (xy 428.854362 -39.733474)
			(xy 428.861982 -39.751762) (xy 428.869094 -39.759128) (xy 428.900151 -39.791182) (xy 428.956375 -39.860504)
			(xy 429.005378 -39.935106) (xy 429.046667 -40.014239) (xy 429.079828 -40.097107) (xy 429.104526 -40.182878)
			(xy 429.120514 -40.270691) (xy 429.124618 -40.315134) (xy 429.125764 -40.324043) (xy 429.133265 -40.340347)
			(xy 429.145884 -40.353107) (xy 429.153828 -40.357298) (xy 429.191716 -40.375504) (xy 429.264185 -40.418108)
			(xy 429.332312 -40.467359) (xy 429.395488 -40.522818) (xy 429.45315 -40.58399) (xy 429.504783 -40.65033)
			(xy 429.549927 -40.721245) (xy 429.588179 -40.796103) (xy 429.619197 -40.874237) (xy 429.642705 -40.954948)
			(xy 429.658494 -41.037517) (xy 429.666421 -41.121207) (xy 429.666908 -41.16324) (xy 429.666385 -41.206557)
			(xy 429.657987 -41.292782) (xy 429.641246 -41.377783) (xy 429.616321 -41.460754) (xy 429.583447 -41.540908)
			(xy 429.542936 -41.617486) (xy 429.495171 -41.689762) (xy 429.440606 -41.757053) (xy 429.379757 -41.81872)
			(xy 429.313202 -41.874179) (xy 429.241569 -41.922904) (xy 429.165539 -41.964434) (xy 429.125888 -41.981882)
			(xy 429.115436 -41.9869) (xy 429.100227 -42.004371) (xy 429.096678 -42.01541) (xy 429.084062 -42.059717)
			(xy 429.050928 -42.14568) (xy 429.009085 -42.227758) (xy 428.958979 -42.305069) (xy 428.901148 -42.376785)
			(xy 428.869094 -42.409872) (xy 428.861982 -42.417238) (xy 428.854362 -42.435526) (xy 428.854362 -42.527474)
			(xy 428.861982 -42.545762) (xy 428.869094 -42.553128) (xy 428.900151 -42.585182) (xy 428.956375 -42.654504)
			(xy 429.005378 -42.729106) (xy 429.046667 -42.808239) (xy 429.079828 -42.891107) (xy 429.104526 -42.976878)
			(xy 429.120514 -43.064691) (xy 429.124618 -43.109134) (xy 429.125764 -43.118043) (xy 429.133265 -43.134347)
			(xy 429.145884 -43.147107) (xy 429.153828 -43.151298) (xy 429.191716 -43.169504) (xy 429.264185 -43.212108)
			(xy 429.332312 -43.261359) (xy 429.395488 -43.316818) (xy 429.45315 -43.37799) (xy 429.504783 -43.44433)
			(xy 429.549927 -43.515245) (xy 429.588179 -43.590103) (xy 429.619197 -43.668237) (xy 429.642705 -43.748948)
			(xy 429.658494 -43.831517) (xy 429.666421 -43.915207) (xy 429.666908 -43.95724) (xy 429.666385 -44.000557)
			(xy 429.657987 -44.086782) (xy 429.641246 -44.171783) (xy 429.616321 -44.254754) (xy 429.583447 -44.334908)
			(xy 429.542936 -44.411486) (xy 429.495171 -44.483762) (xy 429.440606 -44.551053) (xy 429.379757 -44.61272)
			(xy 429.313202 -44.668179) (xy 429.241569 -44.716904) (xy 429.165539 -44.758434) (xy 429.125888 -44.775882)
			(xy 429.115436 -44.7809) (xy 429.100227 -44.798371) (xy 429.096678 -44.80941) (xy 429.084062 -44.853717)
			(xy 429.050928 -44.93968) (xy 429.009085 -45.021758) (xy 428.958979 -45.099069) (xy 428.901148 -45.170785)
			(xy 428.869094 -45.203872) (xy 428.861982 -45.211238) (xy 428.854362 -45.229526) (xy 428.854362 -45.321474)
			(xy 428.861982 -45.339762) (xy 428.869094 -45.347128) (xy 428.89936 -45.378354) (xy 428.954314 -45.445757)
			(xy 429.002431 -45.518199) (xy 429.04325 -45.594991) (xy 429.076383 -45.675398) (xy 429.101514 -45.758654)
			(xy 429.118402 -45.843965) (xy 429.126886 -45.930517) (xy 429.127412 -45.974) (xy 430.395888 -45.974)
			(xy 430.396394 -45.930494) (xy 430.404888 -45.843897) (xy 430.421796 -45.758543) (xy 430.446954 -45.675247)
			(xy 430.480124 -45.594806) (xy 430.520988 -45.517986) (xy 430.569157 -45.445522) (xy 430.624169 -45.378107)
			(xy 430.65446 -45.346874) (xy 430.661826 -45.339762) (xy 430.669192 -45.321474) (xy 430.669446 -45.229272)
			(xy 430.661826 -45.210984) (xy 430.65446 -45.203872) (xy 430.62424 -45.172612) (xy 430.569318 -45.105202)
			(xy 430.521233 -45.032757) (xy 430.480444 -44.955966) (xy 430.44734 -44.875563) (xy 430.422237 -44.792314)
			(xy 430.405374 -44.707014) (xy 430.396912 -44.620476) (xy 430.396396 -44.577) (xy 430.396898 -44.533516)
			(xy 430.405383 -44.446963) (xy 430.422273 -44.361652) (xy 430.447407 -44.278395) (xy 430.480544 -44.197987)
			(xy 430.521368 -44.121197) (xy 430.56949 -44.048756) (xy 430.62445 -43.981357) (xy 430.654714 -43.950128)
			(xy 430.661826 -43.942762) (xy 430.669446 -43.924474) (xy 430.669446 -43.832526) (xy 430.661826 -43.814238)
			(xy 430.654714 -43.806872) (xy 430.624453 -43.775642) (xy 430.569499 -43.70824) (xy 430.521382 -43.635798)
			(xy 430.480562 -43.559007) (xy 430.447429 -43.4786) (xy 430.422299 -43.395344) (xy 430.405411 -43.310034)
			(xy 430.396927 -43.223483) (xy 430.396927 -43.136517) (xy 430.405411 -43.049966) (xy 430.422299 -42.964656)
			(xy 430.447429 -42.8814) (xy 430.480562 -42.800993) (xy 430.521382 -42.724202) (xy 430.569499 -42.65176)
			(xy 430.624453 -42.584358) (xy 430.654714 -42.553128) (xy 430.661826 -42.545762) (xy 430.669446 -42.527474)
			(xy 430.669446 -42.435526) (xy 430.661826 -42.417238) (xy 430.654714 -42.409872) (xy 430.624453 -42.378642)
			(xy 430.569499 -42.31124) (xy 430.521382 -42.238798) (xy 430.480562 -42.162007) (xy 430.447429 -42.0816)
			(xy 430.422299 -41.998344) (xy 430.405411 -41.913034) (xy 430.396927 -41.826483) (xy 430.396927 -41.739517)
			(xy 430.405411 -41.652966) (xy 430.422299 -41.567656) (xy 430.447429 -41.4844) (xy 430.480562 -41.403993)
			(xy 430.521382 -41.327202) (xy 430.569499 -41.25476) (xy 430.624453 -41.187358) (xy 430.654714 -41.156128)
			(xy 430.661826 -41.148762) (xy 430.669446 -41.130474) (xy 430.669446 -41.038526) (xy 430.661826 -41.020238)
			(xy 430.654714 -41.012872) (xy 430.624453 -40.981642) (xy 430.569499 -40.91424) (xy 430.521382 -40.841798)
			(xy 430.480562 -40.765007) (xy 430.447429 -40.6846) (xy 430.422299 -40.601344) (xy 430.405411 -40.516034)
			(xy 430.396927 -40.429483) (xy 430.396927 -40.342517) (xy 430.405411 -40.255966) (xy 430.422299 -40.170656)
			(xy 430.447429 -40.0874) (xy 430.480562 -40.006993) (xy 430.521382 -39.930202) (xy 430.569499 -39.85776)
			(xy 430.624453 -39.790358) (xy 430.654714 -39.759128) (xy 430.661826 -39.751762) (xy 430.669446 -39.733474)
			(xy 430.669446 -39.641526) (xy 430.661826 -39.623238) (xy 430.654714 -39.615872) (xy 430.624453 -39.584642)
			(xy 430.569499 -39.51724) (xy 430.521382 -39.444798) (xy 430.480562 -39.368007) (xy 430.447429 -39.2876)
			(xy 430.422299 -39.204344) (xy 430.405411 -39.119034) (xy 430.396927 -39.032483) (xy 430.396927 -38.945517)
			(xy 430.405411 -38.858966) (xy 430.422299 -38.773656) (xy 430.447429 -38.6904) (xy 430.480562 -38.609993)
			(xy 430.521382 -38.533202) (xy 430.569499 -38.46076) (xy 430.624453 -38.393358) (xy 430.654714 -38.362128)
			(xy 430.661826 -38.354762) (xy 430.669446 -38.336474) (xy 430.669446 -38.244526) (xy 430.661826 -38.226238)
			(xy 430.654714 -38.218872) (xy 430.62445 -38.187645) (xy 430.569495 -38.120242) (xy 430.521378 -38.0478)
			(xy 430.480558 -37.971009) (xy 430.447425 -37.890602) (xy 430.422295 -37.807345) (xy 430.405406 -37.722035)
			(xy 430.396922 -37.635483) (xy 430.396396 -37.592) (xy 430.3969 -37.549652) (xy 430.404951 -37.465338)
			(xy 430.42098 -37.382172) (xy 430.444841 -37.300905) (xy 430.47632 -37.222275) (xy 430.515131 -37.146994)
			(xy 430.560921 -37.075742) (xy 430.613277 -37.009166) (xy 430.671725 -36.947868) (xy 430.735735 -36.892403)
			(xy 430.804727 -36.843274) (xy 430.878077 -36.800925) (xy 430.95512 -36.765741) (xy 431.035159 -36.738039)
			(xy 431.117468 -36.718071) (xy 431.201303 -36.706018) (xy 431.285904 -36.701988) (xy 431.370505 -36.706018)
			(xy 431.45434 -36.718071) (xy 431.536649 -36.738039) (xy 431.616688 -36.765741) (xy 431.693731 -36.800925)
			(xy 431.767081 -36.843274) (xy 431.836073 -36.892403) (xy 431.900083 -36.947868) (xy 431.958531 -37.009166)
			(xy 432.010887 -37.075742) (xy 432.056677 -37.146994) (xy 432.095488 -37.222275) (xy 432.126967 -37.300905)
			(xy 432.150828 -37.382172) (xy 432.166857 -37.465338) (xy 432.174908 -37.549652) (xy 432.175412 -37.592)
			(xy 432.174908 -37.635484) (xy 432.166423 -37.722036) (xy 432.149533 -37.807348) (xy 432.1244 -37.890605)
			(xy 432.091263 -37.971012) (xy 432.050439 -38.047803) (xy 432.002318 -38.120243) (xy 431.947358 -38.187643)
			(xy 431.917094 -38.218872) (xy 431.909982 -38.226238) (xy 431.902362 -38.244526) (xy 431.902362 -38.336474)
			(xy 431.909982 -38.354762) (xy 431.917094 -38.362128) (xy 431.94736 -38.393354) (xy 432.002314 -38.460757)
			(xy 432.050431 -38.533199) (xy 432.09125 -38.609991) (xy 432.124383 -38.690398) (xy 432.149514 -38.773654)
			(xy 432.166402 -38.858965) (xy 432.174886 -38.945517) (xy 432.175412 -38.989) (xy 432.17503 -39.027398)
			(xy 432.168422 -39.10391) (xy 432.155236 -39.179566) (xy 432.135572 -39.253802) (xy 432.109576 -39.326065)
			(xy 432.093878 -39.36111) (xy 432.088798 -39.372286) (xy 432.089814 -39.396162) (xy 432.140868 -39.489126)
			(xy 432.16068 -39.502588) (xy 432.172618 -39.504366) (xy 432.214775 -39.51063) (xy 432.297771 -39.530031)
			(xy 432.37853 -39.55728) (xy 432.456313 -39.592128) (xy 432.530407 -39.634256) (xy 432.600131 -39.683277)
			(xy 432.664847 -39.738743) (xy 432.723962 -39.800144) (xy 432.776933 -39.866917) (xy 432.823275 -39.93845)
			(xy 432.862562 -40.014088) (xy 432.894436 -40.093137) (xy 432.905926 -40.132) (xy 433.348892 -40.132)
			(xy 433.349462 -40.089647) (xy 433.357521 -40.005325) (xy 433.373557 -39.922151) (xy 433.397424 -39.840877)
			(xy 433.428907 -39.762239) (xy 433.46772 -39.686948) (xy 433.513512 -39.615687) (xy 433.565869 -39.5491)
			(xy 433.624317 -39.487789) (xy 433.688327 -39.432311) (xy 433.75732 -39.383166) (xy 433.83067 -39.340801)
			(xy 433.907714 -39.305597) (xy 433.94757 -39.29126) (xy 433.957476 -39.287958) (xy 433.972462 -39.274496)
			(xy 434.012594 -39.19093) (xy 434.01361 -39.17061) (xy 434.010054 -39.160958) (xy 433.99765 -39.124917)
			(xy 433.978312 -39.051183) (xy 433.965356 -38.976065) (xy 433.958875 -38.900114) (xy 433.958492 -38.862)
			(xy 433.958967 -38.820898) (xy 433.966552 -38.739043) (xy 433.981657 -38.658238) (xy 434.004153 -38.579171)
			(xy 434.033849 -38.502517) (xy 434.070491 -38.42893) (xy 434.113766 -38.359038) (xy 434.163306 -38.293437)
			(xy 434.218687 -38.232687) (xy 434.279437 -38.177306) (xy 434.345038 -38.127766) (xy 434.41493 -38.084491)
			(xy 434.488517 -38.047849) (xy 434.565171 -38.018153) (xy 434.644238 -37.995657) (xy 434.725043 -37.980552)
			(xy 434.806898 -37.972967) (xy 434.848 -37.972492) (xy 434.892139 -37.973032) (xy 434.979983 -37.981754)
			(xy 435.066531 -37.999141) (xy 435.150928 -38.025024) (xy 435.232344 -38.059145) (xy 435.271418 -38.07968)
			(xy 435.282949 -38.085107) (xy 435.308401 -38.085107) (xy 435.319932 -38.07968) (xy 435.359002 -38.059138)
			(xy 435.440426 -38.02504) (xy 435.524825 -37.999168) (xy 435.61137 -37.981776) (xy 435.699212 -37.973035)
			(xy 435.74335 -37.972492) (xy 435.784455 -37.97306) (xy 435.866314 -37.98064) (xy 435.947124 -37.995738)
			(xy 436.026198 -38.018227) (xy 436.102859 -38.047915) (xy 436.176455 -38.084549) (xy 436.246357 -38.127816)
			(xy 436.31197 -38.177346) (xy 436.372733 -38.232719) (xy 436.42813 -38.293461) (xy 436.477686 -38.359054)
			(xy 436.520981 -38.428939) (xy 436.557643 -38.502521) (xy 436.587361 -38.57917) (xy 436.609882 -38.658235)
			(xy 436.625012 -38.73904) (xy 436.632624 -38.820896) (xy 436.633112 -38.862) (xy 436.632616 -38.903508)
			(xy 436.624887 -38.986163) (xy 436.609496 -39.06774) (xy 436.586577 -39.147529) (xy 436.571898 -39.186358)
			(xy 436.568088 -39.195756) (xy 436.568342 -39.21506) (xy 436.60314 -39.298626) (xy 436.616602 -39.312342)
			(xy 436.625746 -39.316406) (xy 436.648352 -39.326566) (xy 436.658873 -39.33086) (xy 436.681569 -39.330715)
			(xy 436.701996 -39.320819) (xy 436.709566 -39.312342) (xy 436.737666 -39.278128) (xy 436.799612 -39.214862)
			(xy 436.867536 -39.158062) (xy 436.940766 -39.108289) (xy 437.018577 -39.066037) (xy 437.100201 -39.031722)
			(xy 437.184829 -39.005685) (xy 437.271625 -38.988182) (xy 437.35973 -38.979388) (xy 437.404002 -38.97884)
			(xy 437.434482 -38.979348) (xy 437.44515 -38.979602) (xy 437.4642 -38.972236) (xy 437.532018 -38.905688)
			(xy 437.539892 -38.886638) (xy 437.539638 -38.87597) (xy 437.539384 -38.862) (xy 437.539888 -38.819639)
			(xy 437.547941 -38.735302) (xy 437.563975 -38.652112) (xy 437.587843 -38.570822) (xy 437.619331 -38.49217)
			(xy 437.658153 -38.416867) (xy 437.703956 -38.345595) (xy 437.756327 -38.278999) (xy 437.814792 -38.217684)
			(xy 437.87882 -38.162203) (xy 437.947832 -38.11306) (xy 438.021202 -38.0707) (xy 438.098267 -38.035505)
			(xy 438.178329 -38.007796) (xy 438.260662 -37.987822) (xy 438.344521 -37.975765) (xy 438.429146 -37.971734)
			(xy 438.513771 -37.975765) (xy 438.59763 -37.987822) (xy 438.679963 -38.007796) (xy 438.760025 -38.035505)
			(xy 438.83709 -38.0707) (xy 438.91046 -38.11306) (xy 438.979472 -38.162203) (xy 439.0435 -38.217684)
			(xy 439.101965 -38.278999) (xy 439.154336 -38.345595) (xy 439.200139 -38.416867) (xy 439.238961 -38.49217)
			(xy 439.270449 -38.570822) (xy 439.294317 -38.652112) (xy 439.310351 -38.735302) (xy 439.318404 -38.819639)
			(xy 439.318908 -38.862) (xy 439.318482 -38.901272) (xy 439.311547 -38.97951) (xy 439.29774 -39.056832)
			(xy 439.277168 -39.132635) (xy 439.249992 -39.206328) (xy 439.216424 -39.277338) (xy 439.176725 -39.345112)
			(xy 439.154316 -39.377366) (xy 439.145934 -39.389304) (xy 439.144156 -39.418006) (xy 439.184406 -39.492936)
			(xy 447.147188 -39.492936) (xy 447.147701 -39.451842) (xy 447.155279 -39.370003) (xy 447.170376 -39.289213)
			(xy 447.192861 -39.21016) (xy 447.222544 -39.133518) (xy 447.25917 -39.059942) (xy 447.302428 -38.990058)
			(xy 447.351948 -38.924463) (xy 447.407308 -38.863716) (xy 447.468037 -38.808336) (xy 447.533616 -38.758794)
			(xy 447.603485 -38.715513) (xy 447.677049 -38.678862) (xy 447.753681 -38.649155) (xy 447.832727 -38.626643)
			(xy 447.913512 -38.61152) (xy 447.995348 -38.603914) (xy 448.036442 -38.603428) (xy 448.03695 -38.603428)
			(xy 448.076051 -38.60384) (xy 448.153949 -38.610713) (xy 448.230944 -38.624401) (xy 448.306438 -38.644798)
			(xy 448.379849 -38.671748) (xy 448.41541 -38.68801) (xy 448.425797 -38.692245) (xy 448.448203 -38.692245)
			(xy 448.45859 -38.68801) (xy 448.494158 -38.671767) (xy 448.567573 -38.644836) (xy 448.643066 -38.624445)
			(xy 448.720056 -38.610754) (xy 448.797951 -38.603866) (xy 448.83705 -38.603428) (xy 448.880623 -38.603997)
			(xy 448.967349 -38.612531) (xy 449.052826 -38.629502) (xy 449.136234 -38.654748) (xy 449.216775 -38.688026)
			(xy 449.293677 -38.729019) (xy 449.366204 -38.777333) (xy 449.433659 -38.832506) (xy 449.495399 -38.894008)
			(xy 449.55083 -38.961252) (xy 449.599422 -39.033592) (xy 449.64071 -39.110336) (xy 449.674297 -39.190749)
			(xy 449.699863 -39.27406) (xy 449.709032 -39.31666) (xy 449.712222 -39.328624) (xy 449.727909 -39.347734)
			(xy 449.739004 -39.353236) (xy 449.82765 -39.391082) (xy 449.852796 -39.38905) (xy 449.86321 -39.382192)
			(xy 449.898948 -39.359945) (xy 449.973876 -39.321561) (xy 450.052096 -39.290429) (xy 450.132908 -39.266828)
			(xy 450.215589 -39.250969) (xy 450.299398 -39.242993) (xy 450.341492 -39.242492) (xy 450.342 -39.242492)
			(xy 450.384348 -39.242996) (xy 450.468662 -39.251047) (xy 450.551828 -39.267076) (xy 450.633095 -39.290937)
			(xy 450.711725 -39.322416) (xy 450.787006 -39.361227) (xy 450.858258 -39.407017) (xy 450.924834 -39.459373)
			(xy 450.986132 -39.517821) (xy 451.041597 -39.581831) (xy 451.090726 -39.650823) (xy 451.133075 -39.724173)
			(xy 451.168259 -39.801216) (xy 451.195961 -39.881255) (xy 451.215929 -39.963564) (xy 451.227982 -40.047399)
			(xy 451.232013 -40.132) (xy 451.227982 -40.216601) (xy 451.215929 -40.300436) (xy 451.195961 -40.382745)
			(xy 451.168259 -40.462784) (xy 451.133075 -40.539827) (xy 451.090726 -40.613177) (xy 451.041597 -40.682169)
			(xy 450.986132 -40.746179) (xy 450.924834 -40.804627) (xy 450.858258 -40.856983) (xy 450.787006 -40.902773)
			(xy 450.711725 -40.941584) (xy 450.633095 -40.973063) (xy 450.551828 -40.996924) (xy 450.468662 -41.012953)
			(xy 450.384348 -41.021004) (xy 450.342 -41.021508) (xy 450.341492 -41.021508) (xy 450.300376 -41.021023)
			(xy 450.218496 -41.013418) (xy 450.137667 -40.99829) (xy 450.058578 -40.97577) (xy 449.981904 -40.94605)
			(xy 449.9083 -40.909382) (xy 449.838391 -40.866081) (xy 449.805298 -40.841676) (xy 449.796103 -40.835417)
			(xy 449.774391 -40.830712) (xy 449.752717 -40.835594) (xy 449.743576 -40.84193) (xy 449.710174 -40.867181)
			(xy 449.639436 -40.911999) (xy 449.564799 -40.949969) (xy 449.486924 -40.980757) (xy 449.4065 -41.00409)
			(xy 449.32424 -41.019761) (xy 449.24087 -41.027631) (xy 449.199 -41.028112) (xy 449.157488 -41.02762)
			(xy 449.074828 -41.019852) (xy 448.993252 -41.004412) (xy 448.913471 -40.981434) (xy 448.836179 -40.951119)
			(xy 448.76205 -40.91373) (xy 448.69173 -40.869593) (xy 448.658488 -40.844724) (xy 448.649289 -40.838381)
			(xy 448.6275 -40.83355) (xy 448.605711 -40.838381) (xy 448.596512 -40.844724) (xy 448.563254 -40.869568)
			(xy 448.492928 -40.91369) (xy 448.418799 -40.951069) (xy 448.34151 -40.981382) (xy 448.261734 -41.004365)
			(xy 448.180164 -41.019817) (xy 448.09751 -41.027605) (xy 448.056 -41.028112) (xy 448.014889 -41.027648)
			(xy 447.933019 -41.02006) (xy 447.852199 -41.004949) (xy 447.773118 -40.982444) (xy 447.696451 -40.952738)
			(xy 447.622853 -40.916082) (xy 447.552951 -40.872792) (xy 447.487343 -40.823235) (xy 447.426588 -40.767835)
			(xy 447.371205 -40.707065) (xy 447.321667 -40.641443) (xy 447.278396 -40.571529) (xy 447.241761 -40.49792)
			(xy 447.212076 -40.421245) (xy 447.189594 -40.342158) (xy 447.174506 -40.261333) (xy 447.166941 -40.179461)
			(xy 447.166492 -40.13835) (xy 447.167083 -40.090752) (xy 447.177179 -39.996095) (xy 447.197317 -39.903055)
			(xy 447.211704 -39.85768) (xy 447.214202 -39.849115) (xy 447.213673 -39.83129) (xy 447.210688 -39.822882)
			(xy 447.195473 -39.783451) (xy 447.171711 -39.702337) (xy 447.155739 -39.619337) (xy 447.147701 -39.535197)
			(xy 447.147188 -39.492936) (xy 439.184406 -39.492936) (xy 439.201052 -39.523924) (xy 439.225944 -39.538148)
			(xy 439.240422 -39.53764) (xy 439.270394 -39.537132) (xy 439.311508 -39.537619) (xy 439.393385 -39.545205)
			(xy 439.474213 -39.560314) (xy 439.553302 -39.582816) (xy 439.629978 -39.61252) (xy 439.703585 -39.649171)
			(xy 439.773497 -39.692458) (xy 439.839117 -39.742011) (xy 439.899884 -39.797407) (xy 439.955281 -39.858174)
			(xy 440.004835 -39.923793) (xy 440.048123 -39.993704) (xy 440.084775 -40.067312) (xy 440.11448 -40.143987)
			(xy 440.136983 -40.223075) (xy 440.152093 -40.303903) (xy 440.159681 -40.38578) (xy 440.160156 -40.426894)
			(xy 440.159715 -40.468897) (xy 440.15178 -40.552529) (xy 440.135998 -40.63504) (xy 440.112511 -40.715697)
			(xy 440.081528 -40.793782) (xy 440.043323 -40.868599) (xy 439.998238 -40.939483) (xy 439.946673 -41.005802)
			(xy 439.889088 -41.066967) (xy 439.825994 -41.122432) (xy 439.757955 -41.171705) (xy 439.685575 -41.214346)
			(xy 439.609498 -41.249977) (xy 439.570114 -41.264586) (xy 439.560208 -41.268142) (xy 439.545222 -41.282112)
			(xy 439.50636 -41.36771) (xy 439.506106 -41.388284) (xy 439.509916 -41.397936) (xy 439.525047 -41.437285)
			(xy 439.548666 -41.51822) (xy 439.564512 -41.601028) (xy 439.572441 -41.684964) (xy 439.572908 -41.72712)
			(xy 439.572404 -41.769468) (xy 439.564353 -41.853782) (xy 439.548324 -41.936948) (xy 439.524463 -42.018215)
			(xy 439.492984 -42.096845) (xy 439.454173 -42.172126) (xy 439.408383 -42.243378) (xy 439.356027 -42.309954)
			(xy 439.297579 -42.371252) (xy 439.233569 -42.426717) (xy 439.164577 -42.475846) (xy 439.091227 -42.518195)
			(xy 439.014184 -42.553379) (xy 438.934145 -42.581081) (xy 438.851836 -42.601049) (xy 438.768001 -42.613102)
			(xy 438.6834 -42.617133) (xy 438.598799 -42.613102) (xy 438.514964 -42.601049) (xy 438.432655 -42.581081)
			(xy 438.352616 -42.553379) (xy 438.275573 -42.518195) (xy 438.202223 -42.475846) (xy 438.133231 -42.426717)
			(xy 438.069221 -42.371252) (xy 438.010773 -42.309954) (xy 437.958417 -42.243378) (xy 437.912627 -42.172126)
			(xy 437.873816 -42.096845) (xy 437.842337 -42.018215) (xy 437.818476 -41.936948) (xy 437.802447 -41.853782)
			(xy 437.794396 -41.769468) (xy 437.793892 -41.72712) (xy 437.794341 -41.685123) (xy 437.802255 -41.601502)
			(xy 437.818014 -41.518999) (xy 437.84148 -41.438348) (xy 437.872441 -41.360268) (xy 437.910623 -41.285454)
			(xy 437.955686 -41.214571) (xy 438.007229 -41.14825) (xy 438.064793 -41.087082) (xy 438.127866 -41.031612)
			(xy 438.195885 -40.982332) (xy 438.268246 -40.939683) (xy 438.344305 -40.904043) (xy 438.38368 -40.889428)
			(xy 438.393586 -40.885872) (xy 438.408572 -40.871902) (xy 438.447434 -40.786304) (xy 438.447688 -40.76573)
			(xy 438.443878 -40.756078) (xy 438.428714 -40.716735) (xy 438.405041 -40.635805) (xy 438.389134 -40.552997)
			(xy 438.381136 -40.469055) (xy 438.380632 -40.426894) (xy 438.381066 -40.387622) (xy 438.388001 -40.309385)
			(xy 438.401808 -40.232063) (xy 438.422378 -40.156261) (xy 438.449553 -40.082567) (xy 438.483119 -40.011557)
			(xy 438.522816 -39.943783) (xy 438.545224 -39.911528) (xy 438.553606 -39.89959) (xy 438.555384 -39.870888)
			(xy 438.498488 -39.76497) (xy 438.473596 -39.750746) (xy 438.459118 -39.751254) (xy 438.429146 -39.751508)
			(xy 438.398666 -39.751) (xy 438.387998 -39.750746) (xy 438.368948 -39.758112) (xy 438.30113 -39.82466)
			(xy 438.293256 -39.84371) (xy 438.29351 -39.854378) (xy 438.293764 -39.868348) (xy 438.293393 -39.909461)
			(xy 438.285801 -39.991335) (xy 438.270685 -40.072159) (xy 438.248175 -40.151243) (xy 438.218462 -40.227913)
			(xy 438.181801 -40.301513) (xy 438.138504 -40.371416) (xy 438.088941 -40.437025) (xy 438.033535 -40.49778)
			(xy 437.972758 -40.553162) (xy 437.90713 -40.6027) (xy 437.83721 -40.645969) (xy 437.763596 -40.682602)
			(xy 437.686915 -40.712285) (xy 437.607822 -40.734764) (xy 437.526992 -40.749848) (xy 437.445115 -40.757409)
			(xy 437.404002 -40.757856) (xy 437.364965 -40.757435) (xy 437.287187 -40.750631) (xy 437.210305 -40.737039)
			(xy 437.134909 -40.716764) (xy 437.061578 -40.689963) (xy 437.02605 -40.673782) (xy 437.015524 -40.669507)
			(xy 436.992834 -40.669652) (xy 436.97241 -40.679536) (xy 436.964836 -40.688006) (xy 436.936721 -40.722208)
			(xy 436.874778 -40.785476) (xy 436.806857 -40.842278) (xy 436.733629 -40.892053) (xy 436.65582 -40.934307)
			(xy 436.574198 -40.968623) (xy 436.489571 -40.994661) (xy 436.402776 -41.012165) (xy 436.314671 -41.02096)
			(xy 436.2704 -41.021508) (xy 436.229298 -41.021033) (xy 436.147443 -41.013448) (xy 436.066638 -40.998343)
			(xy 435.987571 -40.975847) (xy 435.910917 -40.946151) (xy 435.83733 -40.909509) (xy 435.767438 -40.866234)
			(xy 435.701837 -40.816694) (xy 435.641087 -40.761313) (xy 435.585706 -40.700563) (xy 435.536166 -40.634962)
			(xy 435.492891 -40.56507) (xy 435.456249 -40.491483) (xy 435.426553 -40.414829) (xy 435.404057 -40.335762)
			(xy 435.388952 -40.254957) (xy 435.381367 -40.173102) (xy 435.380892 -40.132) (xy 435.381329 -40.090497)
			(xy 435.389007 -40.007848) (xy 435.404343 -39.926272) (xy 435.427203 -39.846476) (xy 435.441852 -39.807642)
			(xy 435.445662 -39.798244) (xy 435.445408 -39.77894) (xy 435.41061 -39.695374) (xy 435.397148 -39.681658)
			(xy 435.388004 -39.677594) (xy 435.370681 -39.669914) (xy 435.336632 -39.653273) (xy 435.319932 -39.64432)
			(xy 435.31236 -39.640531) (xy 435.295675 -39.637713) (xy 435.27899 -39.640531) (xy 435.271418 -39.64432)
			(xy 435.239359 -39.661282) (xy 435.172983 -39.690531) (xy 435.13883 -39.70274) (xy 435.128924 -39.706042)
			(xy 435.113938 -39.719504) (xy 435.073806 -39.80307) (xy 435.07279 -39.82339) (xy 435.076346 -39.833042)
			(xy 435.08875 -39.869083) (xy 435.108088 -39.942817) (xy 435.121044 -40.017935) (xy 435.127525 -40.093886)
			(xy 435.127908 -40.132) (xy 435.127404 -40.174348) (xy 435.119353 -40.258662) (xy 435.103324 -40.341828)
			(xy 435.079463 -40.423095) (xy 435.047984 -40.501725) (xy 435.009173 -40.577006) (xy 434.963383 -40.648258)
			(xy 434.911027 -40.714834) (xy 434.852579 -40.776132) (xy 434.788569 -40.831597) (xy 434.719577 -40.880726)
			(xy 434.646227 -40.923075) (xy 434.569184 -40.958259) (xy 434.489145 -40.985961) (xy 434.406836 -41.005929)
			(xy 434.323001 -41.017982) (xy 434.2384 -41.022013) (xy 434.153799 -41.017982) (xy 434.069964 -41.005929)
			(xy 433.987655 -40.985961) (xy 433.907616 -40.958259) (xy 433.830573 -40.923075) (xy 433.757223 -40.880726)
			(xy 433.688231 -40.831597) (xy 433.624221 -40.776132) (xy 433.565773 -40.714834) (xy 433.513417 -40.648258)
			(xy 433.467627 -40.577006) (xy 433.428816 -40.501725) (xy 433.397337 -40.423095) (xy 433.373476 -40.341828)
			(xy 433.357447 -40.258662) (xy 433.349396 -40.174348) (xy 433.348892 -40.132) (xy 432.905926 -40.132)
			(xy 432.918602 -40.174871) (xy 432.934841 -40.258543) (xy 432.943002 -40.343384) (xy 432.943508 -40.386)
			(xy 432.943005 -40.429484) (xy 432.93452 -40.516037) (xy 432.91763 -40.601348) (xy 432.892497 -40.684605)
			(xy 432.85936 -40.765012) (xy 432.818536 -40.841803) (xy 432.770414 -40.914244) (xy 432.715454 -40.981643)
			(xy 432.68519 -41.012872) (xy 432.678078 -41.020238) (xy 432.670458 -41.038526) (xy 432.670458 -41.130474)
			(xy 432.678078 -41.148762) (xy 432.68519 -41.156128) (xy 432.715455 -41.187354) (xy 432.77041 -41.254757)
			(xy 432.818526 -41.3272) (xy 432.859346 -41.403991) (xy 432.892479 -41.484398) (xy 432.91761 -41.567655)
			(xy 432.934498 -41.652965) (xy 432.942982 -41.739517) (xy 432.943508 -41.783) (xy 432.943036 -41.824964)
			(xy 432.93513 -41.90852) (xy 432.919389 -41.99096) (xy 432.895953 -42.07155) (xy 432.865029 -42.149574)
			(xy 432.826894 -42.224339) (xy 432.781886 -42.295179) (xy 432.730405 -42.361465) (xy 432.67291 -42.422606)
			(xy 432.60991 -42.47806) (xy 432.576224 -42.50309) (xy 432.563778 -42.512234) (xy 432.55311 -42.540682)
			(xy 432.580796 -42.661586) (xy 432.602894 -42.682668) (xy 432.61788 -42.685462) (xy 432.658446 -42.693258)
			(xy 432.738043 -42.715372) (xy 432.815246 -42.744771) (xy 432.889392 -42.781199) (xy 432.959842 -42.824344)
			(xy 432.982586 -42.841361) (xy 434.854092 -42.841361) (xy 434.854092 -42.756639) (xy 434.862145 -42.672302)
			(xy 434.878179 -42.589112) (xy 434.902047 -42.507822) (xy 434.933535 -42.42917) (xy 434.972357 -42.353867)
			(xy 435.01816 -42.282595) (xy 435.070531 -42.215999) (xy 435.128996 -42.154684) (xy 435.193024 -42.099203)
			(xy 435.262036 -42.05006) (xy 435.335406 -42.0077) (xy 435.412471 -41.972505) (xy 435.492533 -41.944796)
			(xy 435.574866 -41.924822) (xy 435.658725 -41.912765) (xy 435.74335 -41.908734) (xy 435.827975 -41.912765)
			(xy 435.911834 -41.924822) (xy 435.994167 -41.944796) (xy 436.074229 -41.972505) (xy 436.151294 -42.0077)
			(xy 436.224664 -42.05006) (xy 436.293676 -42.099203) (xy 436.357704 -42.154684) (xy 436.416169 -42.215999)
			(xy 436.46854 -42.282595) (xy 436.514343 -42.353867) (xy 436.553165 -42.42917) (xy 436.584653 -42.507822)
			(xy 436.608521 -42.589112) (xy 436.624555 -42.672302) (xy 436.632608 -42.756639) (xy 436.633112 -42.799)
			(xy 436.632608 -42.841361) (xy 436.624555 -42.925698) (xy 436.608521 -43.008888) (xy 436.584653 -43.090178)
			(xy 436.553165 -43.16883) (xy 436.514343 -43.244133) (xy 436.46854 -43.315405) (xy 436.416169 -43.382001)
			(xy 436.357704 -43.443316) (xy 436.293676 -43.498797) (xy 436.224664 -43.54794) (xy 436.151294 -43.5903)
			(xy 436.074229 -43.625495) (xy 435.994167 -43.653204) (xy 435.911834 -43.673178) (xy 435.827975 -43.685235)
			(xy 435.74335 -43.689267) (xy 435.658725 -43.685235) (xy 435.574866 -43.673178) (xy 435.492533 -43.653204)
			(xy 435.412471 -43.625495) (xy 435.335406 -43.5903) (xy 435.262036 -43.54794) (xy 435.193024 -43.498797)
			(xy 435.128996 -43.443316) (xy 435.070531 -43.382001) (xy 435.01816 -43.315405) (xy 434.972357 -43.244133)
			(xy 434.933535 -43.16883) (xy 434.902047 -43.090178) (xy 434.878179 -43.008888) (xy 434.862145 -42.925698)
			(xy 434.854092 -42.841361) (xy 432.982586 -42.841361) (xy 433.025989 -42.873834) (xy 433.087263 -42.929243)
			(xy 433.143137 -42.990093) (xy 433.193129 -43.055861) (xy 433.236809 -43.12598) (xy 433.273802 -43.199846)
			(xy 433.303787 -43.276824) (xy 433.326507 -43.35625) (xy 433.341767 -43.437439) (xy 433.349434 -43.519694)
			(xy 433.349908 -43.561) (xy 433.349427 -43.604607) (xy 433.340894 -43.691403) (xy 433.323909 -43.776948)
			(xy 433.298635 -43.86042) (xy 433.265316 -43.941018) (xy 433.224271 -44.017971) (xy 433.175893 -44.090537)
			(xy 433.120647 -44.158022) (xy 433.059063 -44.219778) (xy 432.991733 -44.275212) (xy 432.919301 -44.323792)
			(xy 432.842464 -44.365052) (xy 432.761959 -44.398596) (xy 432.678557 -44.424103) (xy 432.635914 -44.433236)
			(xy 432.620928 -44.436284) (xy 432.599592 -44.457366) (xy 432.573684 -44.57827) (xy 432.584352 -44.606464)
			(xy 432.596798 -44.615354) (xy 432.630864 -44.640375) (xy 432.694646 -44.695844) (xy 432.752879 -44.757114)
			(xy 432.805037 -44.82363) (xy 432.850651 -44.894795) (xy 432.889308 -44.969965) (xy 432.920661 -45.048464)
			(xy 432.944427 -45.129582) (xy 432.960391 -45.212589) (xy 432.968409 -45.296736) (xy 432.968908 -45.339)
			(xy 432.96842 -45.38279) (xy 432.959855 -45.469949) (xy 432.94276 -45.555843) (xy 432.93147 -45.593)
			(xy 436.015892 -45.593) (xy 436.016324 -45.551263) (xy 436.024115 -45.468153) (xy 436.039658 -45.386139)
			(xy 436.062814 -45.305941) (xy 436.093381 -45.228265) (xy 436.131089 -45.153794) (xy 436.175608 -45.083183)
			(xy 436.226545 -45.017052) (xy 436.254652 -44.986194) (xy 436.261907 -44.977668) (xy 436.268823 -44.956402)
			(xy 436.266005 -44.934218) (xy 436.260494 -44.924472) (xy 436.238672 -44.888926) (xy 436.201021 -44.814492)
			(xy 436.1705 -44.736861) (xy 436.147376 -44.656716) (xy 436.131853 -44.574758) (xy 436.124066 -44.491707)
			(xy 436.123588 -44.45) (xy 436.124092 -44.407652) (xy 436.132143 -44.323338) (xy 436.148172 -44.240172)
			(xy 436.172033 -44.158905) (xy 436.203512 -44.080275) (xy 436.242323 -44.004994) (xy 436.288113 -43.933742)
			(xy 436.340469 -43.867166) (xy 436.398917 -43.805868) (xy 436.462927 -43.750403) (xy 436.531919 -43.701274)
			(xy 436.605269 -43.658925) (xy 436.682312 -43.623741) (xy 436.762351 -43.596039) (xy 436.84466 -43.576071)
			(xy 436.928495 -43.564018) (xy 437.013096 -43.559988) (xy 437.097697 -43.564018) (xy 437.181532 -43.576071)
			(xy 437.263841 -43.596039) (xy 437.34388 -43.623741) (xy 437.420923 -43.658925) (xy 437.494273 -43.701274)
			(xy 437.563265 -43.750403) (xy 437.627275 -43.805868) (xy 437.685723 -43.867166) (xy 437.738079 -43.933742)
			(xy 437.783869 -44.004994) (xy 437.82268 -44.080275) (xy 437.854159 -44.158905) (xy 437.87802 -44.240172)
			(xy 437.894049 -44.323338) (xy 437.9021 -44.407652) (xy 437.902604 -44.45) (xy 438.142687 -44.45)
			(xy 438.146717 -44.365402) (xy 438.15877 -44.28157) (xy 438.178737 -44.199263) (xy 438.206436 -44.119227)
			(xy 438.241618 -44.042186) (xy 438.283964 -43.968838) (xy 438.33309 -43.899847) (xy 438.388551 -43.835839)
			(xy 438.449845 -43.777391) (xy 438.516417 -43.725035) (xy 438.587665 -43.679243) (xy 438.662942 -43.640431)
			(xy 438.741568 -43.60895) (xy 438.82283 -43.585086) (xy 438.905993 -43.569053) (xy 438.990303 -43.560998)
			(xy 439.03265 -43.560492) (xy 439.078005 -43.561066) (xy 439.168244 -43.570295) (xy 439.257077 -43.588653)
			(xy 439.343582 -43.615948) (xy 439.426864 -43.651898) (xy 439.466736 -43.673522) (xy 439.475346 -43.67781)
			(xy 439.494402 -43.6803) (xy 439.50382 -43.678348) (xy 439.53303 -43.671236) (xy 439.542271 -43.668587)
			(xy 439.557946 -43.657486) (xy 439.56351 -43.649646) (xy 439.588129 -43.61293) (xy 439.643482 -43.543998)
			(xy 439.705398 -43.480897) (xy 439.773269 -43.424249) (xy 439.846425 -43.374613) (xy 439.924143 -43.332479)
			(xy 440.005657 -43.298261) (xy 440.090164 -43.272298) (xy 440.176829 -43.254846) (xy 440.264798 -43.246077)
			(xy 440.309 -43.245532) (xy 440.35135 -43.245956) (xy 440.435668 -43.254007) (xy 440.518838 -43.270037)
			(xy 440.600108 -43.2939) (xy 440.678741 -43.32538) (xy 440.754026 -43.364192) (xy 440.825281 -43.409985)
			(xy 440.89186 -43.462343) (xy 440.953161 -43.520793) (xy 441.008629 -43.584806) (xy 441.05776 -43.653801)
			(xy 441.10011 -43.727154) (xy 441.135296 -43.804201) (xy 441.162999 -43.884243) (xy 441.182968 -43.966556)
			(xy 441.195022 -44.050395) (xy 441.199053 -44.135) (xy 441.195022 -44.219605) (xy 441.182968 -44.303444)
			(xy 441.162999 -44.385757) (xy 441.135296 -44.465799) (xy 441.10011 -44.542846) (xy 441.05776 -44.616199)
			(xy 441.008629 -44.685194) (xy 440.953161 -44.749207) (xy 440.89186 -44.807657) (xy 440.825281 -44.860015)
			(xy 440.754026 -44.905808) (xy 440.678741 -44.94462) (xy 440.600108 -44.9761) (xy 440.518838 -44.999963)
			(xy 440.435668 -45.015993) (xy 440.35135 -45.024044) (xy 440.309 -45.024548) (xy 440.263644 -45.024003)
			(xy 440.173404 -45.014768) (xy 440.084571 -44.996405) (xy 439.998066 -44.969103) (xy 439.914785 -44.933145)
			(xy 439.874914 -44.911518) (xy 439.866316 -44.907203) (xy 439.84725 -44.904732) (xy 439.83783 -44.906692)
			(xy 439.80862 -44.913804) (xy 439.799379 -44.916453) (xy 439.783706 -44.927556) (xy 439.77814 -44.935394)
			(xy 439.753568 -44.972143) (xy 439.698209 -45.041073) (xy 439.636286 -45.104172) (xy 439.568409 -45.160817)
			(xy 439.495248 -45.21045) (xy 439.417525 -45.252581) (xy 439.336006 -45.286795) (xy 439.251495 -45.312753)
			(xy 439.164826 -45.330201) (xy 439.076854 -45.338966) (xy 439.03265 -45.339508) (xy 438.990303 -45.339002)
			(xy 438.905993 -45.330947) (xy 438.82283 -45.314914) (xy 438.741568 -45.29105) (xy 438.662942 -45.259569)
			(xy 438.587665 -45.220757) (xy 438.516417 -45.174965) (xy 438.449845 -45.122609) (xy 438.388551 -45.064161)
			(xy 438.33309 -45.000153) (xy 438.283964 -44.931162) (xy 438.241618 -44.857814) (xy 438.206436 -44.780773)
			(xy 438.178737 -44.700737) (xy 438.15877 -44.61843) (xy 438.146717 -44.534598) (xy 438.142687 -44.45)
			(xy 437.902604 -44.45) (xy 437.902173 -44.491737) (xy 437.894382 -44.574847) (xy 437.878839 -44.656861)
			(xy 437.855683 -44.737059) (xy 437.825116 -44.814735) (xy 437.787407 -44.889206) (xy 437.742889 -44.959818)
			(xy 437.691951 -45.025948) (xy 437.663844 -45.056806) (xy 437.656589 -45.065332) (xy 437.649674 -45.086598)
			(xy 437.652492 -45.108782) (xy 437.658002 -45.118528) (xy 437.679823 -45.154075) (xy 437.717475 -45.228509)
			(xy 437.747996 -45.306139) (xy 437.77112 -45.386284) (xy 437.781408 -45.4406) (xy 446.130987 -45.4406)
			(xy 446.135017 -45.356002) (xy 446.14707 -45.27217) (xy 446.167037 -45.189863) (xy 446.194736 -45.109827)
			(xy 446.229918 -45.032786) (xy 446.272264 -44.959438) (xy 446.32139 -44.890447) (xy 446.376851 -44.826439)
			(xy 446.438145 -44.767991) (xy 446.504717 -44.715635) (xy 446.575965 -44.669843) (xy 446.651242 -44.631031)
			(xy 446.729868 -44.59955) (xy 446.81113 -44.575686) (xy 446.894293 -44.559653) (xy 446.978603 -44.551598)
			(xy 447.02095 -44.551092) (xy 447.060051 -44.551498) (xy 447.13795 -44.558372) (xy 447.214944 -44.572061)
			(xy 447.290439 -44.592459) (xy 447.363849 -44.619411) (xy 447.39941 -44.635674) (xy 447.409797 -44.639909)
			(xy 447.432203 -44.639909) (xy 447.44259 -44.635674) (xy 447.478157 -44.619429) (xy 447.551572 -44.592498)
			(xy 447.627066 -44.572108) (xy 447.704056 -44.558417) (xy 447.781951 -44.55153) (xy 447.82105 -44.551092)
			(xy 447.864585 -44.551601) (xy 447.951237 -44.560113) (xy 448.036644 -44.577051) (xy 448.119986 -44.602252)
			(xy 448.200468 -44.635477) (xy 448.277318 -44.676405) (xy 448.349802 -44.724647) (xy 448.417225 -44.77974)
			(xy 448.478942 -44.841157) (xy 448.534364 -44.908311) (xy 448.582959 -44.980558) (xy 448.624262 -45.057208)
			(xy 448.657879 -45.137526) (xy 448.671188 -45.17898) (xy 448.675118 -45.18985) (xy 448.690908 -45.206702)
			(xy 448.712469 -45.214975) (xy 448.72402 -45.21454) (xy 448.742655 -45.213096) (xy 448.780005 -45.211571)
			(xy 448.798696 -45.211492) (xy 448.79895 -45.211492) (xy 448.838051 -45.211898) (xy 448.91595 -45.218772)
			(xy 448.992944 -45.232461) (xy 449.068439 -45.252859) (xy 449.141849 -45.279811) (xy 449.17741 -45.296074)
			(xy 449.187816 -45.300269) (xy 449.210228 -45.300125) (xy 449.22059 -45.29582) (xy 449.24756 -45.283423)
			(xy 449.302851 -45.261816) (xy 449.33108 -45.25264) (xy 449.339712 -45.249426) (xy 449.354128 -45.23799)
			(xy 449.363591 -45.222208) (xy 449.366888 -45.204104) (xy 449.365624 -45.194982) (xy 449.358751 -45.155142)
			(xy 449.351374 -45.074626) (xy 449.350892 -45.0342) (xy 449.350892 -45.033438) (xy 449.351301 -44.995091)
			(xy 449.357933 -44.918683) (xy 449.371125 -44.843132) (xy 449.390778 -44.768998) (xy 449.416747 -44.696834)
			(xy 449.432426 -44.661836) (xy 449.43679 -44.650863) (xy 449.43598 -44.627287) (xy 449.430902 -44.616624)
			(xy 449.410674 -44.577756) (xy 449.377102 -44.496815) (xy 449.351646 -44.412966) (xy 449.334555 -44.327022)
			(xy 449.325992 -44.239814) (xy 449.325492 -44.196) (xy 449.325873 -44.157602) (xy 449.332482 -44.08109)
			(xy 449.345668 -44.005434) (xy 449.365332 -43.931198) (xy 449.391328 -43.858935) (xy 449.407026 -43.82389)
			(xy 449.407026 -43.823636) (xy 449.411348 -43.812584) (xy 449.410572 -43.788897) (xy 449.405502 -43.77817)
			(xy 449.365878 -43.706542) (xy 449.359675 -43.696419) (xy 449.340194 -43.682903) (xy 449.32854 -43.680634)
			(xy 449.328032 -43.680634) (xy 449.290779 -43.675223) (xy 449.217284 -43.658913) (xy 449.145429 -43.63645)
			(xy 449.07573 -43.607995) (xy 449.042028 -43.591226) (xy 449.041774 -43.591226) (xy 449.031342 -43.586556)
			(xy 449.008523 -43.585909) (xy 448.997832 -43.589956) (xy 448.915282 -43.627294) (xy 448.900296 -43.644566)
			(xy 448.897502 -43.655742) (xy 448.886478 -43.696025) (xy 448.85778 -43.774464) (xy 448.821858 -43.849867)
			(xy 448.779027 -43.921573) (xy 448.729664 -43.988949) (xy 448.674204 -44.051402) (xy 448.613135 -44.108383)
			(xy 448.546995 -44.15939) (xy 448.476366 -44.203974) (xy 448.40187 -44.241742) (xy 448.324162 -44.272363)
			(xy 448.243926 -44.295566) (xy 448.161868 -44.311148) (xy 448.078712 -44.318971) (xy 448.03695 -44.319444)
			(xy 447.994605 -44.318866) (xy 447.910298 -44.310811) (xy 447.827139 -44.294779) (xy 447.74588 -44.270916)
			(xy 447.667257 -44.239436) (xy 447.591983 -44.200626) (xy 447.520738 -44.154836) (xy 447.454169 -44.102481)
			(xy 447.392877 -44.044037) (xy 447.337418 -43.98003) (xy 447.288294 -43.911042) (xy 447.24595 -43.837697)
			(xy 447.21077 -43.76066) (xy 447.183071 -43.680627) (xy 447.163105 -43.598323) (xy 447.151053 -43.514495)
			(xy 447.147023 -43.4299) (xy 447.151053 -43.345305) (xy 447.163105 -43.261477) (xy 447.183071 -43.179173)
			(xy 447.21077 -43.09914) (xy 447.24595 -43.022103) (xy 447.288294 -42.948758) (xy 447.337418 -42.87977)
			(xy 447.392877 -42.815763) (xy 447.454169 -42.757319) (xy 447.520738 -42.704964) (xy 447.591983 -42.659174)
			(xy 447.667257 -42.620364) (xy 447.74588 -42.588884) (xy 447.827139 -42.565021) (xy 447.910298 -42.548989)
			(xy 447.994605 -42.540934) (xy 448.03695 -42.540428) (xy 448.037712 -42.540428) (xy 448.079675 -42.540911)
			(xy 448.163226 -42.548837) (xy 448.245657 -42.564607) (xy 448.326233 -42.588081) (xy 448.404237 -42.61905)
			(xy 448.441826 -42.63771) (xy 448.44208 -42.63771) (xy 448.452522 -42.642354) (xy 448.475333 -42.64302)
			(xy 448.486022 -42.63898) (xy 448.568572 -42.601642) (xy 448.583558 -42.58437) (xy 448.586352 -42.573194)
			(xy 448.597442 -42.53293) (xy 448.626135 -42.454493) (xy 448.662052 -42.37909) (xy 448.704878 -42.307386)
			(xy 448.754235 -42.24001) (xy 448.809689 -42.177556) (xy 448.870753 -42.120574) (xy 448.936887 -42.069566)
			(xy 449.007511 -42.02498) (xy 449.082003 -41.98721) (xy 449.159706 -41.956586) (xy 449.239938 -41.93338)
			(xy 449.321991 -41.917794) (xy 449.405144 -41.909967) (xy 449.446904 -41.909492) (xy 449.488007 -41.909963)
			(xy 449.569861 -41.917548) (xy 449.650666 -41.932654) (xy 449.729733 -41.95515) (xy 449.806387 -41.984847)
			(xy 449.879974 -42.021489) (xy 449.949866 -42.064764) (xy 450.015467 -42.114304) (xy 450.076217 -42.169686)
			(xy 450.131598 -42.230436) (xy 450.181138 -42.296037) (xy 450.224413 -42.365929) (xy 450.261055 -42.439517)
			(xy 450.290751 -42.516171) (xy 450.313247 -42.595238) (xy 450.328352 -42.676043) (xy 450.335937 -42.757897)
			(xy 450.336412 -42.799) (xy 450.336412 -42.799254) (xy 450.336021 -42.837627) (xy 450.329399 -42.914086)
			(xy 450.316209 -42.98969) (xy 450.296549 -43.063875) (xy 450.270567 -43.136088) (xy 450.254878 -43.17111)
			(xy 450.254878 -43.171364) (xy 450.250555 -43.182416) (xy 450.251331 -43.206103) (xy 450.256402 -43.21683)
			(xy 450.296026 -43.288458) (xy 450.302227 -43.298583) (xy 450.32171 -43.312098) (xy 450.333364 -43.314366)
			(xy 450.333872 -43.314366) (xy 450.376027 -43.320593) (xy 450.459002 -43.340021) (xy 450.539739 -43.367293)
			(xy 450.617498 -43.402161) (xy 450.691568 -43.444303) (xy 450.761268 -43.493335) (xy 450.82596 -43.548807)
			(xy 450.885053 -43.61021) (xy 450.938003 -43.676982) (xy 450.984326 -43.748511) (xy 451.023597 -43.824142)
			(xy 451.055457 -43.903181) (xy 451.079613 -43.984904) (xy 451.095845 -44.068563) (xy 451.104003 -44.153391)
			(xy 451.104508 -44.196) (xy 451.104508 -44.196762) (xy 451.104099 -44.235109) (xy 451.097467 -44.311517)
			(xy 451.084275 -44.387068) (xy 451.064622 -44.461202) (xy 451.038653 -44.533366) (xy 451.022974 -44.568364)
			(xy 451.01861 -44.579337) (xy 451.01942 -44.602913) (xy 451.024498 -44.613576) (xy 451.044682 -44.652352)
			(xy 451.078196 -44.733098) (xy 451.10363 -44.816741) (xy 451.120741 -44.902474) (xy 451.129363 -44.989472)
			(xy 451.129908 -45.033184) (xy 451.129908 -45.0342) (xy 451.129476 -45.07748) (xy 451.121079 -45.163632)
			(xy 451.104354 -45.248561) (xy 451.079461 -45.331465) (xy 451.046633 -45.411559) (xy 451.006182 -45.488086)
			(xy 450.95849 -45.560323) (xy 450.904008 -45.627587) (xy 450.843251 -45.689241) (xy 450.776793 -45.744703)
			(xy 450.705263 -45.793449) (xy 450.629337 -45.835017) (xy 450.549733 -45.869015) (xy 450.508624 -45.88256)
			(xy 450.499938 -45.885678) (xy 450.485461 -45.897103) (xy 450.475989 -45.912927) (xy 450.472758 -45.931083)
			(xy 450.47408 -45.940218) (xy 450.480948 -45.980059) (xy 450.488329 -46.060574) (xy 450.488812 -46.101)
			(xy 450.48834 -46.143697) (xy 450.480165 -46.2287) (xy 450.463881 -46.312527) (xy 450.439638 -46.394408)
			(xy 450.407658 -46.473588) (xy 450.368237 -46.549339) (xy 450.321737 -46.620963) (xy 450.268587 -46.687801)
			(xy 450.209275 -46.749237) (xy 450.144349 -46.804705) (xy 450.074405 -46.853695) (xy 450.000087 -46.895756)
			(xy 449.92208 -46.930501) (xy 449.881752 -46.944534) (xy 449.870989 -46.948746) (xy 449.854456 -46.964859)
			(xy 449.850002 -46.975522) (xy 449.819014 -47.061374) (xy 449.821554 -47.084488) (xy 449.82765 -47.094394)
			(xy 449.848966 -47.129617) (xy 449.885742 -47.203285) (xy 449.915559 -47.280034) (xy 449.938162 -47.359207)
			(xy 449.953358 -47.44013) (xy 449.961017 -47.52211) (xy 449.961508 -47.563278) (xy 449.961508 -47.56404)
			(xy 449.961004 -47.606388) (xy 449.952953 -47.690702) (xy 449.936924 -47.773868) (xy 449.913063 -47.855135)
			(xy 449.881584 -47.933765) (xy 449.842773 -48.009046) (xy 449.796983 -48.080298) (xy 449.744627 -48.146874)
			(xy 449.717464 -48.175361) (xy 450.722742 -48.175361) (xy 450.722742 -48.090639) (xy 450.730795 -48.006302)
			(xy 450.746829 -47.923112) (xy 450.770697 -47.841822) (xy 450.802185 -47.76317) (xy 450.841007 -47.687867)
			(xy 450.88681 -47.616595) (xy 450.939181 -47.549999) (xy 450.997646 -47.488684) (xy 451.061674 -47.433203)
			(xy 451.130686 -47.38406) (xy 451.204056 -47.3417) (xy 451.281121 -47.306505) (xy 451.361183 -47.278796)
			(xy 451.443516 -47.258822) (xy 451.527375 -47.246765) (xy 451.612 -47.242734) (xy 451.696625 -47.246765)
			(xy 451.780484 -47.258822) (xy 451.862817 -47.278796) (xy 451.942879 -47.306505) (xy 452.019944 -47.3417)
			(xy 452.093314 -47.38406) (xy 452.162326 -47.433203) (xy 452.226354 -47.488684) (xy 452.284819 -47.549999)
			(xy 452.33719 -47.616595) (xy 452.369815 -47.667361) (xy 456.336142 -47.667361) (xy 456.336142 -47.582639)
			(xy 456.344195 -47.498302) (xy 456.360229 -47.415112) (xy 456.384097 -47.333822) (xy 456.415585 -47.25517)
			(xy 456.454407 -47.179867) (xy 456.50021 -47.108595) (xy 456.552581 -47.041999) (xy 456.611046 -46.980684)
			(xy 456.675074 -46.925203) (xy 456.744086 -46.87606) (xy 456.817456 -46.8337) (xy 456.894521 -46.798505)
			(xy 456.974583 -46.770796) (xy 457.056916 -46.750822) (xy 457.140775 -46.738765) (xy 457.2254 -46.734734)
			(xy 457.310025 -46.738765) (xy 457.393884 -46.750822) (xy 457.476217 -46.770796) (xy 457.556279 -46.798505)
			(xy 457.633344 -46.8337) (xy 457.706714 -46.87606) (xy 457.775726 -46.925203) (xy 457.839754 -46.980684)
			(xy 457.898219 -47.041999) (xy 457.95059 -47.108595) (xy 457.996393 -47.179867) (xy 458.029456 -47.244)
			(xy 459.230988 -47.244) (xy 459.235018 -47.159399) (xy 459.247071 -47.075564) (xy 459.267039 -46.993255)
			(xy 459.294741 -46.913216) (xy 459.329925 -46.836173) (xy 459.372274 -46.762823) (xy 459.421403 -46.693831)
			(xy 459.476868 -46.629821) (xy 459.538166 -46.571373) (xy 459.604742 -46.519017) (xy 459.675994 -46.473227)
			(xy 459.751275 -46.434416) (xy 459.829905 -46.402937) (xy 459.911172 -46.379076) (xy 459.994338 -46.363047)
			(xy 460.078652 -46.354996) (xy 460.121 -46.354492) (xy 460.121254 -46.354492) (xy 460.164582 -46.355012)
			(xy 460.250826 -46.363468) (xy 460.335839 -46.380267) (xy 460.418817 -46.405248) (xy 460.498974 -46.438176)
			(xy 460.575551 -46.478739) (xy 460.647824 -46.526552) (xy 460.715107 -46.581163) (xy 460.776764 -46.642055)
			(xy 460.832211 -46.708651) (xy 460.880924 -46.780321) (xy 460.922439 -46.856386) (xy 460.956366 -46.936126)
			(xy 460.969868 -46.9773) (xy 460.973424 -46.988984) (xy 460.990442 -47.00651) (xy 461.092042 -47.040292)
			(xy 461.116172 -47.036482) (xy 461.125824 -47.02937) (xy 461.158179 -47.006665) (xy 461.226233 -46.966446)
			(xy 461.297588 -46.932426) (xy 461.371681 -46.904875) (xy 461.447927 -46.88401) (xy 461.525725 -46.869995)
			(xy 461.604459 -46.862941) (xy 461.643984 -46.862492) (xy 461.645 -46.862492) (xy 461.687348 -46.862996)
			(xy 461.771662 -46.871047) (xy 461.854828 -46.887076) (xy 461.936095 -46.910937) (xy 462.014725 -46.942416)
			(xy 462.090006 -46.981227) (xy 462.161258 -47.027017) (xy 462.227834 -47.079373) (xy 462.289132 -47.137821)
			(xy 462.344597 -47.201831) (xy 462.393726 -47.270823) (xy 462.436075 -47.344173) (xy 462.471259 -47.421216)
			(xy 462.498961 -47.501255) (xy 462.518929 -47.583564) (xy 462.530982 -47.667399) (xy 462.535013 -47.752)
			(xy 462.530982 -47.836601) (xy 462.518929 -47.920436) (xy 462.498961 -48.002745) (xy 462.471259 -48.082784)
			(xy 462.436075 -48.159827) (xy 462.393726 -48.233177) (xy 462.344597 -48.302169) (xy 462.289132 -48.366179)
			(xy 462.227834 -48.424627) (xy 462.161258 -48.476983) (xy 462.090006 -48.522773) (xy 462.014725 -48.561584)
			(xy 461.936095 -48.593063) (xy 461.854828 -48.616924) (xy 461.771662 -48.632953) (xy 461.687348 -48.641004)
			(xy 461.645 -48.641508) (xy 461.644746 -48.641508) (xy 461.601418 -48.640988) (xy 461.515174 -48.632532)
			(xy 461.430161 -48.615733) (xy 461.347183 -48.590752) (xy 461.267026 -48.557824) (xy 461.190449 -48.517261)
			(xy 461.118176 -48.469448) (xy 461.050893 -48.414837) (xy 460.989236 -48.353945) (xy 460.933789 -48.287349)
			(xy 460.885076 -48.215679) (xy 460.843561 -48.139614) (xy 460.809634 -48.059874) (xy 460.796132 -48.0187)
			(xy 460.792576 -48.007016) (xy 460.775558 -47.98949) (xy 460.673958 -47.955708) (xy 460.649828 -47.959518)
			(xy 460.640176 -47.96663) (xy 460.607821 -47.989335) (xy 460.539767 -48.029554) (xy 460.468412 -48.063574)
			(xy 460.394319 -48.091125) (xy 460.318073 -48.11199) (xy 460.240275 -48.126005) (xy 460.161541 -48.133059)
			(xy 460.122016 -48.133508) (xy 460.121 -48.133508) (xy 460.078652 -48.133004) (xy 459.994338 -48.124953)
			(xy 459.911172 -48.108924) (xy 459.829905 -48.085063) (xy 459.751275 -48.053584) (xy 459.675994 -48.014773)
			(xy 459.604742 -47.968983) (xy 459.538166 -47.916627) (xy 459.476868 -47.858179) (xy 459.421403 -47.794169)
			(xy 459.372274 -47.725177) (xy 459.329925 -47.651827) (xy 459.294741 -47.574784) (xy 459.267039 -47.494745)
			(xy 459.247071 -47.412436) (xy 459.235018 -47.328601) (xy 459.230988 -47.244) (xy 458.029456 -47.244)
			(xy 458.035215 -47.25517) (xy 458.066703 -47.333822) (xy 458.090571 -47.415112) (xy 458.106605 -47.498302)
			(xy 458.114658 -47.582639) (xy 458.115162 -47.625) (xy 458.114658 -47.667361) (xy 458.106605 -47.751698)
			(xy 458.090571 -47.834888) (xy 458.066703 -47.916178) (xy 458.035215 -47.99483) (xy 457.996393 -48.070133)
			(xy 457.95059 -48.141405) (xy 457.898219 -48.208001) (xy 457.839754 -48.269316) (xy 457.775726 -48.324797)
			(xy 457.706714 -48.37394) (xy 457.633344 -48.4163) (xy 457.556279 -48.451495) (xy 457.476217 -48.479204)
			(xy 457.393884 -48.499178) (xy 457.310025 -48.511235) (xy 457.2254 -48.515267) (xy 457.140775 -48.511235)
			(xy 457.056916 -48.499178) (xy 456.974583 -48.479204) (xy 456.894521 -48.451495) (xy 456.817456 -48.4163)
			(xy 456.744086 -48.37394) (xy 456.675074 -48.324797) (xy 456.611046 -48.269316) (xy 456.552581 -48.208001)
			(xy 456.50021 -48.141405) (xy 456.454407 -48.070133) (xy 456.415585 -47.99483) (xy 456.384097 -47.916178)
			(xy 456.360229 -47.834888) (xy 456.344195 -47.751698) (xy 456.336142 -47.667361) (xy 452.369815 -47.667361)
			(xy 452.382993 -47.687867) (xy 452.421815 -47.76317) (xy 452.453303 -47.841822) (xy 452.477171 -47.923112)
			(xy 452.493205 -48.006302) (xy 452.501258 -48.090639) (xy 452.501762 -48.133) (xy 452.501258 -48.175361)
			(xy 452.493205 -48.259698) (xy 452.477171 -48.342888) (xy 452.453303 -48.424178) (xy 452.421815 -48.50283)
			(xy 452.382993 -48.578133) (xy 452.33719 -48.649405) (xy 452.284819 -48.716001) (xy 452.226354 -48.777316)
			(xy 452.162326 -48.832797) (xy 452.093314 -48.88194) (xy 452.019944 -48.9243) (xy 451.942879 -48.959495)
			(xy 451.862817 -48.987204) (xy 451.780484 -49.007178) (xy 451.696625 -49.019235) (xy 451.612 -49.023267)
			(xy 451.527375 -49.019235) (xy 451.443516 -49.007178) (xy 451.361183 -48.987204) (xy 451.281121 -48.959495)
			(xy 451.204056 -48.9243) (xy 451.130686 -48.88194) (xy 451.061674 -48.832797) (xy 450.997646 -48.777316)
			(xy 450.939181 -48.716001) (xy 450.88681 -48.649405) (xy 450.841007 -48.578133) (xy 450.802185 -48.50283)
			(xy 450.770697 -48.424178) (xy 450.746829 -48.342888) (xy 450.730795 -48.259698) (xy 450.722742 -48.175361)
			(xy 449.717464 -48.175361) (xy 449.686179 -48.208172) (xy 449.622169 -48.263637) (xy 449.553177 -48.312766)
			(xy 449.479827 -48.355115) (xy 449.402784 -48.390299) (xy 449.322745 -48.418001) (xy 449.240436 -48.437969)
			(xy 449.156601 -48.450022) (xy 449.072 -48.454053) (xy 448.987399 -48.450022) (xy 448.903564 -48.437969)
			(xy 448.821255 -48.418001) (xy 448.741216 -48.390299) (xy 448.664173 -48.355115) (xy 448.590823 -48.312766)
			(xy 448.521831 -48.263637) (xy 448.457821 -48.208172) (xy 448.399373 -48.146874) (xy 448.347017 -48.080298)
			(xy 448.301227 -48.009046) (xy 448.262416 -47.933765) (xy 448.230937 -47.855135) (xy 448.207076 -47.773868)
			(xy 448.191047 -47.690702) (xy 448.182996 -47.606388) (xy 448.182492 -47.56404) (xy 448.182492 -47.563786)
			(xy 448.182977 -47.52157) (xy 448.191003 -47.437519) (xy 448.206953 -47.354606) (xy 448.230683 -47.273576)
			(xy 448.261981 -47.195158) (xy 448.300564 -47.120056) (xy 448.346087 -47.048946) (xy 448.371722 -47.0154)
			(xy 448.37858 -47.006764) (xy 448.38366 -46.985682) (xy 448.367658 -46.899576) (xy 448.365202 -46.889121)
			(xy 448.352975 -46.871491) (xy 448.344036 -46.86554) (xy 448.343782 -46.865286) (xy 448.308929 -46.843927)
			(xy 448.242837 -46.795816) (xy 448.181436 -46.741847) (xy 448.125243 -46.682474) (xy 448.074731 -46.618198)
			(xy 448.030327 -46.549561) (xy 447.992405 -46.477141) (xy 447.961284 -46.401548) (xy 447.948812 -46.36262)
			(xy 447.944882 -46.35175) (xy 447.929092 -46.334898) (xy 447.907531 -46.326625) (xy 447.89598 -46.32706)
			(xy 447.877345 -46.328504) (xy 447.839995 -46.330029) (xy 447.821304 -46.330108) (xy 447.82105 -46.330108)
			(xy 447.781949 -46.329702) (xy 447.70405 -46.322828) (xy 447.627056 -46.309139) (xy 447.551561 -46.288741)
			(xy 447.478151 -46.261789) (xy 447.44259 -46.245526) (xy 447.432203 -46.241291) (xy 447.409797 -46.241291)
			(xy 447.39941 -46.245526) (xy 447.363843 -46.261771) (xy 447.290428 -46.288702) (xy 447.214934 -46.309092)
			(xy 447.137944 -46.322783) (xy 447.060049 -46.32967) (xy 447.02095 -46.330108) (xy 446.978603 -46.329602)
			(xy 446.894293 -46.321547) (xy 446.81113 -46.305514) (xy 446.729868 -46.28165) (xy 446.651242 -46.250169)
			(xy 446.575965 -46.211357) (xy 446.504717 -46.165565) (xy 446.438145 -46.113209) (xy 446.376851 -46.054761)
			(xy 446.32139 -45.990753) (xy 446.272264 -45.921762) (xy 446.229918 -45.848414) (xy 446.194736 -45.771373)
			(xy 446.167037 -45.691337) (xy 446.14707 -45.60903) (xy 446.135017 -45.525198) (xy 446.130987 -45.4406)
			(xy 437.781408 -45.4406) (xy 437.786643 -45.468242) (xy 437.79443 -45.551293) (xy 437.794908 -45.593)
			(xy 437.794404 -45.635348) (xy 437.786353 -45.719662) (xy 437.770324 -45.802828) (xy 437.746463 -45.884095)
			(xy 437.714984 -45.962725) (xy 437.676173 -46.038006) (xy 437.630383 -46.109258) (xy 437.578027 -46.175834)
			(xy 437.519579 -46.237132) (xy 437.455569 -46.292597) (xy 437.386577 -46.341726) (xy 437.313227 -46.384075)
			(xy 437.236184 -46.419259) (xy 437.156145 -46.446961) (xy 437.073836 -46.466929) (xy 436.990001 -46.478982)
			(xy 436.9054 -46.483013) (xy 436.820799 -46.478982) (xy 436.736964 -46.466929) (xy 436.654655 -46.446961)
			(xy 436.574616 -46.419259) (xy 436.497573 -46.384075) (xy 436.424223 -46.341726) (xy 436.355231 -46.292597)
			(xy 436.291221 -46.237132) (xy 436.232773 -46.175834) (xy 436.180417 -46.109258) (xy 436.134627 -46.038006)
			(xy 436.095816 -45.962725) (xy 436.064337 -45.884095) (xy 436.040476 -45.802828) (xy 436.024447 -45.719662)
			(xy 436.016396 -45.635348) (xy 436.015892 -45.593) (xy 432.93147 -45.593) (xy 432.917299 -45.63964)
			(xy 432.88372 -45.720526) (xy 432.863498 -45.75937) (xy 432.85808 -45.770836) (xy 432.85808 -45.796164)
			(xy 432.863498 -45.80763) (xy 432.883723 -45.846471) (xy 432.917274 -45.927366) (xy 432.94272 -46.011164)
			(xy 432.959816 -46.097056) (xy 432.968395 -46.184212) (xy 432.968908 -46.228) (xy 432.968501 -46.266451)
			(xy 432.961878 -46.343066) (xy 432.948656 -46.418822) (xy 432.93919 -46.456092) (xy 432.93538 -46.470824)
			(xy 432.944524 -46.499018) (xy 433.03952 -46.576742) (xy 433.06873 -46.580044) (xy 433.082446 -46.57344)
			(xy 433.119254 -46.555791) (xy 433.195459 -46.526512) (xy 433.274024 -46.504333) (xy 433.35429 -46.48944)
			(xy 433.435582 -46.481957) (xy 433.4764 -46.481492) (xy 433.518534 -46.48201) (xy 433.602424 -46.489977)
			(xy 433.685186 -46.50584) (xy 433.766077 -46.529457) (xy 433.844372 -46.560616) (xy 433.919371 -46.599038)
			(xy 433.990401 -46.644378) (xy 434.056827 -46.696232) (xy 434.087778 -46.724824) (xy 434.096076 -46.732055)
			(xy 434.116892 -46.739147) (xy 434.138762 -46.736847) (xy 434.148484 -46.731682) (xy 434.182739 -46.712004)
			(xy 434.254089 -46.678079) (xy 434.328166 -46.650618) (xy 434.404388 -46.629835) (xy 434.482153 -46.615896)
			(xy 434.560848 -46.60891) (xy 434.60035 -46.608492) (xy 434.639444 -46.608895) (xy 434.717333 -46.61573)
			(xy 434.794322 -46.629371) (xy 434.869819 -46.64971) (xy 434.94324 -46.676593) (xy 434.97881 -46.69282)
			(xy 434.989197 -46.697055) (xy 435.011603 -46.697055) (xy 435.02199 -46.69282) (xy 435.057561 -46.676594)
			(xy 435.130977 -46.649695) (xy 435.206473 -46.629348) (xy 435.283464 -46.615712) (xy 435.361355 -46.608892)
			(xy 435.40045 -46.608492) (xy 435.442801 -46.608978) (xy 435.527119 -46.617025) (xy 435.610291 -46.63305)
			(xy 435.672661 -46.651361) (xy 438.276742 -46.651361) (xy 438.276742 -46.566639) (xy 438.284795 -46.482302)
			(xy 438.300829 -46.399112) (xy 438.324697 -46.317822) (xy 438.356185 -46.23917) (xy 438.395007 -46.163867)
			(xy 438.44081 -46.092595) (xy 438.493181 -46.025999) (xy 438.551646 -45.964684) (xy 438.615674 -45.909203)
			(xy 438.684686 -45.86006) (xy 438.758056 -45.8177) (xy 438.835121 -45.782505) (xy 438.915183 -45.754796)
			(xy 438.997516 -45.734822) (xy 439.081375 -45.722765) (xy 439.166 -45.718734) (xy 439.250625 -45.722765)
			(xy 439.334484 -45.734822) (xy 439.416817 -45.754796) (xy 439.496879 -45.782505) (xy 439.573944 -45.8177)
			(xy 439.647314 -45.86006) (xy 439.716326 -45.909203) (xy 439.780354 -45.964684) (xy 439.838819 -46.025999)
			(xy 439.89119 -46.092595) (xy 439.936993 -46.163867) (xy 439.975815 -46.23917) (xy 440.007303 -46.317822)
			(xy 440.031171 -46.399112) (xy 440.047205 -46.482302) (xy 440.055258 -46.566639) (xy 440.055762 -46.609)
			(xy 440.055258 -46.651361) (xy 440.047205 -46.735698) (xy 440.031171 -46.818888) (xy 440.007303 -46.900178)
			(xy 439.975815 -46.97883) (xy 439.936993 -47.054133) (xy 439.89119 -47.125405) (xy 439.838819 -47.192001)
			(xy 439.780354 -47.253316) (xy 439.716326 -47.308797) (xy 439.647314 -47.35794) (xy 439.573944 -47.4003)
			(xy 439.496879 -47.435495) (xy 439.416817 -47.463204) (xy 439.334484 -47.483178) (xy 439.250625 -47.495235)
			(xy 439.166 -47.499267) (xy 439.081375 -47.495235) (xy 438.997516 -47.483178) (xy 438.915183 -47.463204)
			(xy 438.835121 -47.435495) (xy 438.758056 -47.4003) (xy 438.684686 -47.35794) (xy 438.615674 -47.308797)
			(xy 438.551646 -47.253316) (xy 438.493181 -47.192001) (xy 438.44081 -47.125405) (xy 438.395007 -47.054133)
			(xy 438.356185 -46.97883) (xy 438.324697 -46.900178) (xy 438.300829 -46.818888) (xy 438.284795 -46.735698)
			(xy 438.276742 -46.651361) (xy 435.672661 -46.651361) (xy 435.691562 -46.65691) (xy 435.770198 -46.688387)
			(xy 435.845485 -46.727196) (xy 435.916742 -46.772987) (xy 435.983324 -46.825344) (xy 436.044627 -46.883793)
			(xy 436.100096 -46.947805) (xy 436.149229 -47.016799) (xy 436.191581 -47.090152) (xy 436.226769 -47.167199)
			(xy 436.254473 -47.247241) (xy 436.274443 -47.329555) (xy 436.286498 -47.413394) (xy 436.290528 -47.498)
			(xy 436.286498 -47.582606) (xy 436.283077 -47.606401) (xy 444.692782 -47.606401) (xy 444.692782 -47.521679)
			(xy 444.700835 -47.437342) (xy 444.716869 -47.354152) (xy 444.740737 -47.272862) (xy 444.772225 -47.19421)
			(xy 444.811047 -47.118907) (xy 444.85685 -47.047635) (xy 444.909221 -46.981039) (xy 444.967686 -46.919724)
			(xy 445.031714 -46.864243) (xy 445.100726 -46.8151) (xy 445.174096 -46.77274) (xy 445.251161 -46.737545)
			(xy 445.331223 -46.709836) (xy 445.413556 -46.689862) (xy 445.497415 -46.677805) (xy 445.58204 -46.673774)
			(xy 445.666665 -46.677805) (xy 445.750524 -46.689862) (xy 445.832857 -46.709836) (xy 445.912919 -46.737545)
			(xy 445.989984 -46.77274) (xy 446.063354 -46.8151) (xy 446.132366 -46.864243) (xy 446.196394 -46.919724)
			(xy 446.254859 -46.981039) (xy 446.30723 -47.047635) (xy 446.353033 -47.118907) (xy 446.391855 -47.19421)
			(xy 446.423343 -47.272862) (xy 446.447211 -47.354152) (xy 446.463245 -47.437342) (xy 446.471298 -47.521679)
			(xy 446.471802 -47.56404) (xy 446.471298 -47.606401) (xy 446.463245 -47.690738) (xy 446.447211 -47.773928)
			(xy 446.423343 -47.855218) (xy 446.391855 -47.93387) (xy 446.353033 -48.009173) (xy 446.30723 -48.080445)
			(xy 446.254859 -48.147041) (xy 446.196394 -48.208356) (xy 446.132366 -48.263837) (xy 446.063354 -48.31298)
			(xy 445.989984 -48.35534) (xy 445.912919 -48.390535) (xy 445.832857 -48.418244) (xy 445.750524 -48.438218)
			(xy 445.666665 -48.450275) (xy 445.58204 -48.454307) (xy 445.497415 -48.450275) (xy 445.413556 -48.438218)
			(xy 445.331223 -48.418244) (xy 445.251161 -48.390535) (xy 445.174096 -48.35534) (xy 445.100726 -48.31298)
			(xy 445.031714 -48.263837) (xy 444.967686 -48.208356) (xy 444.909221 -48.147041) (xy 444.85685 -48.080445)
			(xy 444.811047 -48.009173) (xy 444.772225 -47.93387) (xy 444.740737 -47.855218) (xy 444.716869 -47.773928)
			(xy 444.700835 -47.690738) (xy 444.692782 -47.606401) (xy 436.283077 -47.606401) (xy 436.274443 -47.666445)
			(xy 436.254473 -47.748759) (xy 436.226769 -47.828801) (xy 436.191581 -47.905848) (xy 436.149229 -47.979201)
			(xy 436.100096 -48.048195) (xy 436.044627 -48.112207) (xy 435.983324 -48.170656) (xy 435.916742 -48.223013)
			(xy 435.845485 -48.268804) (xy 435.770198 -48.307613) (xy 435.691562 -48.33909) (xy 435.610291 -48.36295)
			(xy 435.527119 -48.378975) (xy 435.442801 -48.387022) (xy 435.40045 -48.387508) (xy 435.361356 -48.387105)
			(xy 435.283467 -48.38027) (xy 435.206478 -48.366629) (xy 435.130981 -48.34629) (xy 435.05756 -48.319407)
			(xy 435.02199 -48.30318) (xy 435.011603 -48.298945) (xy 434.989197 -48.298945) (xy 434.97881 -48.30318)
			(xy 434.943239 -48.319406) (xy 434.869823 -48.346305) (xy 434.794327 -48.366652) (xy 434.717336 -48.380288)
			(xy 434.639445 -48.387108) (xy 434.60035 -48.387508) (xy 434.558215 -48.387022) (xy 434.474324 -48.37905)
			(xy 434.391562 -48.363183) (xy 434.310671 -48.339561) (xy 434.232375 -48.308398) (xy 434.157377 -48.269972)
			(xy 434.086347 -48.224627) (xy 434.019923 -48.17277) (xy 433.988972 -48.144176) (xy 433.980643 -48.136987)
			(xy 433.959845 -48.129883) (xy 433.937987 -48.132164) (xy 433.928266 -48.137318) (xy 433.894023 -48.157017)
			(xy 433.82267 -48.190938) (xy 433.74859 -48.218396) (xy 433.672366 -48.239175) (xy 433.594599 -48.25311)
			(xy 433.515903 -48.260092) (xy 433.4764 -48.260508) (xy 433.435298 -48.260033) (xy 433.353443 -48.252448)
			(xy 433.272638 -48.237343) (xy 433.193571 -48.214847) (xy 433.116917 -48.185151) (xy 433.04333 -48.148509)
			(xy 432.973438 -48.105234) (xy 432.907837 -48.055694) (xy 432.847087 -48.000313) (xy 432.791706 -47.939563)
			(xy 432.742166 -47.873962) (xy 432.698891 -47.80407) (xy 432.662249 -47.730483) (xy 432.632553 -47.653829)
			(xy 432.610057 -47.574762) (xy 432.594952 -47.493957) (xy 432.587367 -47.412102) (xy 432.586892 -47.371)
			(xy 432.587299 -47.332549) (xy 432.593922 -47.255934) (xy 432.607144 -47.180178) (xy 432.61661 -47.142908)
			(xy 432.62042 -47.128176) (xy 432.611276 -47.099982) (xy 432.51628 -47.022258) (xy 432.48707 -47.018956)
			(xy 432.473354 -47.02556) (xy 432.436546 -47.043209) (xy 432.360341 -47.072488) (xy 432.281776 -47.094667)
			(xy 432.20151 -47.10956) (xy 432.120218 -47.117043) (xy 432.0794 -47.117508) (xy 432.036653 -47.117036)
			(xy 431.951552 -47.108861) (xy 431.867628 -47.092558) (xy 431.785656 -47.068278) (xy 431.706391 -47.036244)
			(xy 431.630566 -46.996752) (xy 431.558881 -46.950167) (xy 431.491996 -46.896918) (xy 431.46091 -46.867572)
			(xy 431.452062 -46.859827) (xy 431.429685 -46.852684) (xy 431.417984 -46.853856) (xy 431.385093 -46.858429)
			(xy 431.318857 -46.863257) (xy 431.28565 -46.863508) (xy 431.244545 -46.86294) (xy 431.162686 -46.85536)
			(xy 431.081876 -46.840262) (xy 431.002802 -46.817773) (xy 430.926141 -46.788085) (xy 430.852545 -46.751451)
			(xy 430.782643 -46.708184) (xy 430.71703 -46.658654) (xy 430.656267 -46.603281) (xy 430.60087 -46.542539)
			(xy 430.551314 -46.476946) (xy 430.508019 -46.407061) (xy 430.471357 -46.333479) (xy 430.441639 -46.25683)
			(xy 430.419118 -46.177765) (xy 430.403988 -46.09696) (xy 430.396376 -46.015104) (xy 430.395888 -45.974)
			(xy 429.127412 -45.974) (xy 429.166969 -45.991478) (xy 429.242797 -46.033071) (xy 429.314231 -46.081827)
			(xy 429.380597 -46.137285) (xy 429.441267 -46.198921) (xy 429.495669 -46.266154) (xy 429.54329 -46.33835)
			(xy 429.583679 -46.414826) (xy 429.616457 -46.494861) (xy 429.641313 -46.577699) (xy 429.658012 -46.662558)
			(xy 429.666397 -46.748637) (xy 429.666908 -46.79188) (xy 429.666357 -46.835803) (xy 429.657711 -46.923222)
			(xy 429.640492 -47.009363) (xy 429.614866 -47.093387) (xy 429.581084 -47.174477) (xy 429.539475 -47.251843)
			(xy 429.490443 -47.324731) (xy 429.434467 -47.392433) (xy 429.372091 -47.454287) (xy 429.303922 -47.509693)
			(xy 429.230624 -47.558111) (xy 429.152911 -47.599069) (xy 429.112426 -47.61611) (xy 429.10233 -47.62075)
			(xy 429.08718 -47.636971) (xy 429.083216 -47.647352) (xy 429.069395 -47.688012) (xy 429.034956 -47.76669)
			(xy 428.993096 -47.841683) (xy 428.944205 -47.912294) (xy 428.888737 -47.977864) (xy 428.827208 -48.037784)
			(xy 428.760192 -48.091497) (xy 428.688312 -48.138501) (xy 428.612237 -48.17836) (xy 428.532674 -48.210703)
			(xy 428.450366 -48.235228) (xy 428.366077 -48.251708) (xy 428.280592 -48.259989) (xy 428.23765 -48.260508)
			(xy 428.196545 -48.25994) (xy 428.114686 -48.25236) (xy 428.033876 -48.237262) (xy 427.954802 -48.214773)
			(xy 427.878141 -48.185085) (xy 427.804545 -48.148451) (xy 427.734643 -48.105184) (xy 427.66903 -48.055654)
			(xy 427.608267 -48.000281) (xy 427.55287 -47.939539) (xy 427.503314 -47.873946) (xy 427.460019 -47.804061)
			(xy 427.423357 -47.730479) (xy 427.393639 -47.65383) (xy 427.371118 -47.574765) (xy 427.355988 -47.49396)
			(xy 427.348376 -47.412104) (xy 427.347888 -47.371) (xy 427.348394 -47.327494) (xy 427.356888 -47.240897)
			(xy 427.373796 -47.155543) (xy 427.398954 -47.072247) (xy 427.432124 -46.991806) (xy 427.472988 -46.914986)
			(xy 427.521157 -46.842522) (xy 427.576169 -46.775107) (xy 427.60646 -46.743874) (xy 427.613826 -46.736762)
			(xy 427.621192 -46.718474) (xy 427.621446 -46.626272) (xy 427.613826 -46.607984) (xy 427.60646 -46.600872)
			(xy 427.57624 -46.569612) (xy 427.521318 -46.502202) (xy 427.473233 -46.429757) (xy 427.432444 -46.352966)
			(xy 427.39934 -46.272563) (xy 427.374237 -46.189314) (xy 427.357374 -46.104014) (xy 427.348912 -46.017476)
			(xy 427.348396 -45.974) (xy 427.348898 -45.930516) (xy 427.357383 -45.843963) (xy 427.374273 -45.758652)
			(xy 427.399407 -45.675395) (xy 427.432544 -45.594987) (xy 427.473368 -45.518197) (xy 427.52149 -45.445756)
			(xy 427.57645 -45.378357) (xy 427.606714 -45.347128) (xy 427.613826 -45.339762) (xy 427.621446 -45.321474)
			(xy 427.621446 -45.229526) (xy 427.613826 -45.211238) (xy 427.606714 -45.203872) (xy 427.576453 -45.172642)
			(xy 427.521499 -45.10524) (xy 427.473382 -45.032798) (xy 427.432562 -44.956007) (xy 427.399429 -44.8756)
			(xy 427.374299 -44.792344) (xy 427.357411 -44.707034) (xy 427.348927 -44.620483) (xy 427.348927 -44.533517)
			(xy 427.357411 -44.446966) (xy 427.374299 -44.361656) (xy 427.399429 -44.2784) (xy 427.432562 -44.197993)
			(xy 427.473382 -44.121202) (xy 427.521499 -44.04876) (xy 427.576453 -43.981358) (xy 427.606714 -43.950128)
			(xy 427.613826 -43.942762) (xy 427.621446 -43.924474) (xy 427.621446 -43.832526) (xy 427.613826 -43.814238)
			(xy 427.606714 -43.806872) (xy 427.576453 -43.775642) (xy 427.521499 -43.70824) (xy 427.473382 -43.635798)
			(xy 427.432562 -43.559007) (xy 427.399429 -43.4786) (xy 427.374299 -43.395344) (xy 427.357411 -43.310034)
			(xy 427.348927 -43.223483) (xy 427.348927 -43.136517) (xy 427.357411 -43.049966) (xy 427.374299 -42.964656)
			(xy 427.399429 -42.8814) (xy 427.432562 -42.800993) (xy 427.473382 -42.724202) (xy 427.521499 -42.65176)
			(xy 427.576453 -42.584358) (xy 427.606714 -42.553128) (xy 427.613826 -42.545762) (xy 427.621446 -42.527474)
			(xy 427.621446 -42.435526) (xy 427.613826 -42.417238) (xy 427.606714 -42.409872) (xy 427.576453 -42.378642)
			(xy 427.521499 -42.31124) (xy 427.473382 -42.238798) (xy 427.432562 -42.162007) (xy 427.399429 -42.0816)
			(xy 427.374299 -41.998344) (xy 427.357411 -41.913034) (xy 427.348927 -41.826483) (xy 427.348927 -41.739517)
			(xy 427.357411 -41.652966) (xy 427.374299 -41.567656) (xy 427.399429 -41.4844) (xy 427.432562 -41.403993)
			(xy 427.473382 -41.327202) (xy 427.521499 -41.25476) (xy 427.576453 -41.187358) (xy 427.606714 -41.156128)
			(xy 427.613826 -41.148762) (xy 427.621446 -41.130474) (xy 427.621446 -41.038526) (xy 427.613826 -41.020238)
			(xy 427.606714 -41.012872) (xy 427.578131 -40.98338) (xy 427.525875 -40.920013) (xy 427.479682 -40.8521)
			(xy 427.439943 -40.780219) (xy 427.406999 -40.704981) (xy 427.381129 -40.627027) (xy 427.362554 -40.547021)
			(xy 427.356524 -40.506396) (xy 427.354664 -40.496234) (xy 427.344036 -40.478538) (xy 427.33595 -40.472106)
			(xy 427.319186 -40.45966) (xy 427.310044 -40.453426) (xy 427.288452 -40.448692) (xy 427.26686 -40.453426)
			(xy 427.257718 -40.45966) (xy 427.221227 -40.486675) (xy 427.143683 -40.533913) (xy 427.061728 -40.573003)
			(xy 426.976217 -40.603538) (xy 426.88804 -40.6252) (xy 426.798114 -40.637764) (xy 426.752766 -40.64)
			(xy 426.743057 -40.640825) (xy 426.725294 -40.648791) (xy 426.718222 -40.655494) (xy 426.696886 -40.677084)
			(xy 426.690397 -40.684373) (xy 426.682948 -40.702392) (xy 426.682408 -40.712136) (xy 426.681553 -40.75555)
			(xy 426.672291 -40.841896) (xy 426.65466 -40.926928) (xy 426.628827 -41.009838) (xy 426.595038 -41.089836)
			(xy 426.553615 -41.166161) (xy 426.504951 -41.238086) (xy 426.449511 -41.304927) (xy 426.387822 -41.366048)
			(xy 426.32047 -41.420867) (xy 426.248098 -41.468862) (xy 426.171393 -41.509577) (xy 426.091085 -41.542623)
			(xy 426.00794 -41.567688) (xy 425.922748 -41.584531) (xy 425.83632 -41.592993) (xy 425.7929 -41.593516)
			(xy 425.75179 -41.593048) (xy 425.66992 -41.58546) (xy 425.589099 -41.570349) (xy 425.510018 -41.547845)
			(xy 425.433352 -41.518138) (xy 425.359754 -41.481483) (xy 425.289852 -41.438193) (xy 425.224244 -41.388636)
			(xy 425.16349 -41.333236) (xy 425.108107 -41.272466) (xy 425.058568 -41.206845) (xy 425.015297 -41.136931)
			(xy 424.978663 -41.063323) (xy 424.948977 -40.986648) (xy 424.926494 -40.907561) (xy 424.911406 -40.826737)
			(xy 424.903841 -40.744865) (xy 424.903392 -40.703754) (xy 413.337002 -40.703754) (xy 413.411827 -40.737925)
			(xy 413.485177 -40.780274) (xy 413.554169 -40.829403) (xy 413.618179 -40.884868) (xy 413.676627 -40.946166)
			(xy 413.728983 -41.012742) (xy 413.774773 -41.083994) (xy 413.813584 -41.159275) (xy 413.845063 -41.237905)
			(xy 413.868924 -41.319172) (xy 413.884953 -41.402338) (xy 413.893004 -41.486652) (xy 413.893508 -41.529)
			(xy 413.893005 -41.571315) (xy 413.884974 -41.655563) (xy 413.868976 -41.738666) (xy 413.845155 -41.819875)
			(xy 413.813728 -41.898452) (xy 413.774977 -41.973689) (xy 413.752538 -42.009568) (xy 413.747655 -42.017957)
			(xy 413.743983 -42.037) (xy 413.747655 -42.056043) (xy 413.752538 -42.064432) (xy 413.774984 -42.100306)
			(xy 413.813727 -42.175547) (xy 413.845151 -42.254126) (xy 413.86897 -42.335335) (xy 413.88497 -42.418438)
			(xy 413.893006 -42.502685) (xy 413.893508 -42.545) (xy 413.892993 -42.5882) (xy 413.884627 -42.674194)
			(xy 413.867965 -42.758972) (xy 413.843162 -42.841736) (xy 413.810454 -42.921705) (xy 413.770147 -42.998127)
			(xy 413.722622 -43.070282) (xy 413.668327 -43.13749) (xy 413.607772 -43.199119) (xy 413.541528 -43.254586)
			(xy 413.470219 -43.303371) (xy 413.394516 -43.345014) (xy 413.315134 -43.379122) (xy 413.232819 -43.405375)
			(xy 413.19069 -43.41495) (xy 413.180022 -43.417236) (xy 413.16275 -43.429682) (xy 413.113982 -43.513502)
			(xy 413.111696 -43.534838) (xy 413.114998 -43.544998) (xy 413.121742 -43.566575) (xy 413.133304 -43.610284)
			(xy 413.138112 -43.632374) (xy 413.140652 -43.644566) (xy 413.1564 -43.663616) (xy 413.244792 -43.701208)
			(xy 413.256366 -43.705263) (xy 413.280771 -43.703284) (xy 413.291528 -43.697398) (xy 413.291782 -43.697398)
			(xy 413.327317 -43.675598) (xy 413.401707 -43.637955) (xy 413.479293 -43.607436) (xy 413.559394 -43.58431)
			(xy 413.641307 -43.568779) (xy 413.724314 -43.560979) (xy 413.766 -43.560492) (xy 413.808348 -43.560996)
			(xy 413.892662 -43.569047) (xy 413.975828 -43.585076) (xy 414.057095 -43.608937) (xy 414.135725 -43.640416)
			(xy 414.211006 -43.679227) (xy 414.282258 -43.725017) (xy 414.348834 -43.777373) (xy 414.410132 -43.835821)
			(xy 414.465597 -43.899831) (xy 414.514726 -43.968823) (xy 414.557075 -44.042173) (xy 414.588672 -44.111361)
			(xy 414.807142 -44.111361) (xy 414.807142 -44.026639) (xy 414.815195 -43.942302) (xy 414.831229 -43.859112)
			(xy 414.855097 -43.777822) (xy 414.886585 -43.69917) (xy 414.925407 -43.623867) (xy 414.97121 -43.552595)
			(xy 415.023581 -43.485999) (xy 415.082046 -43.424684) (xy 415.146074 -43.369203) (xy 415.215086 -43.32006)
			(xy 415.288456 -43.2777) (xy 415.365521 -43.242505) (xy 415.445583 -43.214796) (xy 415.527916 -43.194822)
			(xy 415.611775 -43.182765) (xy 415.6964 -43.178734) (xy 415.781025 -43.182765) (xy 415.864884 -43.194822)
			(xy 415.947217 -43.214796) (xy 416.027279 -43.242505) (xy 416.104344 -43.2777) (xy 416.177714 -43.32006)
			(xy 416.246726 -43.369203) (xy 416.310754 -43.424684) (xy 416.369219 -43.485999) (xy 416.42159 -43.552595)
			(xy 416.467393 -43.623867) (xy 416.506215 -43.69917) (xy 416.537703 -43.777822) (xy 416.561571 -43.859112)
			(xy 416.577605 -43.942302) (xy 416.585658 -44.026639) (xy 416.586162 -44.069) (xy 416.585658 -44.111361)
			(xy 416.577605 -44.195698) (xy 416.561571 -44.278888) (xy 416.537703 -44.360178) (xy 416.506215 -44.43883)
			(xy 416.467393 -44.514133) (xy 416.42159 -44.585405) (xy 416.369219 -44.652001) (xy 416.310754 -44.713316)
			(xy 416.246726 -44.768797) (xy 416.177714 -44.81794) (xy 416.104344 -44.8603) (xy 416.027279 -44.895495)
			(xy 415.947217 -44.923204) (xy 415.864884 -44.943178) (xy 415.781025 -44.955235) (xy 415.6964 -44.959267)
			(xy 415.611775 -44.955235) (xy 415.527916 -44.943178) (xy 415.445583 -44.923204) (xy 415.365521 -44.895495)
			(xy 415.288456 -44.8603) (xy 415.215086 -44.81794) (xy 415.146074 -44.768797) (xy 415.082046 -44.713316)
			(xy 415.023581 -44.652001) (xy 414.97121 -44.585405) (xy 414.925407 -44.514133) (xy 414.886585 -44.43883)
			(xy 414.855097 -44.360178) (xy 414.831229 -44.278888) (xy 414.815195 -44.195698) (xy 414.807142 -44.111361)
			(xy 414.588672 -44.111361) (xy 414.592259 -44.119216) (xy 414.619961 -44.199255) (xy 414.639929 -44.281564)
			(xy 414.651982 -44.365399) (xy 414.656013 -44.45) (xy 414.651982 -44.534601) (xy 414.639929 -44.618436)
			(xy 414.619961 -44.700745) (xy 414.592259 -44.780784) (xy 414.557075 -44.857827) (xy 414.514726 -44.931177)
			(xy 414.465597 -45.000169) (xy 414.410132 -45.064179) (xy 414.348834 -45.122627) (xy 414.282258 -45.174983)
			(xy 414.211006 -45.220773) (xy 414.135725 -45.259584) (xy 414.057095 -45.291063) (xy 413.975828 -45.314924)
			(xy 413.892662 -45.330953) (xy 413.808348 -45.339004) (xy 413.766 -45.339508) (xy 413.765492 -45.339508)
			(xy 413.725368 -45.339032) (xy 413.645447 -45.331785) (xy 413.566504 -45.317367) (xy 413.489181 -45.295897)
			(xy 413.414106 -45.267549) (xy 413.34189 -45.232553) (xy 413.307276 -45.212254) (xy 413.299722 -45.208112)
			(xy 413.282877 -45.204576) (xy 413.265817 -45.20686) (xy 413.258 -45.210476) (xy 413.169354 -45.255688)
			(xy 413.154876 -45.277024) (xy 413.153606 -45.290232) (xy 413.149558 -45.331263) (xy 413.134727 -45.412375)
			(xy 413.112454 -45.491767) (xy 413.08293 -45.568757) (xy 413.046408 -45.642685) (xy 413.003202 -45.712915)
			(xy 412.953682 -45.778846) (xy 412.898273 -45.839912) (xy 412.837451 -45.895588) (xy 412.771738 -45.945397)
			(xy 412.701698 -45.988911) (xy 412.627931 -46.025757) (xy 412.551072 -46.055618) (xy 412.471779 -46.078239)
			(xy 412.390732 -46.093426) (xy 412.308628 -46.101047) (xy 412.2674 -46.101508) (xy 412.226298 -46.101033)
			(xy 412.144443 -46.093448) (xy 412.063638 -46.078343) (xy 411.984571 -46.055847) (xy 411.907917 -46.026151)
			(xy 411.83433 -45.989509) (xy 411.764438 -45.946234) (xy 411.698837 -45.896694) (xy 411.638087 -45.841313)
			(xy 411.582706 -45.780563) (xy 411.533166 -45.714962) (xy 411.489891 -45.64507) (xy 411.453249 -45.571483)
			(xy 411.423553 -45.494829) (xy 411.401057 -45.415762) (xy 411.385952 -45.334957) (xy 411.378367 -45.253102)
			(xy 411.377892 -45.212) (xy 402.6154 -45.212) (xy 402.6154 -46.863) (xy 416.177988 -46.863) (xy 416.182018 -46.778399)
			(xy 416.194071 -46.694564) (xy 416.214039 -46.612255) (xy 416.241741 -46.532216) (xy 416.276925 -46.455173)
			(xy 416.319274 -46.381823) (xy 416.368403 -46.312831) (xy 416.423868 -46.248821) (xy 416.485166 -46.190373)
			(xy 416.551742 -46.138017) (xy 416.622994 -46.092227) (xy 416.698275 -46.053416) (xy 416.776905 -46.021937)
			(xy 416.858172 -45.998076) (xy 416.941338 -45.982047) (xy 417.025652 -45.973996) (xy 417.068 -45.973492)
			(xy 417.068508 -45.973492) (xy 417.11484 -45.974098) (xy 417.206998 -45.983769) (xy 417.297652 -46.002965)
			(xy 417.385821 -46.031477) (xy 417.428426 -46.049692) (xy 417.438368 -46.053498) (xy 417.459632 -46.053498)
			(xy 417.469574 -46.049692) (xy 417.512236 -46.031447) (xy 417.600529 -46.002903) (xy 417.691314 -45.98371)
			(xy 417.783604 -45.974077) (xy 417.83 -45.973492) (xy 417.867812 -45.973862) (xy 417.943167 -45.980241)
			(xy 418.017707 -45.993004) (xy 418.090891 -46.012059) (xy 418.126672 -46.024292) (xy 418.126926 -46.024292)
			(xy 418.135499 -46.026993) (xy 418.153464 -46.02675) (xy 418.170233 -46.0203) (xy 418.177218 -46.01464)
			(xy 418.254434 -45.947076) (xy 418.26307 -45.92066) (xy 418.260022 -45.907198) (xy 418.250668 -45.860964)
			(xy 418.240615 -45.767167) (xy 418.239956 -45.72) (xy 418.240446 -45.678974) (xy 418.248011 -45.59727)
			(xy 418.263067 -45.516611) (xy 418.285487 -45.43768) (xy 418.315081 -45.36115) (xy 418.351596 -45.28767)
			(xy 418.394722 -45.217864) (xy 418.444093 -45.152327) (xy 418.499289 -45.091614) (xy 418.559841 -45.036242)
			(xy 418.592254 -45.011086) (xy 418.602668 -45.003212) (xy 418.613336 -44.979082) (xy 418.602668 -44.866814)
			(xy 418.587936 -44.845224) (xy 418.575998 -44.839382) (xy 418.539474 -44.820596) (xy 418.46966 -44.777322)
			(xy 418.404133 -44.727795) (xy 418.343452 -44.672437) (xy 418.288134 -44.61172) (xy 418.23865 -44.546161)
			(xy 418.195421 -44.476318) (xy 418.158816 -44.402788) (xy 418.129147 -44.326195) (xy 418.106667 -44.247194)
			(xy 418.091566 -44.166455) (xy 418.083974 -44.084669) (xy 418.083492 -44.0436) (xy 418.083492 -44.043092)
			(xy 418.083996 -44.000744) (xy 418.092047 -43.91643) (xy 418.108076 -43.833264) (xy 418.131937 -43.751997)
			(xy 418.163416 -43.673367) (xy 418.202227 -43.598086) (xy 418.248017 -43.526834) (xy 418.300373 -43.460258)
			(xy 418.358821 -43.39896) (xy 418.422831 -43.343495) (xy 418.491823 -43.294366) (xy 418.565173 -43.252017)
			(xy 418.642216 -43.216833) (xy 418.722255 -43.189131) (xy 418.804564 -43.169163) (xy 418.888399 -43.15711)
			(xy 418.973 -43.15308) (xy 419.057601 -43.15711) (xy 419.141436 -43.169163) (xy 419.223745 -43.189131)
			(xy 419.303784 -43.216833) (xy 419.380827 -43.252017) (xy 419.454177 -43.294366) (xy 419.523169 -43.343495)
			(xy 419.587179 -43.39896) (xy 419.645627 -43.460258) (xy 419.697983 -43.526834) (xy 419.743773 -43.598086)
			(xy 419.782584 -43.673367) (xy 419.814063 -43.751997) (xy 419.837924 -43.833264) (xy 419.853953 -43.91643)
			(xy 419.862004 -44.000744) (xy 419.862508 -44.043092) (xy 419.862066 -44.084113) (xy 419.854514 -44.165806)
			(xy 419.839473 -44.246457) (xy 419.817071 -44.325381) (xy 419.787498 -44.401907) (xy 419.751006 -44.475386)
			(xy 419.707904 -44.545193) (xy 419.658559 -44.610736) (xy 419.603389 -44.671458) (xy 419.542863 -44.726842)
			(xy 419.510464 -44.752006) (xy 419.50005 -44.75988) (xy 419.489382 -44.78401) (xy 419.50005 -44.896278)
			(xy 419.514782 -44.917868) (xy 419.52672 -44.92371) (xy 419.563288 -44.942468) (xy 419.633148 -44.98577)
			(xy 419.698717 -45.03533) (xy 419.759436 -45.090726) (xy 419.814787 -45.151485) (xy 419.864299 -45.217091)
			(xy 419.907549 -45.286983) (xy 419.94417 -45.360565) (xy 419.973847 -45.437212) (xy 419.99633 -45.516269)
			(xy 420.011426 -45.597063) (xy 420.014973 -45.635361) (xy 420.242742 -45.635361) (xy 420.242742 -45.550639)
			(xy 420.250795 -45.466302) (xy 420.266829 -45.383112) (xy 420.290697 -45.301822) (xy 420.322185 -45.22317)
			(xy 420.361007 -45.147867) (xy 420.40681 -45.076595) (xy 420.459181 -45.009999) (xy 420.517646 -44.948684)
			(xy 420.581674 -44.893203) (xy 420.650686 -44.84406) (xy 420.724056 -44.8017) (xy 420.801121 -44.766505)
			(xy 420.881183 -44.738796) (xy 420.963516 -44.718822) (xy 421.047375 -44.706765) (xy 421.132 -44.702734)
			(xy 421.216625 -44.706765) (xy 421.300484 -44.718822) (xy 421.382817 -44.738796) (xy 421.462879 -44.766505)
			(xy 421.539944 -44.8017) (xy 421.613314 -44.84406) (xy 421.682326 -44.893203) (xy 421.746354 -44.948684)
			(xy 421.804819 -45.009999) (xy 421.85719 -45.076595) (xy 421.902993 -45.147867) (xy 421.941815 -45.22317)
			(xy 421.973303 -45.301822) (xy 421.997171 -45.383112) (xy 422.013205 -45.466302) (xy 422.021258 -45.550639)
			(xy 422.021762 -45.593) (xy 422.021258 -45.635361) (xy 422.013205 -45.719698) (xy 421.997171 -45.802888)
			(xy 421.973303 -45.884178) (xy 421.941815 -45.96283) (xy 421.902993 -46.038133) (xy 421.85719 -46.109405)
			(xy 421.8205 -46.156061) (xy 423.811442 -46.156061) (xy 423.811442 -46.071339) (xy 423.819495 -45.987002)
			(xy 423.835529 -45.903812) (xy 423.859397 -45.822522) (xy 423.890885 -45.74387) (xy 423.929707 -45.668567)
			(xy 423.97551 -45.597295) (xy 424.027881 -45.530699) (xy 424.086346 -45.469384) (xy 424.150374 -45.413903)
			(xy 424.219386 -45.36476) (xy 424.292756 -45.3224) (xy 424.369821 -45.287205) (xy 424.449883 -45.259496)
			(xy 424.532216 -45.239522) (xy 424.616075 -45.227465) (xy 424.7007 -45.223434) (xy 424.785325 -45.227465)
			(xy 424.869184 -45.239522) (xy 424.951517 -45.259496) (xy 425.031579 -45.287205) (xy 425.108644 -45.3224)
			(xy 425.182014 -45.36476) (xy 425.251026 -45.413903) (xy 425.315054 -45.469384) (xy 425.373519 -45.530699)
			(xy 425.42589 -45.597295) (xy 425.471693 -45.668567) (xy 425.510515 -45.74387) (xy 425.542003 -45.822522)
			(xy 425.565871 -45.903812) (xy 425.581905 -45.987002) (xy 425.589958 -46.071339) (xy 425.590462 -46.1137)
			(xy 425.589958 -46.156061) (xy 425.581905 -46.240398) (xy 425.565871 -46.323588) (xy 425.542003 -46.404878)
			(xy 425.510515 -46.48353) (xy 425.471693 -46.558833) (xy 425.42589 -46.630105) (xy 425.373519 -46.696701)
			(xy 425.315054 -46.758016) (xy 425.251026 -46.813497) (xy 425.182014 -46.86264) (xy 425.108644 -46.905)
			(xy 425.031579 -46.940195) (xy 424.951517 -46.967904) (xy 424.869184 -46.987878) (xy 424.785325 -46.999935)
			(xy 424.7007 -47.003967) (xy 424.616075 -46.999935) (xy 424.532216 -46.987878) (xy 424.449883 -46.967904)
			(xy 424.369821 -46.940195) (xy 424.292756 -46.905) (xy 424.219386 -46.86264) (xy 424.150374 -46.813497)
			(xy 424.086346 -46.758016) (xy 424.027881 -46.696701) (xy 423.97551 -46.630105) (xy 423.929707 -46.558833)
			(xy 423.890885 -46.48353) (xy 423.859397 -46.404878) (xy 423.835529 -46.323588) (xy 423.819495 -46.240398)
			(xy 423.811442 -46.156061) (xy 421.8205 -46.156061) (xy 421.804819 -46.176001) (xy 421.746354 -46.237316)
			(xy 421.682326 -46.292797) (xy 421.613314 -46.34194) (xy 421.539944 -46.3843) (xy 421.462879 -46.419495)
			(xy 421.382817 -46.447204) (xy 421.300484 -46.467178) (xy 421.216625 -46.479235) (xy 421.132 -46.483267)
			(xy 421.047375 -46.479235) (xy 420.963516 -46.467178) (xy 420.881183 -46.447204) (xy 420.801121 -46.419495)
			(xy 420.724056 -46.3843) (xy 420.650686 -46.34194) (xy 420.581674 -46.292797) (xy 420.517646 -46.237316)
			(xy 420.459181 -46.176001) (xy 420.40681 -46.109405) (xy 420.361007 -46.038133) (xy 420.322185 -45.96283)
			(xy 420.290697 -45.884178) (xy 420.266829 -45.802888) (xy 420.250795 -45.719698) (xy 420.242742 -45.635361)
			(xy 420.014973 -45.635361) (xy 420.019006 -45.678904) (xy 420.01948 -45.72) (xy 420.019048 -45.761111)
			(xy 420.011459 -45.842983) (xy 419.996348 -45.923806) (xy 419.973842 -46.002889) (xy 419.944134 -46.079557)
			(xy 419.907477 -46.153157) (xy 419.864185 -46.223059) (xy 419.814626 -46.288668) (xy 419.759224 -46.349423)
			(xy 419.698451 -46.404806) (xy 419.632826 -46.454344) (xy 419.56291 -46.497615) (xy 419.489299 -46.534248)
			(xy 419.412621 -46.563932) (xy 419.333531 -46.586413) (xy 419.252704 -46.601498) (xy 419.17083 -46.609061)
			(xy 419.129718 -46.609508) (xy 419.091906 -46.609133) (xy 419.016551 -46.602756) (xy 418.942011 -46.589994)
			(xy 418.868827 -46.570941) (xy 418.833046 -46.558708) (xy 418.832792 -46.558708) (xy 418.824215 -46.556021)
			(xy 418.806253 -46.556259) (xy 418.789485 -46.562703) (xy 418.7825 -46.56836) (xy 418.705284 -46.635924)
			(xy 418.696648 -46.66234) (xy 418.699696 -46.675802) (xy 418.708949 -46.721791) (xy 418.718876 -46.815078)
			(xy 418.719508 -46.861984) (xy 418.719508 -46.863) (xy 418.719033 -46.904102) (xy 418.711448 -46.985957)
			(xy 418.696343 -47.066762) (xy 418.673847 -47.145829) (xy 418.644151 -47.222483) (xy 418.607509 -47.29607)
			(xy 418.564234 -47.365962) (xy 418.514694 -47.431563) (xy 418.459313 -47.492313) (xy 418.398563 -47.547694)
			(xy 418.332962 -47.597234) (xy 418.26307 -47.640509) (xy 418.189483 -47.677151) (xy 418.112829 -47.706847)
			(xy 418.033762 -47.729343) (xy 417.952957 -47.744448) (xy 417.871102 -47.752033) (xy 417.83 -47.752508)
			(xy 417.829492 -47.752508) (xy 417.78316 -47.751902) (xy 417.691002 -47.742231) (xy 417.600348 -47.723035)
			(xy 417.512179 -47.694523) (xy 417.469574 -47.676308) (xy 417.459632 -47.672502) (xy 417.438368 -47.672502)
			(xy 417.428426 -47.676308) (xy 417.385823 -47.69453) (xy 417.297656 -47.723048) (xy 417.207 -47.74224)
			(xy 417.11484 -47.7519) (xy 417.068508 -47.752508) (xy 417.068 -47.752508) (xy 417.025652 -47.752004)
			(xy 416.941338 -47.743953) (xy 416.858172 -47.727924) (xy 416.776905 -47.704063) (xy 416.698275 -47.672584)
			(xy 416.622994 -47.633773) (xy 416.551742 -47.587983) (xy 416.485166 -47.535627) (xy 416.423868 -47.477179)
			(xy 416.368403 -47.413169) (xy 416.319274 -47.344177) (xy 416.276925 -47.270827) (xy 416.241741 -47.193784)
			(xy 416.214039 -47.113745) (xy 416.194071 -47.031436) (xy 416.182018 -46.947601) (xy 416.177988 -46.863)
			(xy 402.6154 -46.863) (xy 402.6154 -48.048361) (xy 411.606742 -48.048361) (xy 411.606742 -47.963639)
			(xy 411.614795 -47.879302) (xy 411.630829 -47.796112) (xy 411.654697 -47.714822) (xy 411.686185 -47.63617)
			(xy 411.725007 -47.560867) (xy 411.77081 -47.489595) (xy 411.823181 -47.422999) (xy 411.881646 -47.361684)
			(xy 411.945674 -47.306203) (xy 412.014686 -47.25706) (xy 412.088056 -47.2147) (xy 412.165121 -47.179505)
			(xy 412.245183 -47.151796) (xy 412.327516 -47.131822) (xy 412.411375 -47.119765) (xy 412.496 -47.115734)
			(xy 412.580625 -47.119765) (xy 412.664484 -47.131822) (xy 412.746817 -47.151796) (xy 412.826879 -47.179505)
			(xy 412.903944 -47.2147) (xy 412.977314 -47.25706) (xy 413.046326 -47.306203) (xy 413.110354 -47.361684)
			(xy 413.168819 -47.422999) (xy 413.22119 -47.489595) (xy 413.266993 -47.560867) (xy 413.305815 -47.63617)
			(xy 413.337303 -47.714822) (xy 413.361171 -47.796112) (xy 413.377205 -47.879302) (xy 413.385258 -47.963639)
			(xy 413.385592 -47.991719) (xy 413.533332 -47.991719) (xy 413.533332 -47.906997) (xy 413.541385 -47.82266)
			(xy 413.557419 -47.73947) (xy 413.581287 -47.65818) (xy 413.612775 -47.579528) (xy 413.651597 -47.504225)
			(xy 413.6974 -47.432953) (xy 413.749771 -47.366357) (xy 413.808236 -47.305042) (xy 413.872264 -47.249561)
			(xy 413.941276 -47.200418) (xy 414.014646 -47.158058) (xy 414.091711 -47.122863) (xy 414.171773 -47.095154)
			(xy 414.254106 -47.07518) (xy 414.337965 -47.063123) (xy 414.42259 -47.059092) (xy 414.507215 -47.063123)
			(xy 414.591074 -47.07518) (xy 414.673407 -47.095154) (xy 414.753469 -47.122863) (xy 414.830534 -47.158058)
			(xy 414.903904 -47.200418) (xy 414.972916 -47.249561) (xy 415.036944 -47.305042) (xy 415.095409 -47.366357)
			(xy 415.14778 -47.432953) (xy 415.193583 -47.504225) (xy 415.232405 -47.579528) (xy 415.263893 -47.65818)
			(xy 415.287761 -47.73947) (xy 415.303795 -47.82266) (xy 415.311848 -47.906997) (xy 415.312352 -47.949358)
			(xy 415.311848 -47.991719) (xy 415.303795 -48.076056) (xy 415.287761 -48.159246) (xy 415.263893 -48.240536)
			(xy 415.232405 -48.319188) (xy 415.193583 -48.394491) (xy 415.14778 -48.465763) (xy 415.095409 -48.532359)
			(xy 415.036944 -48.593674) (xy 414.972916 -48.649155) (xy 414.903904 -48.698298) (xy 414.830534 -48.740658)
			(xy 414.753469 -48.775853) (xy 414.673407 -48.803562) (xy 414.591074 -48.823536) (xy 414.507215 -48.835593)
			(xy 414.42259 -48.839625) (xy 414.337965 -48.835593) (xy 414.254106 -48.823536) (xy 414.171773 -48.803562)
			(xy 414.091711 -48.775853) (xy 414.014646 -48.740658) (xy 413.941276 -48.698298) (xy 413.872264 -48.649155)
			(xy 413.808236 -48.593674) (xy 413.749771 -48.532359) (xy 413.6974 -48.465763) (xy 413.651597 -48.394491)
			(xy 413.612775 -48.319188) (xy 413.581287 -48.240536) (xy 413.557419 -48.159246) (xy 413.541385 -48.076056)
			(xy 413.533332 -47.991719) (xy 413.385592 -47.991719) (xy 413.385762 -48.006) (xy 413.385258 -48.048361)
			(xy 413.377205 -48.132698) (xy 413.361171 -48.215888) (xy 413.337303 -48.297178) (xy 413.305815 -48.37583)
			(xy 413.266993 -48.451133) (xy 413.22119 -48.522405) (xy 413.168819 -48.589001) (xy 413.110354 -48.650316)
			(xy 413.046326 -48.705797) (xy 412.977314 -48.75494) (xy 412.903944 -48.7973) (xy 412.826879 -48.832495)
			(xy 412.746817 -48.860204) (xy 412.664484 -48.880178) (xy 412.580625 -48.892235) (xy 412.522592 -48.895)
			(xy 419.225988 -48.895) (xy 419.230018 -48.810399) (xy 419.242071 -48.726564) (xy 419.262039 -48.644255)
			(xy 419.289741 -48.564216) (xy 419.324925 -48.487173) (xy 419.367274 -48.413823) (xy 419.416403 -48.344831)
			(xy 419.471868 -48.280821) (xy 419.533166 -48.222373) (xy 419.599742 -48.170017) (xy 419.670994 -48.124227)
			(xy 419.746275 -48.085416) (xy 419.824905 -48.053937) (xy 419.906172 -48.030076) (xy 419.989338 -48.014047)
			(xy 420.073652 -48.005996) (xy 420.116 -48.005492) (xy 420.116254 -48.005492) (xy 420.168635 -48.006265)
			(xy 420.272666 -48.018617) (xy 420.323772 -48.03013) (xy 420.33234 -48.031758) (xy 420.349665 -48.029875)
			(xy 420.365378 -48.022337) (xy 420.371778 -48.016414) (xy 420.403115 -47.985451) (xy 420.470886 -47.929158)
			(xy 420.543886 -47.879836) (xy 420.621403 -47.837968) (xy 420.702676 -47.803962) (xy 420.786911 -47.778153)
			(xy 420.873284 -47.760791) (xy 420.96095 -47.752048) (xy 421.005 -47.751492) (xy 421.046587 -47.751959)
			(xy 421.129397 -47.759724) (xy 421.211121 -47.775184) (xy 421.291045 -47.798207) (xy 421.368471 -47.828589)
			(xy 421.442723 -47.866067) (xy 421.513151 -47.910312) (xy 421.579142 -47.960939) (xy 421.640119 -48.017504)
			(xy 421.695549 -48.079515) (xy 421.744948 -48.14643) (xy 421.762386 -48.175361) (xy 422.801792 -48.175361)
			(xy 422.801792 -48.090639) (xy 422.809845 -48.006302) (xy 422.825879 -47.923112) (xy 422.849747 -47.841822)
			(xy 422.881235 -47.76317) (xy 422.920057 -47.687867) (xy 422.96586 -47.616595) (xy 423.018231 -47.549999)
			(xy 423.076696 -47.488684) (xy 423.140724 -47.433203) (xy 423.209736 -47.38406) (xy 423.283106 -47.3417)
			(xy 423.360171 -47.306505) (xy 423.440233 -47.278796) (xy 423.522566 -47.258822) (xy 423.606425 -47.246765)
			(xy 423.69105 -47.242734) (xy 423.775675 -47.246765) (xy 423.859534 -47.258822) (xy 423.941867 -47.278796)
			(xy 424.021929 -47.306505) (xy 424.098994 -47.3417) (xy 424.172364 -47.38406) (xy 424.241376 -47.433203)
			(xy 424.305404 -47.488684) (xy 424.363869 -47.549999) (xy 424.41624 -47.616595) (xy 424.462043 -47.687867)
			(xy 424.500865 -47.76317) (xy 424.532353 -47.841822) (xy 424.556221 -47.923112) (xy 424.572255 -48.006302)
			(xy 424.580308 -48.090639) (xy 424.580812 -48.133) (xy 424.580308 -48.175361) (xy 424.572255 -48.259698)
			(xy 424.556221 -48.342888) (xy 424.532353 -48.424178) (xy 424.500865 -48.50283) (xy 424.462043 -48.578133)
			(xy 424.41624 -48.649405) (xy 424.363869 -48.716001) (xy 424.305404 -48.777316) (xy 424.241376 -48.832797)
			(xy 424.172364 -48.88194) (xy 424.098994 -48.9243) (xy 424.021929 -48.959495) (xy 423.941867 -48.987204)
			(xy 423.859534 -49.007178) (xy 423.775675 -49.019235) (xy 423.69105 -49.023267) (xy 423.606425 -49.019235)
			(xy 423.522566 -49.007178) (xy 423.440233 -48.987204) (xy 423.360171 -48.959495) (xy 423.283106 -48.9243)
			(xy 423.209736 -48.88194) (xy 423.140724 -48.832797) (xy 423.076696 -48.777316) (xy 423.018231 -48.716001)
			(xy 422.96586 -48.649405) (xy 422.920057 -48.578133) (xy 422.881235 -48.50283) (xy 422.849747 -48.424178)
			(xy 422.825879 -48.342888) (xy 422.809845 -48.259698) (xy 422.801792 -48.175361) (xy 421.762386 -48.175361)
			(xy 421.787885 -48.217664) (xy 421.80637 -48.25492) (xy 421.811929 -48.264841) (xy 421.829733 -48.278946)
			(xy 421.84066 -48.282098) (xy 421.882137 -48.292216) (xy 421.963083 -48.319377) (xy 422.041054 -48.354168)
			(xy 422.115334 -48.396267) (xy 422.18524 -48.445288) (xy 422.25013 -48.50078) (xy 422.309405 -48.562232)
			(xy 422.362521 -48.629079) (xy 422.40899 -48.700707) (xy 422.448384 -48.776457) (xy 422.480341 -48.855632)
			(xy 422.504567 -48.937504) (xy 422.52084 -49.02132) (xy 422.529009 -49.106309) (xy 422.529508 -49.149)
			(xy 422.529508 -49.149508) (xy 422.529025 -49.19045) (xy 422.521487 -49.271988) (xy 422.506483 -49.352486)
			(xy 422.484142 -49.431265) (xy 422.454653 -49.507655) (xy 422.452795 -49.511401) (xy 425.621446 -49.511401)
			(xy 425.621446 -49.426679) (xy 425.629499 -49.342342) (xy 425.645533 -49.259152) (xy 425.669401 -49.177862)
			(xy 425.700889 -49.09921) (xy 425.739711 -49.023907) (xy 425.785514 -48.952635) (xy 425.837885 -48.886039)
			(xy 425.89635 -48.824724) (xy 425.960378 -48.769243) (xy 426.02939 -48.7201) (xy 426.10276 -48.67774)
			(xy 426.179825 -48.642545) (xy 426.259887 -48.614836) (xy 426.34222 -48.594862) (xy 426.426079 -48.582805)
			(xy 426.510704 -48.578774) (xy 426.595329 -48.582805) (xy 426.679188 -48.594862) (xy 426.761521 -48.614836)
			(xy 426.841583 -48.642545) (xy 426.918648 -48.67774) (xy 426.992018 -48.7201) (xy 427.06103 -48.769243)
			(xy 427.125058 -48.824724) (xy 427.183523 -48.886039) (xy 427.235894 -48.952635) (xy 427.281697 -49.023907)
			(xy 427.320519 -49.09921) (xy 427.352007 -49.177862) (xy 427.375875 -49.259152) (xy 427.391909 -49.342342)
			(xy 427.399962 -49.426679) (xy 427.400466 -49.46904) (xy 427.399962 -49.511401) (xy 427.391909 -49.595738)
			(xy 427.375875 -49.678928) (xy 427.352007 -49.760218) (xy 427.320519 -49.83887) (xy 427.281697 -49.914173)
			(xy 427.235894 -49.985445) (xy 427.183523 -50.052041) (xy 427.125058 -50.113356) (xy 427.06103 -50.168837)
			(xy 426.992018 -50.21798) (xy 426.918648 -50.26034) (xy 426.841583 -50.295535) (xy 426.761521 -50.323244)
			(xy 426.679188 -50.343218) (xy 426.595329 -50.355275) (xy 426.510704 -50.359307) (xy 426.426079 -50.355275)
			(xy 426.34222 -50.343218) (xy 426.259887 -50.323244) (xy 426.179825 -50.295535) (xy 426.10276 -50.26034)
			(xy 426.02939 -50.21798) (xy 425.960378 -50.168837) (xy 425.89635 -50.113356) (xy 425.837885 -50.052041)
			(xy 425.785514 -49.985445) (xy 425.739711 -49.914173) (xy 425.700889 -49.83887) (xy 425.669401 -49.760218)
			(xy 425.645533 -49.678928) (xy 425.629499 -49.595738) (xy 425.621446 -49.511401) (xy 422.452795 -49.511401)
			(xy 422.418265 -49.581011) (xy 422.397174 -49.616106) (xy 422.391586 -49.62525) (xy 422.388538 -49.645824)
			(xy 422.413684 -49.738026) (xy 422.426892 -49.754282) (xy 422.43629 -49.759108) (xy 422.468951 -49.776799)
			(xy 422.531526 -49.81683) (xy 422.590547 -49.861938) (xy 422.645605 -49.911806) (xy 422.67124 -49.938686)
			(xy 422.679114 -49.947322) (xy 422.700958 -49.955704) (xy 422.791636 -49.948338) (xy 422.803155 -49.946873)
			(xy 422.823142 -49.935108) (xy 422.82999 -49.925732) (xy 422.854672 -49.889634) (xy 422.910069 -49.821965)
			(xy 422.97184 -49.76006) (xy 423.03939 -49.704517) (xy 423.112066 -49.655873) (xy 423.189165 -49.614597)
			(xy 423.269943 -49.581089) (xy 423.353621 -49.555672) (xy 423.439389 -49.538591) (xy 423.52642 -49.530011)
			(xy 423.570146 -49.529492) (xy 423.5704 -49.529492) (xy 423.611502 -49.529967) (xy 423.693357 -49.537552)
			(xy 423.774162 -49.552657) (xy 423.853229 -49.575153) (xy 423.929883 -49.604849) (xy 424.00347 -49.641491)
			(xy 424.073362 -49.684766) (xy 424.138963 -49.734306) (xy 424.199713 -49.789687) (xy 424.255094 -49.850437)
			(xy 424.304634 -49.916038) (xy 424.347909 -49.98593) (xy 424.384551 -50.059517) (xy 424.414247 -50.136171)
			(xy 424.436743 -50.215238) (xy 424.451848 -50.296043) (xy 424.459433 -50.377898) (xy 424.459908 -50.419)
			(xy 424.459437 -50.460531) (xy 424.451712 -50.543232) (xy 424.436309 -50.624852) (xy 424.413363 -50.704681)
			(xy 424.383074 -50.782023) (xy 424.345707 -50.856204) (xy 424.301585 -50.926578) (xy 424.251095 -50.992532)
			(xy 424.194675 -51.05349) (xy 424.132817 -51.108923) (xy 424.06606 -51.158347) (xy 423.994986 -51.201331)
			(xy 423.920214 -51.237502) (xy 423.842396 -51.266543) (xy 423.762208 -51.288203) (xy 423.68035 -51.302292)
			(xy 423.63898 -51.305968) (xy 423.629074 -51.30673) (xy 423.611802 -51.315366) (xy 423.558208 -51.374802)
			(xy 423.55208 -51.382214) (xy 423.54542 -51.400238) (xy 423.545254 -51.409854) (xy 423.545254 -51.410108)
			(xy 423.545508 -51.435) (xy 423.545033 -51.476102) (xy 423.537448 -51.557957) (xy 423.522343 -51.638762)
			(xy 423.499847 -51.717829) (xy 423.470151 -51.794483) (xy 423.433509 -51.86807) (xy 423.390234 -51.937962)
			(xy 423.340694 -52.003563) (xy 423.285313 -52.064313) (xy 423.224563 -52.119694) (xy 423.158962 -52.169234)
			(xy 423.114118 -52.197) (xy 431.437288 -52.197) (xy 431.437757 -52.154008) (xy 431.446047 -52.068424)
			(xy 431.462559 -51.98404) (xy 431.487139 -51.901644) (xy 431.519557 -51.822005) (xy 431.559511 -51.745867)
			(xy 431.606627 -51.673941) (xy 431.660466 -51.606898) (xy 431.720525 -51.545366) (xy 431.786242 -51.489917)
			(xy 431.857005 -51.441071) (xy 431.932152 -51.399283) (xy 432.010981 -51.364944) (xy 432.051714 -51.35118)
			(xy 432.062722 -51.346919) (xy 432.079515 -51.330374) (xy 432.087185 -51.308082) (xy 432.086258 -51.296316)
			(xy 432.082774 -51.267615) (xy 432.07909 -51.209911) (xy 432.078892 -51.181) (xy 432.079396 -51.138652)
			(xy 432.087447 -51.054338) (xy 432.103476 -50.971172) (xy 432.127337 -50.889905) (xy 432.158816 -50.811275)
			(xy 432.197627 -50.735994) (xy 432.243417 -50.664742) (xy 432.295773 -50.598166) (xy 432.354221 -50.536868)
			(xy 432.418231 -50.481403) (xy 432.487223 -50.432274) (xy 432.560573 -50.389925) (xy 432.637616 -50.354741)
			(xy 432.717655 -50.327039) (xy 432.799964 -50.307071) (xy 432.883799 -50.295018) (xy 432.9684 -50.290988)
			(xy 433.053001 -50.295018) (xy 433.136836 -50.307071) (xy 433.219145 -50.327039) (xy 433.299184 -50.354741)
			(xy 433.376227 -50.389925) (xy 433.449577 -50.432274) (xy 433.518569 -50.481403) (xy 433.582579 -50.536868)
			(xy 433.641027 -50.598166) (xy 433.693383 -50.664742) (xy 433.739173 -50.735994) (xy 433.777984 -50.811275)
			(xy 433.809463 -50.889905) (xy 433.833324 -50.971172) (xy 433.849353 -51.054338) (xy 433.857404 -51.138652)
			(xy 433.857908 -51.181) (xy 433.857388 -51.223981) (xy 433.849095 -51.309543) (xy 433.832586 -51.393906)
			(xy 433.808016 -51.476283) (xy 433.775613 -51.555905) (xy 433.73568 -51.63203) (xy 433.68859 -51.703947)
			(xy 433.634781 -51.770986) (xy 433.574755 -51.832521) (xy 433.509074 -51.887979) (xy 433.438348 -51.936841)
			(xy 433.363239 -51.978652) (xy 433.284446 -52.013023) (xy 433.243736 -52.02682) (xy 433.232719 -52.031059)
			(xy 433.215932 -52.047617) (xy 433.208264 -52.069915) (xy 433.208271 -52.07) (xy 436.371492 -52.07)
			(xy 436.371921 -52.029564) (xy 436.379252 -51.949025) (xy 436.393863 -51.869485) (xy 436.415633 -51.791598)
			(xy 436.444382 -51.716009) (xy 436.479874 -51.643342) (xy 436.521814 -51.574195) (xy 436.569858 -51.509141)
			(xy 436.623607 -51.448716) (xy 436.682619 -51.393419) (xy 436.746407 -51.343706) (xy 436.780178 -51.321462)
			(xy 436.790846 -51.314604) (xy 436.803292 -51.292252) (xy 436.80507 -51.18227) (xy 436.793132 -51.159664)
			(xy 436.782718 -51.152298) (xy 436.74747 -51.127481) (xy 436.681478 -51.072008) (xy 436.62116 -51.010413)
			(xy 436.567082 -50.943274) (xy 436.51975 -50.871219) (xy 436.47961 -50.794924) (xy 436.447036 -50.715104)
			(xy 436.422335 -50.632509) (xy 436.405737 -50.547911) (xy 436.3974 -50.462105) (xy 436.396892 -50.419)
			(xy 436.397293 -50.379744) (xy 436.404188 -50.301535) (xy 436.41795 -50.224238) (xy 436.438473 -50.148455)
			(xy 436.465596 -50.074777) (xy 436.499109 -50.003776) (xy 436.518558 -49.969674) (xy 436.52277 -49.961721)
			(xy 436.525927 -49.944017) (xy 436.522782 -49.926311) (xy 436.518558 -49.918366) (xy 436.4991 -49.88427)
			(xy 436.465598 -49.813265) (xy 436.438483 -49.739584) (xy 436.417965 -49.663801) (xy 436.404206 -49.586504)
			(xy 436.397311 -49.508296) (xy 436.396892 -49.46904) (xy 436.397396 -49.426692) (xy 436.405447 -49.342378)
			(xy 436.421476 -49.259212) (xy 436.445337 -49.177945) (xy 436.476816 -49.099315) (xy 436.515627 -49.024034)
			(xy 436.561417 -48.952782) (xy 436.613773 -48.886206) (xy 436.672221 -48.824908) (xy 436.736231 -48.769443)
			(xy 436.805223 -48.720314) (xy 436.878573 -48.677965) (xy 436.955616 -48.642781) (xy 437.035655 -48.615079)
			(xy 437.117964 -48.595111) (xy 437.201799 -48.583058) (xy 437.2864 -48.579028) (xy 437.371001 -48.583058)
			(xy 437.454836 -48.595111) (xy 437.537145 -48.615079) (xy 437.612038 -48.641) (xy 440.749987 -48.641)
			(xy 440.754017 -48.556401) (xy 440.76607 -48.472569) (xy 440.786037 -48.390261) (xy 440.813737 -48.310225)
			(xy 440.84892 -48.233183) (xy 440.891266 -48.159835) (xy 440.940392 -48.090844) (xy 440.995854 -48.026835)
			(xy 441.057149 -47.968388) (xy 441.123722 -47.916031) (xy 441.194971 -47.87024) (xy 441.270249 -47.831428)
			(xy 441.348876 -47.799948) (xy 441.430139 -47.776084) (xy 441.513302 -47.760052) (xy 441.597613 -47.751997)
			(xy 441.63996 -47.751492) (xy 441.682994 -47.751994) (xy 441.768661 -47.760295) (xy 441.853126 -47.776832)
			(xy 441.935598 -47.801451) (xy 442.015307 -47.833922) (xy 442.091505 -47.873941) (xy 442.163482 -47.921133)
			(xy 442.230564 -47.975058) (xy 442.292122 -48.03521) (xy 442.347582 -48.101028) (xy 442.396425 -48.171895)
			(xy 442.438193 -48.247149) (xy 442.455808 -48.286416) (xy 442.46154 -48.29867) (xy 442.478503 -48.319739)
			(xy 442.5004 -48.335619) (xy 442.525697 -48.345195) (xy 442.552621 -48.347797) (xy 442.579284 -48.343242)
			(xy 442.603816 -48.33185) (xy 442.6245 -48.314418) (xy 442.639884 -48.29217) (xy 442.644784 -48.279558)
			(xy 442.659282 -48.239954) (xy 442.694709 -48.163412) (xy 442.737221 -48.090566) (xy 442.786435 -48.02207)
			(xy 442.841911 -47.958539) (xy 442.90315 -47.900543) (xy 442.969602 -47.848602) (xy 443.040672 -47.803183)
			(xy 443.115721 -47.764694) (xy 443.194075 -47.73348) (xy 443.275032 -47.70982) (xy 443.357864 -47.693929)
			(xy 443.441828 -47.685947) (xy 443.484 -47.685452) (xy 443.526347 -47.686036) (xy 443.610656 -47.694086)
			(xy 443.693819 -47.710114) (xy 443.775081 -47.733975) (xy 443.853708 -47.765453) (xy 443.928986 -47.804261)
			(xy 444.000235 -47.85005) (xy 444.066808 -47.902404) (xy 444.128103 -47.960849) (xy 444.183566 -48.024856)
			(xy 444.232693 -48.093845) (xy 444.275039 -48.167191) (xy 444.310222 -48.244231) (xy 444.337922 -48.324266)
			(xy 444.35789 -48.406572) (xy 444.369943 -48.490403) (xy 444.373973 -48.575) (xy 444.369943 -48.659597)
			(xy 444.35789 -48.743428) (xy 444.337922 -48.825734) (xy 444.310222 -48.905769) (xy 444.275039 -48.982809)
			(xy 444.232693 -49.056155) (xy 444.183566 -49.125144) (xy 444.128103 -49.189151) (xy 444.066808 -49.247596)
			(xy 444.000235 -49.29995) (xy 443.928986 -49.345739) (xy 443.853708 -49.384547) (xy 443.775081 -49.416025)
			(xy 443.693819 -49.439886) (xy 443.610656 -49.455914) (xy 443.526347 -49.463964) (xy 443.484 -49.464468)
			(xy 443.440966 -49.463937) (xy 443.355299 -49.455642) (xy 443.270834 -49.43911) (xy 443.188362 -49.414494)
			(xy 443.108653 -49.382027) (xy 443.032454 -49.342011) (xy 442.960476 -49.294821) (xy 442.893394 -49.240899)
			(xy 442.831836 -49.180748) (xy 442.776376 -49.114931) (xy 442.727534 -49.044065) (xy 442.685766 -48.968811)
			(xy 442.668152 -48.929544) (xy 442.662318 -48.917345) (xy 442.645366 -48.896291) (xy 442.623485 -48.880423)
			(xy 442.598207 -48.870851) (xy 442.571303 -48.868246) (xy 442.544658 -48.872791) (xy 442.520139 -48.884166)
			(xy 442.499463 -48.901576) (xy 442.484079 -48.923801) (xy 442.479176 -48.936402) (xy 442.464661 -48.975999)
			(xy 442.429232 -49.052539) (xy 442.38672 -49.125382) (xy 442.337505 -49.193876) (xy 442.28203 -49.257405)
			(xy 442.220793 -49.3154) (xy 442.154342 -49.36734) (xy 442.083275 -49.412759) (xy 442.008228 -49.45125)
			(xy 441.929877 -49.482466) (xy 441.848923 -49.506128) (xy 441.766093 -49.522024) (xy 441.682131 -49.53001)
			(xy 441.63996 -49.530508) (xy 441.597613 -49.530003) (xy 441.513302 -49.521948) (xy 441.430139 -49.505916)
			(xy 441.348876 -49.482052) (xy 441.270249 -49.450572) (xy 441.194971 -49.41176) (xy 441.123722 -49.365969)
			(xy 441.057149 -49.313612) (xy 440.995854 -49.255165) (xy 440.940392 -49.191156) (xy 440.891266 -49.122165)
			(xy 440.84892 -49.048817) (xy 440.813737 -48.971775) (xy 440.786037 -48.891739) (xy 440.76607 -48.809431)
			(xy 440.754017 -48.725599) (xy 440.749987 -48.641) (xy 437.612038 -48.641) (xy 437.617184 -48.642781)
			(xy 437.694227 -48.677965) (xy 437.767577 -48.720314) (xy 437.836569 -48.769443) (xy 437.900579 -48.824908)
			(xy 437.959027 -48.886206) (xy 438.011383 -48.952782) (xy 438.057173 -49.024034) (xy 438.095984 -49.099315)
			(xy 438.127463 -49.177945) (xy 438.151324 -49.259212) (xy 438.167353 -49.342378) (xy 438.175404 -49.426692)
			(xy 438.175908 -49.46904) (xy 438.175479 -49.508296) (xy 438.16859 -49.586504) (xy 438.154833 -49.6638)
			(xy 438.134315 -49.739583) (xy 438.107197 -49.813262) (xy 438.073688 -49.884263) (xy 438.054242 -49.918366)
			(xy 438.049998 -49.926304) (xy 438.046853 -49.944017) (xy 438.05001 -49.961729) (xy 438.054242 -49.969674)
			(xy 438.073676 -50.003784) (xy 438.107181 -50.074786) (xy 438.134301 -50.148463) (xy 438.154822 -50.224244)
			(xy 438.168587 -50.301538) (xy 438.175487 -50.379745) (xy 438.175908 -50.419) (xy 438.175383 -50.461647)
			(xy 438.167221 -50.546548) (xy 438.159107 -50.588361) (xy 439.019692 -50.588361) (xy 439.019692 -50.503639)
			(xy 439.027745 -50.419302) (xy 439.043779 -50.336112) (xy 439.067647 -50.254822) (xy 439.099135 -50.17617)
			(xy 439.137957 -50.100867) (xy 439.18376 -50.029595) (xy 439.236131 -49.962999) (xy 439.294596 -49.901684)
			(xy 439.358624 -49.846203) (xy 439.427636 -49.79706) (xy 439.501006 -49.7547) (xy 439.578071 -49.719505)
			(xy 439.658133 -49.691796) (xy 439.740466 -49.671822) (xy 439.824325 -49.659765) (xy 439.90895 -49.655734)
			(xy 439.993575 -49.659765) (xy 440.077434 -49.671822) (xy 440.159767 -49.691796) (xy 440.239829 -49.719505)
			(xy 440.316894 -49.7547) (xy 440.390264 -49.79706) (xy 440.459276 -49.846203) (xy 440.523304 -49.901684)
			(xy 440.581769 -49.962999) (xy 440.63414 -50.029595) (xy 440.679943 -50.100867) (xy 440.718765 -50.17617)
			(xy 440.750253 -50.254822) (xy 440.774121 -50.336112) (xy 440.790155 -50.419302) (xy 440.798208 -50.503639)
			(xy 440.798712 -50.546) (xy 440.798208 -50.588361) (xy 440.790155 -50.672698) (xy 440.774121 -50.755888)
			(xy 440.750253 -50.837178) (xy 440.718765 -50.91583) (xy 440.679943 -50.991133) (xy 440.63414 -51.062405)
			(xy 440.581769 -51.129001) (xy 440.523304 -51.190316) (xy 440.459276 -51.245797) (xy 440.390264 -51.29494)
			(xy 440.316894 -51.3373) (xy 440.239829 -51.372495) (xy 440.159767 -51.400204) (xy 440.077434 -51.420178)
			(xy 439.993575 -51.432235) (xy 439.90895 -51.436267) (xy 439.824325 -51.432235) (xy 439.740466 -51.420178)
			(xy 439.658133 -51.400204) (xy 439.578071 -51.372495) (xy 439.501006 -51.3373) (xy 439.427636 -51.29494)
			(xy 439.358624 -51.245797) (xy 439.294596 -51.190316) (xy 439.236131 -51.129001) (xy 439.18376 -51.062405)
			(xy 439.137957 -50.991133) (xy 439.099135 -50.91583) (xy 439.067647 -50.837178) (xy 439.043779 -50.755888)
			(xy 439.027745 -50.672698) (xy 439.019692 -50.588361) (xy 438.159107 -50.588361) (xy 438.150972 -50.630279)
			(xy 438.126786 -50.712071) (xy 438.094883 -50.791173) (xy 438.055558 -50.866859) (xy 438.00917 -50.938435)
			(xy 437.956146 -51.005243) (xy 437.896973 -51.066671) (xy 437.832192 -51.122154) (xy 437.7624 -51.171184)
			(xy 437.725566 -51.192684) (xy 437.718078 -51.19736) (xy 437.706638 -51.210793) (xy 437.700417 -51.227303)
			(xy 437.699912 -51.236118) (xy 437.699404 -51.26609) (xy 437.699601 -51.274927) (xy 437.705346 -51.291631)
			(xy 437.716432 -51.305384) (xy 437.723788 -51.310286) (xy 437.726074 -51.311556) (xy 437.736606 -51.317274)
			(xy 437.760459 -51.31926) (xy 437.771794 -51.315366) (xy 437.811614 -51.299839) (xy 437.893571 -51.275569)
			(xy 437.977476 -51.259271) (xy 438.062559 -51.251093) (xy 438.105296 -51.250596) (xy 438.147646 -51.251076)
			(xy 438.231961 -51.259127) (xy 438.31513 -51.275156) (xy 438.396398 -51.299018) (xy 438.47503 -51.330497)
			(xy 438.550314 -51.369308) (xy 438.621567 -51.4151) (xy 438.688145 -51.467457) (xy 438.749445 -51.525906)
			(xy 438.804911 -51.589917) (xy 438.854042 -51.658911) (xy 438.896391 -51.732263) (xy 438.931577 -51.809308)
			(xy 438.933893 -51.816) (xy 443.083188 -51.816) (xy 443.083671 -51.77414) (xy 443.091519 -51.69079)
			(xy 443.107166 -51.608546) (xy 443.130472 -51.528136) (xy 443.161231 -51.450272) (xy 443.199171 -51.375643)
			(xy 443.243956 -51.30491) (xy 443.29519 -51.238698) (xy 443.35242 -51.177594) (xy 443.415138 -51.122138)
			(xy 443.48279 -51.072822) (xy 443.554777 -51.030081) (xy 443.630462 -50.994294) (xy 443.709175 -50.965778)
			(xy 443.790219 -50.944785) (xy 443.831472 -50.937668) (xy 443.844172 -50.935636) (xy 443.864492 -50.919888)
			(xy 443.904116 -50.829972) (xy 443.907286 -50.822092) (xy 443.908671 -50.805169) (xy 443.904462 -50.788719)
			(xy 443.900052 -50.781458) (xy 443.876713 -50.745099) (xy 443.836369 -50.668694) (xy 443.803629 -50.588734)
			(xy 443.778802 -50.505975) (xy 443.762123 -50.421197) (xy 443.753749 -50.335201) (xy 443.75324 -50.292)
			(xy 443.753744 -50.249639) (xy 443.761797 -50.165302) (xy 443.777831 -50.082112) (xy 443.801699 -50.000822)
			(xy 443.833187 -49.92217) (xy 443.872009 -49.846867) (xy 443.917812 -49.775595) (xy 443.970183 -49.708999)
			(xy 444.028648 -49.647684) (xy 444.092676 -49.592203) (xy 444.161688 -49.54306) (xy 444.235058 -49.5007)
			(xy 444.312123 -49.465505) (xy 444.392185 -49.437796) (xy 444.474518 -49.417822) (xy 444.558377 -49.405765)
			(xy 444.643002 -49.401734) (xy 444.727627 -49.405765) (xy 444.811486 -49.417822) (xy 444.893819 -49.437796)
			(xy 444.973881 -49.465505) (xy 445.050946 -49.5007) (xy 445.124316 -49.54306) (xy 445.165464 -49.572361)
			(xy 458.749142 -49.572361) (xy 458.749142 -49.487639) (xy 458.757195 -49.403302) (xy 458.773229 -49.320112)
			(xy 458.797097 -49.238822) (xy 458.828585 -49.16017) (xy 458.867407 -49.084867) (xy 458.91321 -49.013595)
			(xy 458.965581 -48.946999) (xy 459.024046 -48.885684) (xy 459.088074 -48.830203) (xy 459.157086 -48.78106)
			(xy 459.230456 -48.7387) (xy 459.307521 -48.703505) (xy 459.387583 -48.675796) (xy 459.469916 -48.655822)
			(xy 459.553775 -48.643765) (xy 459.6384 -48.639734) (xy 459.723025 -48.643765) (xy 459.806884 -48.655822)
			(xy 459.889217 -48.675796) (xy 459.969279 -48.703505) (xy 460.046344 -48.7387) (xy 460.119714 -48.78106)
			(xy 460.188726 -48.830203) (xy 460.252754 -48.885684) (xy 460.311219 -48.946999) (xy 460.36359 -49.013595)
			(xy 460.409393 -49.084867) (xy 460.448215 -49.16017) (xy 460.479703 -49.238822) (xy 460.503571 -49.320112)
			(xy 460.519605 -49.403302) (xy 460.527658 -49.487639) (xy 460.528162 -49.53) (xy 460.527658 -49.572361)
			(xy 460.519605 -49.656698) (xy 460.503571 -49.739888) (xy 460.479703 -49.821178) (xy 460.448215 -49.89983)
			(xy 460.409393 -49.975133) (xy 460.36359 -50.046405) (xy 460.311219 -50.113001) (xy 460.252754 -50.174316)
			(xy 460.188726 -50.229797) (xy 460.119714 -50.27894) (xy 460.046344 -50.3213) (xy 459.969279 -50.356495)
			(xy 459.889217 -50.384204) (xy 459.806884 -50.404178) (xy 459.723025 -50.416235) (xy 459.6384 -50.420267)
			(xy 459.553775 -50.416235) (xy 459.469916 -50.404178) (xy 459.387583 -50.384204) (xy 459.307521 -50.356495)
			(xy 459.230456 -50.3213) (xy 459.157086 -50.27894) (xy 459.088074 -50.229797) (xy 459.024046 -50.174316)
			(xy 458.965581 -50.113001) (xy 458.91321 -50.046405) (xy 458.867407 -49.975133) (xy 458.828585 -49.89983)
			(xy 458.797097 -49.821178) (xy 458.773229 -49.739888) (xy 458.757195 -49.656698) (xy 458.749142 -49.572361)
			(xy 445.165464 -49.572361) (xy 445.193328 -49.592203) (xy 445.257356 -49.647684) (xy 445.315821 -49.708999)
			(xy 445.368192 -49.775595) (xy 445.413995 -49.846867) (xy 445.452817 -49.92217) (xy 445.484305 -50.000822)
			(xy 445.508173 -50.082112) (xy 445.524207 -50.165302) (xy 445.53226 -50.249639) (xy 445.532764 -50.292)
			(xy 445.53219 -50.336316) (xy 445.52331 -50.424504) (xy 445.505698 -50.51137) (xy 445.49314 -50.553874)
			(xy 445.49314 -50.554128) (xy 445.490922 -50.562451) (xy 445.491587 -50.579654) (xy 445.497916 -50.595664)
			(xy 445.5033 -50.602388) (xy 445.560196 -50.667412) (xy 445.566137 -50.673668) (xy 445.581144 -50.682159)
			(xy 445.598113 -50.685211) (xy 445.606678 -50.684176) (xy 445.642241 -50.678719) (xy 445.713957 -50.67287)
			(xy 445.749934 -50.672492) (xy 445.75095 -50.672492) (xy 445.793301 -50.672978) (xy 445.877619 -50.681025)
			(xy 445.960791 -50.69705) (xy 446.042062 -50.72091) (xy 446.120698 -50.752387) (xy 446.195985 -50.791196)
			(xy 446.267242 -50.836987) (xy 446.333824 -50.889344) (xy 446.395127 -50.947793) (xy 446.450596 -51.011805)
			(xy 446.499729 -51.080799) (xy 446.542081 -51.154152) (xy 446.577269 -51.231199) (xy 446.604973 -51.311241)
			(xy 446.624943 -51.393555) (xy 446.636998 -51.477394) (xy 446.641028 -51.562) (xy 446.63901 -51.604361)
			(xy 448.544692 -51.604361) (xy 448.544692 -51.519639) (xy 448.552745 -51.435302) (xy 448.568779 -51.352112)
			(xy 448.592647 -51.270822) (xy 448.624135 -51.19217) (xy 448.662957 -51.116867) (xy 448.70876 -51.045595)
			(xy 448.761131 -50.978999) (xy 448.819596 -50.917684) (xy 448.883624 -50.862203) (xy 448.952636 -50.81306)
			(xy 449.026006 -50.7707) (xy 449.103071 -50.735505) (xy 449.183133 -50.707796) (xy 449.265466 -50.687822)
			(xy 449.349325 -50.675765) (xy 449.43395 -50.671734) (xy 449.518575 -50.675765) (xy 449.602434 -50.687822)
			(xy 449.684767 -50.707796) (xy 449.764829 -50.735505) (xy 449.841894 -50.7707) (xy 449.915264 -50.81306)
			(xy 449.984276 -50.862203) (xy 450.048304 -50.917684) (xy 450.106769 -50.978999) (xy 450.15914 -51.045595)
			(xy 450.204943 -51.116867) (xy 450.243765 -51.19217) (xy 450.275253 -51.270822) (xy 450.299121 -51.352112)
			(xy 450.315155 -51.435302) (xy 450.323208 -51.519639) (xy 450.323712 -51.562) (xy 450.323208 -51.604361)
			(xy 450.315155 -51.688698) (xy 450.299121 -51.771888) (xy 450.275253 -51.853178) (xy 450.243765 -51.93183)
			(xy 450.204943 -52.007133) (xy 450.15914 -52.078405) (xy 450.106769 -52.145001) (xy 450.048304 -52.206316)
			(xy 449.984276 -52.261797) (xy 449.915264 -52.31094) (xy 449.841894 -52.3533) (xy 449.764829 -52.388495)
			(xy 449.684767 -52.416204) (xy 449.602434 -52.436178) (xy 449.518575 -52.448235) (xy 449.43395 -52.452267)
			(xy 449.349325 -52.448235) (xy 449.265466 -52.436178) (xy 449.183133 -52.416204) (xy 449.103071 -52.388495)
			(xy 449.026006 -52.3533) (xy 448.952636 -52.31094) (xy 448.883624 -52.261797) (xy 448.819596 -52.206316)
			(xy 448.761131 -52.145001) (xy 448.70876 -52.078405) (xy 448.662957 -52.007133) (xy 448.624135 -51.93183)
			(xy 448.592647 -51.853178) (xy 448.568779 -51.771888) (xy 448.552745 -51.688698) (xy 448.544692 -51.604361)
			(xy 446.63901 -51.604361) (xy 446.636998 -51.646606) (xy 446.624943 -51.730445) (xy 446.604973 -51.812759)
			(xy 446.577269 -51.892801) (xy 446.542081 -51.969848) (xy 446.499729 -52.043201) (xy 446.450596 -52.112195)
			(xy 446.395127 -52.176207) (xy 446.333824 -52.234656) (xy 446.267242 -52.287013) (xy 446.195985 -52.332804)
			(xy 446.120698 -52.371613) (xy 446.042062 -52.40309) (xy 445.960791 -52.42695) (xy 445.877619 -52.442975)
			(xy 445.793301 -52.451022) (xy 445.75095 -52.451508) (xy 445.750442 -52.451508) (xy 445.706344 -52.450996)
			(xy 445.618583 -52.442226) (xy 445.532121 -52.424818) (xy 445.447804 -52.398943) (xy 445.366461 -52.364854)
			(xy 445.288889 -52.322886) (xy 445.215848 -52.27345) (xy 445.148057 -52.217031) (xy 445.086178 -52.154184)
			(xy 445.03082 -52.085523) (xy 445.006222 -52.048918) (xy 444.998094 -52.036472) (xy 444.971424 -52.02428)
			(xy 444.865506 -52.039266) (xy 444.856023 -52.041031) (xy 444.839313 -52.050643) (xy 444.827307 -52.065726)
			(xy 444.824104 -52.074826) (xy 444.810878 -52.116429) (xy 444.777408 -52.197062) (xy 444.736201 -52.274029)
			(xy 444.687651 -52.346589) (xy 444.632228 -52.414044) (xy 444.570463 -52.475745) (xy 444.502951 -52.531098)
			(xy 444.430342 -52.579573) (xy 444.353333 -52.620701) (xy 444.272665 -52.654087) (xy 444.189115 -52.679411)
			(xy 444.103486 -52.696429) (xy 444.016602 -52.704976) (xy 443.97295 -52.705508) (xy 443.931845 -52.70494)
			(xy 443.849986 -52.69736) (xy 443.769176 -52.682262) (xy 443.690102 -52.659773) (xy 443.613441 -52.630085)
			(xy 443.539845 -52.593451) (xy 443.469943 -52.550184) (xy 443.40433 -52.500654) (xy 443.343567 -52.445281)
			(xy 443.28817 -52.384539) (xy 443.238614 -52.318946) (xy 443.195319 -52.249061) (xy 443.158657 -52.175479)
			(xy 443.128939 -52.09883) (xy 443.106418 -52.019765) (xy 443.091288 -51.93896) (xy 443.083676 -51.857104)
			(xy 443.083188 -51.816) (xy 438.933893 -51.816) (xy 438.959279 -51.889348) (xy 438.979248 -51.97166)
			(xy 438.991302 -52.055497) (xy 438.995332 -52.1401) (xy 438.991302 -52.224703) (xy 438.979248 -52.30854)
			(xy 438.959279 -52.390852) (xy 438.931577 -52.470892) (xy 438.896391 -52.547937) (xy 438.854042 -52.621289)
			(xy 438.804911 -52.690283) (xy 438.749445 -52.754294) (xy 438.688145 -52.812743) (xy 438.621567 -52.8651)
			(xy 438.550314 -52.910892) (xy 438.47503 -52.949703) (xy 438.396398 -52.981182) (xy 438.31513 -53.005044)
			(xy 438.231961 -53.021073) (xy 438.147646 -53.029124) (xy 438.105296 -53.029612) (xy 438.06451 -53.02916)
			(xy 437.983277 -53.021733) (xy 437.903067 -53.006895) (xy 437.824553 -52.984771) (xy 437.748396 -52.955547)
			(xy 437.675236 -52.919469) (xy 437.640222 -52.898548) (xy 437.629691 -52.892827) (xy 437.605837 -52.890843)
			(xy 437.594502 -52.894738) (xy 437.554682 -52.910267) (xy 437.472726 -52.934536) (xy 437.38882 -52.950834)
			(xy 437.303737 -52.959011) (xy 437.261 -52.959508) (xy 437.219898 -52.959033) (xy 437.138043 -52.951448)
			(xy 437.057238 -52.936343) (xy 436.978171 -52.913847) (xy 436.901517 -52.884151) (xy 436.82793 -52.847509)
			(xy 436.758038 -52.804234) (xy 436.692437 -52.754694) (xy 436.631687 -52.699313) (xy 436.576306 -52.638563)
			(xy 436.526766 -52.572962) (xy 436.483491 -52.50307) (xy 436.446849 -52.429483) (xy 436.417153 -52.352829)
			(xy 436.394657 -52.273762) (xy 436.379552 -52.192957) (xy 436.371967 -52.111102) (xy 436.371492 -52.07)
			(xy 433.208271 -52.07) (xy 433.209192 -52.081684) (xy 433.212748 -52.110381) (xy 433.216558 -52.168085)
			(xy 433.216812 -52.197) (xy 433.216308 -52.239361) (xy 433.208255 -52.323698) (xy 433.192221 -52.406888)
			(xy 433.168353 -52.488178) (xy 433.136865 -52.56683) (xy 433.098043 -52.642133) (xy 433.05224 -52.713405)
			(xy 432.999869 -52.780001) (xy 432.941404 -52.841316) (xy 432.877376 -52.896797) (xy 432.808364 -52.94594)
			(xy 432.734994 -52.9883) (xy 432.657929 -53.023495) (xy 432.577867 -53.051204) (xy 432.495534 -53.071178)
			(xy 432.411675 -53.083235) (xy 432.32705 -53.087267) (xy 432.242425 -53.083235) (xy 432.158566 -53.071178)
			(xy 432.076233 -53.051204) (xy 431.996171 -53.023495) (xy 431.919106 -52.9883) (xy 431.845736 -52.94594)
			(xy 431.776724 -52.896797) (xy 431.712696 -52.841316) (xy 431.654231 -52.780001) (xy 431.60186 -52.713405)
			(xy 431.556057 -52.642133) (xy 431.517235 -52.56683) (xy 431.485747 -52.488178) (xy 431.461879 -52.406888)
			(xy 431.445845 -52.323698) (xy 431.437792 -52.239361) (xy 431.437288 -52.197) (xy 423.114118 -52.197)
			(xy 423.08907 -52.212509) (xy 423.015483 -52.249151) (xy 422.938829 -52.278847) (xy 422.859762 -52.301343)
			(xy 422.778957 -52.316448) (xy 422.697102 -52.324033) (xy 422.656 -52.324508) (xy 422.614905 -52.324034)
			(xy 422.533065 -52.316452) (xy 422.452274 -52.301352) (xy 422.373221 -52.278864) (xy 422.296579 -52.249178)
			(xy 422.223002 -52.212549) (xy 422.153118 -52.169289) (xy 422.087523 -52.119766) (xy 422.026777 -52.064403)
			(xy 421.971397 -52.003672) (xy 421.921855 -51.938091) (xy 421.878575 -51.86822) (xy 421.841924 -51.794654)
			(xy 421.812217 -51.71802) (xy 421.789706 -51.638973) (xy 421.774584 -51.558186) (xy 421.766978 -51.476349)
			(xy 421.766492 -51.435254) (xy 421.766492 -51.434746) (xy 421.767 -51.398678) (xy 421.728109 -51.386621)
			(xy 421.652528 -51.356316) (xy 421.580033 -51.319232) (xy 421.511229 -51.275679) (xy 421.446692 -51.226022)
			(xy 421.386963 -51.170676) (xy 421.33254 -51.110104) (xy 421.283879 -51.044813) (xy 421.241387 -50.975348)
			(xy 421.20542 -50.902292) (xy 421.176279 -50.826256) (xy 421.154207 -50.747874) (xy 421.139389 -50.667804)
			(xy 421.131948 -50.586715) (xy 421.131492 -50.546) (xy 421.131492 -50.545492) (xy 421.131975 -50.50455)
			(xy 421.139513 -50.423012) (xy 421.154517 -50.342514) (xy 421.176858 -50.263735) (xy 421.206347 -50.187345)
			(xy 421.242735 -50.113989) (xy 421.263826 -50.078894) (xy 421.269414 -50.06975) (xy 421.272462 -50.049176)
			(xy 421.247316 -49.956974) (xy 421.234108 -49.940718) (xy 421.22471 -49.935892) (xy 421.189175 -49.916589)
			(xy 421.121391 -49.87248) (xy 421.05789 -49.8224) (xy 420.999197 -49.766765) (xy 420.945794 -49.706031)
			(xy 420.898124 -49.640702) (xy 420.85658 -49.571317) (xy 420.83863 -49.53508) (xy 420.833187 -49.525019)
			(xy 420.815355 -49.51073) (xy 420.80434 -49.507648) (xy 420.797482 -49.506124) (xy 420.788876 -49.504361)
			(xy 420.771417 -49.50617) (xy 420.755617 -49.513817) (xy 420.749222 -49.51984) (xy 420.71791 -49.550821)
			(xy 420.650126 -49.607083) (xy 420.577115 -49.656371) (xy 420.499591 -49.698205) (xy 420.418313 -49.732174)
			(xy 420.334076 -49.757945) (xy 420.247705 -49.775268) (xy 420.160045 -49.783972) (xy 420.116 -49.784508)
			(xy 420.073652 -49.784004) (xy 419.989338 -49.775953) (xy 419.906172 -49.759924) (xy 419.824905 -49.736063)
			(xy 419.746275 -49.704584) (xy 419.670994 -49.665773) (xy 419.599742 -49.619983) (xy 419.533166 -49.567627)
			(xy 419.471868 -49.509179) (xy 419.416403 -49.445169) (xy 419.367274 -49.376177) (xy 419.324925 -49.302827)
			(xy 419.289741 -49.225784) (xy 419.262039 -49.145745) (xy 419.242071 -49.063436) (xy 419.230018 -48.979601)
			(xy 419.225988 -48.895) (xy 412.522592 -48.895) (xy 412.496 -48.896267) (xy 412.411375 -48.892235)
			(xy 412.327516 -48.880178) (xy 412.245183 -48.860204) (xy 412.165121 -48.832495) (xy 412.088056 -48.7973)
			(xy 412.014686 -48.75494) (xy 411.945674 -48.705797) (xy 411.881646 -48.650316) (xy 411.823181 -48.589001)
			(xy 411.77081 -48.522405) (xy 411.725007 -48.451133) (xy 411.686185 -48.37583) (xy 411.654697 -48.297178)
			(xy 411.630829 -48.215888) (xy 411.614795 -48.132698) (xy 411.606742 -48.048361) (xy 402.6154 -48.048361)
			(xy 402.6154 -53.890361) (xy 418.871142 -53.890361) (xy 418.871142 -53.805639) (xy 418.879195 -53.721302)
			(xy 418.895229 -53.638112) (xy 418.919097 -53.556822) (xy 418.950585 -53.47817) (xy 418.989407 -53.402867)
			(xy 419.03521 -53.331595) (xy 419.087581 -53.264999) (xy 419.146046 -53.203684) (xy 419.210074 -53.148203)
			(xy 419.279086 -53.09906) (xy 419.352456 -53.0567) (xy 419.429521 -53.021505) (xy 419.509583 -52.993796)
			(xy 419.591916 -52.973822) (xy 419.675775 -52.961765) (xy 419.7604 -52.957734) (xy 419.845025 -52.961765)
			(xy 419.928884 -52.973822) (xy 420.011217 -52.993796) (xy 420.091279 -53.021505) (xy 420.168344 -53.0567)
			(xy 420.241714 -53.09906) (xy 420.310726 -53.148203) (xy 420.374754 -53.203684) (xy 420.433219 -53.264999)
			(xy 420.48559 -53.331595) (xy 420.531393 -53.402867) (xy 420.570215 -53.47817) (xy 420.601703 -53.556822)
			(xy 420.625571 -53.638112) (xy 420.641605 -53.721302) (xy 420.649658 -53.805639) (xy 420.650162 -53.848)
			(xy 420.649658 -53.890361) (xy 420.641605 -53.974698) (xy 420.625571 -54.057888) (xy 420.601703 -54.139178)
			(xy 420.570215 -54.21783) (xy 420.531393 -54.293133) (xy 420.48559 -54.364405) (xy 420.433219 -54.431001)
			(xy 420.374754 -54.492316) (xy 420.310726 -54.547797) (xy 420.241714 -54.59694) (xy 420.168344 -54.6393)
			(xy 420.091279 -54.674495) (xy 420.011217 -54.702204) (xy 419.928884 -54.722178) (xy 419.845025 -54.734235)
			(xy 419.7604 -54.738267) (xy 419.675775 -54.734235) (xy 419.591916 -54.722178) (xy 419.509583 -54.702204)
			(xy 419.429521 -54.674495) (xy 419.352456 -54.6393) (xy 419.279086 -54.59694) (xy 419.210074 -54.547797)
			(xy 419.146046 -54.492316) (xy 419.087581 -54.431001) (xy 419.03521 -54.364405) (xy 418.989407 -54.293133)
			(xy 418.950585 -54.21783) (xy 418.919097 -54.139178) (xy 418.895229 -54.057888) (xy 418.879195 -53.974698)
			(xy 418.871142 -53.890361) (xy 402.6154 -53.890361) (xy 402.6154 -60.099956) (xy 419.2359 -60.099956)
			(xy 419.239883 -59.885707) (xy 419.251827 -59.671755) (xy 419.271716 -59.458394) (xy 419.299521 -59.24592)
			(xy 419.335205 -59.034627) (xy 419.378718 -58.824805) (xy 419.43 -58.616747) (xy 419.48898 -58.410738)
			(xy 419.555576 -58.207063) (xy 419.629697 -58.006005) (xy 419.711241 -57.807841) (xy 419.800093 -57.612845)
			(xy 419.896133 -57.421286) (xy 419.999226 -57.233429) (xy 420.109231 -57.049535) (xy 420.225995 -56.869856)
			(xy 420.349357 -56.694641) (xy 420.479146 -56.524133) (xy 420.615184 -56.358567) (xy 420.757281 -56.198172)
			(xy 420.905243 -56.043169) (xy 421.058863 -55.893774) (xy 421.217931 -55.750191) (xy 421.382225 -55.612621)
			(xy 421.55152 -55.481252) (xy 421.72558 -55.356267) (xy 421.904166 -55.237838) (xy 422.08703 -55.126129)
			(xy 422.273921 -55.021294) (xy 422.464578 -54.923479) (xy 422.65874 -54.832817) (xy 422.856138 -54.749436)
			(xy 423.056499 -54.673449) (xy 423.259545 -54.604962) (xy 423.464997 -54.54407) (xy 423.67257 -54.490856)
			(xy 423.881978 -54.445395) (xy 424.092931 -54.407749) (xy 424.305137 -54.37797) (xy 424.518304 -54.356099)
			(xy 424.732136 -54.342167) (xy 424.946338 -54.336193) (xy 425.160615 -54.338185) (xy 425.374669 -54.34814)
			(xy 425.588205 -54.366044) (xy 425.800928 -54.391873) (xy 426.012545 -54.425592) (xy 426.222761 -54.467153)
			(xy 426.431288 -54.516498) (xy 426.637836 -54.573561) (xy 426.84212 -54.638262) (xy 427.043859 -54.710511)
			(xy 427.242772 -54.790209) (xy 427.438586 -54.877246) (xy 427.631029 -54.9715) (xy 427.819836 -55.072843)
			(xy 428.004745 -55.181134) (xy 428.185501 -55.296223) (xy 428.361855 -55.417951) (xy 428.533562 -55.54615)
			(xy 428.700385 -55.680643) (xy 428.862094 -55.821243) (xy 429.018465 -55.967758) (xy 429.169282 -56.119983)
			(xy 429.314337 -56.277709) (xy 429.453429 -56.440718) (xy 429.586365 -56.608784) (xy 429.712963 -56.781675)
			(xy 429.833046 -56.959153) (xy 429.94645 -57.140971) (xy 430.053018 -57.326879) (xy 430.152601 -57.516619)
			(xy 430.245063 -57.70993) (xy 430.330276 -57.906544) (xy 430.408122 -58.10619) (xy 430.478493 -58.308591)
			(xy 430.541292 -58.513468) (xy 430.596432 -58.720538) (xy 430.643838 -58.929514) (xy 430.683443 -59.140108)
			(xy 430.715193 -59.352028) (xy 430.739044 -59.564982) (xy 430.754963 -59.778676) (xy 430.762928 -59.992813)
			(xy 430.763426 -60.099956) (xy 430.762928 -60.207099) (xy 430.754963 -60.421236) (xy 430.739044 -60.63493)
			(xy 430.715193 -60.847884) (xy 430.683443 -61.059804) (xy 430.678328 -61.087) (xy 441.222892 -61.087)
			(xy 441.222892 -61.086238) (xy 441.2233 -61.048018) (xy 441.229865 -60.971859) (xy 441.242949 -60.896547)
			(xy 441.262456 -60.822637) (xy 441.274962 -60.786518) (xy 441.277548 -60.778202) (xy 441.277548 -60.760798)
			(xy 441.274962 -60.752482) (xy 441.262442 -60.716268) (xy 441.24292 -60.642168) (xy 441.229835 -60.566664)
			(xy 441.223286 -60.490315) (xy 441.222892 -60.452) (xy 441.22326 -60.413684) (xy 441.229792 -60.33733)
			(xy 441.242877 -60.261823) (xy 441.262417 -60.187724) (xy 441.274962 -60.151518) (xy 441.277548 -60.143202)
			(xy 441.277548 -60.125798) (xy 441.274962 -60.117482) (xy 441.262442 -60.081268) (xy 441.24292 -60.007168)
			(xy 441.229835 -59.931664) (xy 441.223286 -59.855315) (xy 441.222892 -59.817) (xy 441.22326 -59.778684)
			(xy 441.229792 -59.70233) (xy 441.242877 -59.626823) (xy 441.262417 -59.552724) (xy 441.274962 -59.516518)
			(xy 441.277548 -59.508202) (xy 441.277548 -59.490798) (xy 441.274962 -59.482482) (xy 441.262471 -59.446359)
			(xy 441.242981 -59.372447) (xy 441.229897 -59.297136) (xy 441.223315 -59.220981) (xy 441.222892 -59.182762)
			(xy 441.222892 -59.182) (xy 441.223396 -59.139652) (xy 441.231447 -59.055338) (xy 441.247476 -58.972172)
			(xy 441.271337 -58.890905) (xy 441.302816 -58.812275) (xy 441.341627 -58.736994) (xy 441.387417 -58.665742)
			(xy 441.439773 -58.599166) (xy 441.498221 -58.537868) (xy 441.562231 -58.482403) (xy 441.631223 -58.433274)
			(xy 441.704573 -58.390925) (xy 441.781616 -58.355741) (xy 441.861655 -58.328039) (xy 441.943964 -58.308071)
			(xy 442.027799 -58.296018) (xy 442.1124 -58.291988) (xy 442.197001 -58.296018) (xy 442.280836 -58.308071)
			(xy 442.363145 -58.328039) (xy 442.443184 -58.355741) (xy 442.520227 -58.390925) (xy 442.593577 -58.433274)
			(xy 442.662569 -58.482403) (xy 442.726579 -58.537868) (xy 442.785027 -58.599166) (xy 442.837383 -58.665742)
			(xy 442.883173 -58.736994) (xy 442.921984 -58.812275) (xy 442.953463 -58.890905) (xy 442.977324 -58.972172)
			(xy 442.993353 -59.055338) (xy 443.001404 -59.139652) (xy 443.001908 -59.182) (xy 443.001908 -59.182762)
			(xy 443.0015 -59.220982) (xy 442.994935 -59.297141) (xy 442.981851 -59.372453) (xy 442.962344 -59.446363)
			(xy 442.949838 -59.482482) (xy 442.947252 -59.490798) (xy 442.947252 -59.508202) (xy 442.949838 -59.516518)
			(xy 442.962358 -59.552732) (xy 442.98188 -59.626832) (xy 442.994965 -59.702336) (xy 443.001514 -59.778685)
			(xy 443.001908 -59.817) (xy 443.00154 -59.855316) (xy 442.995008 -59.93167) (xy 442.981923 -60.007177)
			(xy 442.962383 -60.081276) (xy 442.949838 -60.117482) (xy 442.947252 -60.125798) (xy 442.947252 -60.143202)
			(xy 442.949838 -60.151518) (xy 442.962358 -60.187732) (xy 442.98188 -60.261832) (xy 442.994965 -60.337336)
			(xy 443.001514 -60.413685) (xy 443.001908 -60.452) (xy 443.00154 -60.490316) (xy 442.995008 -60.56667)
			(xy 442.981923 -60.642177) (xy 442.962383 -60.716276) (xy 442.949838 -60.752482) (xy 442.947252 -60.760798)
			(xy 442.947252 -60.778202) (xy 442.949838 -60.786518) (xy 442.962329 -60.822641) (xy 442.981819 -60.896553)
			(xy 442.994903 -60.971864) (xy 443.001485 -61.048019) (xy 443.001908 -61.086238) (xy 443.001908 -61.087)
			(xy 444.016892 -61.087) (xy 444.016892 -61.086238) (xy 444.0173 -61.048018) (xy 444.023865 -60.971859)
			(xy 444.036949 -60.896547) (xy 444.056456 -60.822637) (xy 444.068962 -60.786518) (xy 444.071548 -60.778202)
			(xy 444.071548 -60.760798) (xy 444.068962 -60.752482) (xy 444.056442 -60.716268) (xy 444.03692 -60.642168)
			(xy 444.023835 -60.566664) (xy 444.017286 -60.490315) (xy 444.016892 -60.452) (xy 444.01726 -60.413684)
			(xy 444.023792 -60.33733) (xy 444.036877 -60.261823) (xy 444.056417 -60.187724) (xy 444.068962 -60.151518)
			(xy 444.071548 -60.143202) (xy 444.071548 -60.125798) (xy 444.068962 -60.117482) (xy 444.056442 -60.081268)
			(xy 444.03692 -60.007168) (xy 444.023835 -59.931664) (xy 444.017286 -59.855315) (xy 444.016892 -59.817)
			(xy 444.01726 -59.778684) (xy 444.023792 -59.70233) (xy 444.036877 -59.626823) (xy 444.056417 -59.552724)
			(xy 444.068962 -59.516518) (xy 444.071548 -59.508202) (xy 444.071548 -59.490798) (xy 444.068962 -59.482482)
			(xy 444.056471 -59.446359) (xy 444.036981 -59.372447) (xy 444.023897 -59.297136) (xy 444.017315 -59.220981)
			(xy 444.016892 -59.182762) (xy 444.016892 -59.182) (xy 444.017396 -59.139652) (xy 444.025447 -59.055338)
			(xy 444.041476 -58.972172) (xy 444.065337 -58.890905) (xy 444.096816 -58.812275) (xy 444.135627 -58.736994)
			(xy 444.181417 -58.665742) (xy 444.233773 -58.599166) (xy 444.292221 -58.537868) (xy 444.356231 -58.482403)
			(xy 444.425223 -58.433274) (xy 444.498573 -58.390925) (xy 444.575616 -58.355741) (xy 444.655655 -58.328039)
			(xy 444.737964 -58.308071) (xy 444.821799 -58.296018) (xy 444.9064 -58.291988) (xy 444.991001 -58.296018)
			(xy 445.074836 -58.308071) (xy 445.157145 -58.328039) (xy 445.237184 -58.355741) (xy 445.314227 -58.390925)
			(xy 445.387577 -58.433274) (xy 445.456569 -58.482403) (xy 445.520579 -58.537868) (xy 445.579027 -58.599166)
			(xy 445.631383 -58.665742) (xy 445.677173 -58.736994) (xy 445.715984 -58.812275) (xy 445.747463 -58.890905)
			(xy 445.771324 -58.972172) (xy 445.787353 -59.055338) (xy 445.795404 -59.139652) (xy 445.795908 -59.182)
			(xy 445.795908 -59.182762) (xy 445.7955 -59.220982) (xy 445.788935 -59.297141) (xy 445.775851 -59.372453)
			(xy 445.756344 -59.446363) (xy 445.743838 -59.482482) (xy 445.741252 -59.490798) (xy 445.741252 -59.508202)
			(xy 445.743838 -59.516518) (xy 445.756358 -59.552732) (xy 445.77588 -59.626832) (xy 445.788965 -59.702336)
			(xy 445.795514 -59.778685) (xy 445.795908 -59.817) (xy 445.79554 -59.855316) (xy 445.789008 -59.93167)
			(xy 445.775923 -60.007177) (xy 445.756383 -60.081276) (xy 445.743838 -60.117482) (xy 445.741252 -60.125798)
			(xy 445.741252 -60.143202) (xy 445.743838 -60.151518) (xy 445.756358 -60.187732) (xy 445.77588 -60.261832)
			(xy 445.788965 -60.337336) (xy 445.795514 -60.413685) (xy 445.795908 -60.452) (xy 445.79554 -60.490316)
			(xy 445.789008 -60.56667) (xy 445.775923 -60.642177) (xy 445.756383 -60.716276) (xy 445.743838 -60.752482)
			(xy 445.741252 -60.760798) (xy 445.741252 -60.778202) (xy 445.743838 -60.786518) (xy 445.756329 -60.822641)
			(xy 445.775819 -60.896553) (xy 445.788903 -60.971864) (xy 445.795485 -61.048019) (xy 445.795908 -61.086238)
			(xy 445.795908 -61.087) (xy 445.795404 -61.129348) (xy 445.787353 -61.213662) (xy 445.771324 -61.296828)
			(xy 445.747463 -61.378095) (xy 445.715984 -61.456725) (xy 445.677173 -61.532006) (xy 445.631383 -61.603258)
			(xy 445.579027 -61.669834) (xy 445.520579 -61.731132) (xy 445.456569 -61.786597) (xy 445.387577 -61.835726)
			(xy 445.314227 -61.878075) (xy 445.237184 -61.913259) (xy 445.157145 -61.940961) (xy 445.074836 -61.960929)
			(xy 444.991001 -61.972982) (xy 444.9064 -61.977013) (xy 444.821799 -61.972982) (xy 444.737964 -61.960929)
			(xy 444.655655 -61.940961) (xy 444.575616 -61.913259) (xy 444.498573 -61.878075) (xy 444.425223 -61.835726)
			(xy 444.356231 -61.786597) (xy 444.292221 -61.731132) (xy 444.233773 -61.669834) (xy 444.181417 -61.603258)
			(xy 444.135627 -61.532006) (xy 444.096816 -61.456725) (xy 444.065337 -61.378095) (xy 444.041476 -61.296828)
			(xy 444.025447 -61.213662) (xy 444.017396 -61.129348) (xy 444.016892 -61.087) (xy 443.001908 -61.087)
			(xy 443.001404 -61.129348) (xy 442.993353 -61.213662) (xy 442.977324 -61.296828) (xy 442.953463 -61.378095)
			(xy 442.921984 -61.456725) (xy 442.883173 -61.532006) (xy 442.837383 -61.603258) (xy 442.785027 -61.669834)
			(xy 442.726579 -61.731132) (xy 442.662569 -61.786597) (xy 442.593577 -61.835726) (xy 442.520227 -61.878075)
			(xy 442.443184 -61.913259) (xy 442.363145 -61.940961) (xy 442.280836 -61.960929) (xy 442.197001 -61.972982)
			(xy 442.1124 -61.977013) (xy 442.027799 -61.972982) (xy 441.943964 -61.960929) (xy 441.861655 -61.940961)
			(xy 441.781616 -61.913259) (xy 441.704573 -61.878075) (xy 441.631223 -61.835726) (xy 441.562231 -61.786597)
			(xy 441.498221 -61.731132) (xy 441.439773 -61.669834) (xy 441.387417 -61.603258) (xy 441.341627 -61.532006)
			(xy 441.302816 -61.456725) (xy 441.271337 -61.378095) (xy 441.247476 -61.296828) (xy 441.231447 -61.213662)
			(xy 441.223396 -61.129348) (xy 441.222892 -61.087) (xy 430.678328 -61.087) (xy 430.643838 -61.270398)
			(xy 430.596432 -61.479374) (xy 430.541292 -61.686444) (xy 430.478493 -61.891321) (xy 430.408122 -62.093722)
			(xy 430.330276 -62.293368) (xy 430.245063 -62.489982) (xy 430.152601 -62.683293) (xy 430.053018 -62.873033)
			(xy 429.94645 -63.058941) (xy 429.833046 -63.240759) (xy 429.712963 -63.418237) (xy 429.586365 -63.591128)
			(xy 429.453429 -63.759194) (xy 429.314337 -63.922203) (xy 429.169282 -64.079929) (xy 429.018465 -64.232154)
			(xy 428.862094 -64.378669) (xy 428.700385 -64.519269) (xy 428.533562 -64.653762) (xy 428.361855 -64.781961)
			(xy 428.185501 -64.903689) (xy 428.004745 -65.018778) (xy 427.819836 -65.127069) (xy 427.631029 -65.228412)
			(xy 427.438586 -65.322666) (xy 427.242772 -65.409703) (xy 427.043859 -65.489401) (xy 426.924911 -65.532)
			(xy 441.222892 -65.532) (xy 441.222892 -65.531238) (xy 441.2233 -65.493018) (xy 441.229865 -65.416859)
			(xy 441.242949 -65.341547) (xy 441.262456 -65.267637) (xy 441.274962 -65.231518) (xy 441.277548 -65.223202)
			(xy 441.277548 -65.205798) (xy 441.274962 -65.197482) (xy 441.262442 -65.161268) (xy 441.24292 -65.087168)
			(xy 441.229835 -65.011664) (xy 441.223286 -64.935315) (xy 441.222892 -64.897) (xy 441.22326 -64.858684)
			(xy 441.229792 -64.78233) (xy 441.242877 -64.706823) (xy 441.262417 -64.632724) (xy 441.274962 -64.596518)
			(xy 441.277548 -64.588202) (xy 441.277548 -64.570798) (xy 441.274962 -64.562482) (xy 441.262442 -64.526268)
			(xy 441.24292 -64.452168) (xy 441.229835 -64.376664) (xy 441.223286 -64.300315) (xy 441.222892 -64.262)
			(xy 441.22326 -64.223684) (xy 441.229792 -64.14733) (xy 441.242877 -64.071823) (xy 441.262417 -63.997724)
			(xy 441.274962 -63.961518) (xy 441.277548 -63.953202) (xy 441.277548 -63.935798) (xy 441.274962 -63.927482)
			(xy 441.262442 -63.891268) (xy 441.24292 -63.817168) (xy 441.229835 -63.741664) (xy 441.223286 -63.665315)
			(xy 441.222892 -63.627) (xy 441.22326 -63.588684) (xy 441.229792 -63.51233) (xy 441.242877 -63.436823)
			(xy 441.262417 -63.362724) (xy 441.274962 -63.326518) (xy 441.277548 -63.318202) (xy 441.277548 -63.300798)
			(xy 441.274962 -63.292482) (xy 441.262471 -63.256359) (xy 441.242981 -63.182447) (xy 441.229897 -63.107136)
			(xy 441.223315 -63.030981) (xy 441.222892 -62.992762) (xy 441.222892 -62.992) (xy 441.223396 -62.949652)
			(xy 441.231447 -62.865338) (xy 441.247476 -62.782172) (xy 441.271337 -62.700905) (xy 441.302816 -62.622275)
			(xy 441.341627 -62.546994) (xy 441.387417 -62.475742) (xy 441.439773 -62.409166) (xy 441.498221 -62.347868)
			(xy 441.562231 -62.292403) (xy 441.631223 -62.243274) (xy 441.704573 -62.200925) (xy 441.781616 -62.165741)
			(xy 441.861655 -62.138039) (xy 441.943964 -62.118071) (xy 442.027799 -62.106018) (xy 442.1124 -62.101988)
			(xy 442.197001 -62.106018) (xy 442.280836 -62.118071) (xy 442.363145 -62.138039) (xy 442.443184 -62.165741)
			(xy 442.520227 -62.200925) (xy 442.593577 -62.243274) (xy 442.662569 -62.292403) (xy 442.726579 -62.347868)
			(xy 442.785027 -62.409166) (xy 442.837383 -62.475742) (xy 442.883173 -62.546994) (xy 442.921984 -62.622275)
			(xy 442.953463 -62.700905) (xy 442.977324 -62.782172) (xy 442.993353 -62.865338) (xy 443.001404 -62.949652)
			(xy 443.001908 -62.992) (xy 443.001908 -62.992762) (xy 443.0015 -63.030982) (xy 442.994935 -63.107141)
			(xy 442.981851 -63.182453) (xy 442.962344 -63.256363) (xy 442.949838 -63.292482) (xy 442.947252 -63.300798)
			(xy 442.947252 -63.318202) (xy 442.949838 -63.326518) (xy 442.962358 -63.362732) (xy 442.98188 -63.436832)
			(xy 442.994965 -63.512336) (xy 443.001514 -63.588685) (xy 443.001908 -63.627) (xy 443.00154 -63.665316)
			(xy 442.995008 -63.74167) (xy 442.981923 -63.817177) (xy 442.962383 -63.891276) (xy 442.949838 -63.927482)
			(xy 442.947252 -63.935798) (xy 442.947252 -63.953202) (xy 442.949838 -63.961518) (xy 442.962358 -63.997732)
			(xy 442.98188 -64.071832) (xy 442.994965 -64.147336) (xy 443.001514 -64.223685) (xy 443.001908 -64.262)
			(xy 443.00154 -64.300316) (xy 442.995008 -64.37667) (xy 442.981923 -64.452177) (xy 442.962383 -64.526276)
			(xy 442.949838 -64.562482) (xy 442.947252 -64.570798) (xy 442.947252 -64.588202) (xy 442.949838 -64.596518)
			(xy 442.962358 -64.632732) (xy 442.98188 -64.706832) (xy 442.994965 -64.782336) (xy 443.001514 -64.858685)
			(xy 443.001908 -64.897) (xy 443.00154 -64.935316) (xy 442.995008 -65.01167) (xy 442.981923 -65.087177)
			(xy 442.962383 -65.161276) (xy 442.949838 -65.197482) (xy 442.947252 -65.205798) (xy 442.947252 -65.223202)
			(xy 442.949838 -65.231518) (xy 442.962329 -65.267641) (xy 442.981819 -65.341553) (xy 442.994903 -65.416864)
			(xy 443.001485 -65.493019) (xy 443.001908 -65.531238) (xy 443.001908 -65.532) (xy 444.016892 -65.532)
			(xy 444.016892 -65.531238) (xy 444.0173 -65.493018) (xy 444.023865 -65.416859) (xy 444.036949 -65.341547)
			(xy 444.056456 -65.267637) (xy 444.068962 -65.231518) (xy 444.071548 -65.223202) (xy 444.071548 -65.205798)
			(xy 444.068962 -65.197482) (xy 444.056442 -65.161268) (xy 444.03692 -65.087168) (xy 444.023835 -65.011664)
			(xy 444.017286 -64.935315) (xy 444.016892 -64.897) (xy 444.01726 -64.858684) (xy 444.023792 -64.78233)
			(xy 444.036877 -64.706823) (xy 444.056417 -64.632724) (xy 444.068962 -64.596518) (xy 444.071548 -64.588202)
			(xy 444.071548 -64.570798) (xy 444.068962 -64.562482) (xy 444.056442 -64.526268) (xy 444.03692 -64.452168)
			(xy 444.023835 -64.376664) (xy 444.017286 -64.300315) (xy 444.016892 -64.262) (xy 444.01726 -64.223684)
			(xy 444.023792 -64.14733) (xy 444.036877 -64.071823) (xy 444.056417 -63.997724) (xy 444.068962 -63.961518)
			(xy 444.071548 -63.953202) (xy 444.071548 -63.935798) (xy 444.068962 -63.927482) (xy 444.056442 -63.891268)
			(xy 444.03692 -63.817168) (xy 444.023835 -63.741664) (xy 444.017286 -63.665315) (xy 444.016892 -63.627)
			(xy 444.01726 -63.588684) (xy 444.023792 -63.51233) (xy 444.036877 -63.436823) (xy 444.056417 -63.362724)
			(xy 444.068962 -63.326518) (xy 444.071548 -63.318202) (xy 444.071548 -63.300798) (xy 444.068962 -63.292482)
			(xy 444.056471 -63.256359) (xy 444.036981 -63.182447) (xy 444.023897 -63.107136) (xy 444.017315 -63.030981)
			(xy 444.016892 -62.992762) (xy 444.016892 -62.992) (xy 444.017396 -62.949652) (xy 444.025447 -62.865338)
			(xy 444.041476 -62.782172) (xy 444.065337 -62.700905) (xy 444.096816 -62.622275) (xy 444.135627 -62.546994)
			(xy 444.181417 -62.475742) (xy 444.233773 -62.409166) (xy 444.292221 -62.347868) (xy 444.356231 -62.292403)
			(xy 444.425223 -62.243274) (xy 444.498573 -62.200925) (xy 444.575616 -62.165741) (xy 444.655655 -62.138039)
			(xy 444.737964 -62.118071) (xy 444.821799 -62.106018) (xy 444.9064 -62.101988) (xy 444.991001 -62.106018)
			(xy 445.074836 -62.118071) (xy 445.157145 -62.138039) (xy 445.237184 -62.165741) (xy 445.314227 -62.200925)
			(xy 445.387577 -62.243274) (xy 445.456569 -62.292403) (xy 445.520579 -62.347868) (xy 445.579027 -62.409166)
			(xy 445.631383 -62.475742) (xy 445.677173 -62.546994) (xy 445.715984 -62.622275) (xy 445.747463 -62.700905)
			(xy 445.771324 -62.782172) (xy 445.787353 -62.865338) (xy 445.795404 -62.949652) (xy 445.795908 -62.992)
			(xy 445.795908 -62.992762) (xy 445.7955 -63.030982) (xy 445.788935 -63.107141) (xy 445.775851 -63.182453)
			(xy 445.756344 -63.256363) (xy 445.743838 -63.292482) (xy 445.741252 -63.300798) (xy 445.741252 -63.318202)
			(xy 445.743838 -63.326518) (xy 445.756358 -63.362732) (xy 445.77588 -63.436832) (xy 445.788965 -63.512336)
			(xy 445.794465 -63.576454) (xy 447.78422 -63.576454) (xy 447.78422 -63.575946) (xy 447.784843 -63.529615)
			(xy 447.794509 -63.437457) (xy 447.813699 -63.346803) (xy 447.842207 -63.258634) (xy 447.86042 -63.216028)
			(xy 447.864251 -63.206094) (xy 447.864234 -63.184823) (xy 447.86042 -63.17488) (xy 447.842217 -63.132269)
			(xy 447.813694 -63.044105) (xy 447.794496 -62.953452) (xy 447.784831 -62.861294) (xy 447.78422 -62.814962)
			(xy 447.78422 -62.814454) (xy 447.78468 -62.7727) (xy 447.792516 -62.689559) (xy 447.808106 -62.607519)
			(xy 447.831313 -62.527299) (xy 447.861931 -62.449606) (xy 447.899693 -62.375123) (xy 447.944266 -62.304504)
			(xy 447.969386 -62.271148) (xy 447.975731 -62.262005) (xy 447.980648 -62.240328) (xy 447.975925 -62.218609)
			(xy 447.96964 -62.209426) (xy 447.944951 -62.176255) (xy 447.90117 -62.106099) (xy 447.86409 -62.032182)
			(xy 447.834031 -61.955142) (xy 447.811252 -61.875645) (xy 447.79595 -61.794377) (xy 447.788256 -61.71204)
			(xy 447.787776 -61.670692) (xy 447.7884 -61.62429) (xy 447.798091 -61.531992) (xy 447.817345 -61.441207)
			(xy 447.845954 -61.352922) (xy 447.86423 -61.310266) (xy 447.868044 -61.300326) (xy 447.868041 -61.27906)
			(xy 447.86423 -61.269118) (xy 447.845965 -61.226458) (xy 447.817373 -61.13817) (xy 447.798116 -61.047387)
			(xy 447.788405 -60.955093) (xy 447.787776 -60.908692) (xy 447.78828 -60.866331) (xy 447.796333 -60.781994)
			(xy 447.812367 -60.698804) (xy 447.836235 -60.617514) (xy 447.867723 -60.538862) (xy 447.906545 -60.463559)
			(xy 447.952348 -60.392287) (xy 448.004719 -60.325691) (xy 448.063184 -60.264376) (xy 448.127212 -60.208895)
			(xy 448.196224 -60.159752) (xy 448.269594 -60.117392) (xy 448.346659 -60.082197) (xy 448.426721 -60.054488)
			(xy 448.509054 -60.034514) (xy 448.592913 -60.022457) (xy 448.677538 -60.018426) (xy 448.762163 -60.022457)
			(xy 448.846022 -60.034514) (xy 448.928355 -60.054488) (xy 449.008417 -60.082197) (xy 449.085482 -60.117392)
			(xy 449.158852 -60.159752) (xy 449.227864 -60.208895) (xy 449.291892 -60.264376) (xy 449.350357 -60.325691)
			(xy 449.402728 -60.392287) (xy 449.448531 -60.463559) (xy 449.487353 -60.538862) (xy 449.518841 -60.617514)
			(xy 449.542709 -60.698804) (xy 449.558743 -60.781994) (xy 449.566796 -60.866331) (xy 449.5673 -60.908692)
			(xy 449.566672 -60.955094) (xy 449.556983 -61.047391) (xy 449.53773 -61.138177) (xy 449.509122 -61.226462)
			(xy 449.490846 -61.269118) (xy 449.487043 -61.279061) (xy 449.48704 -61.300324) (xy 449.490846 -61.310266)
			(xy 449.509104 -61.352928) (xy 449.537699 -61.441216) (xy 449.556957 -61.531998) (xy 449.566671 -61.624291)
			(xy 449.5673 -61.670692) (xy 449.566799 -61.712452) (xy 449.558944 -61.795603) (xy 449.543329 -61.877651)
			(xy 449.520092 -61.957875) (xy 449.489438 -62.035567) (xy 449.451637 -62.110044) (xy 449.407022 -62.180651)
			(xy 449.38188 -62.213998) (xy 449.375496 -62.223118) (xy 449.370596 -62.244808) (xy 449.375334 -62.266535)
			(xy 449.381626 -62.27572) (xy 449.406266 -62.308918) (xy 449.449995 -62.379087) (xy 449.48703 -62.453009)
			(xy 449.517051 -62.530046) (xy 449.539799 -62.609535) (xy 449.55508 -62.690791) (xy 449.562759 -62.773114)
			(xy 449.563236 -62.814454) (xy 449.562635 -62.860849) (xy 449.552995 -62.953137) (xy 449.533804 -63.043921)
			(xy 449.505271 -63.132215) (xy 449.487036 -63.17488) (xy 449.483256 -63.18483) (xy 449.483239 -63.206087)
			(xy 449.487036 -63.216028) (xy 449.505245 -63.258636) (xy 449.533765 -63.346802) (xy 449.552962 -63.437456)
			(xy 449.562626 -63.529614) (xy 449.563236 -63.575946) (xy 449.563236 -63.576454) (xy 449.563067 -63.590678)
			(xy 450.07022 -63.590678) (xy 450.07022 -63.59017) (xy 450.070816 -63.543838) (xy 450.08049 -63.45168)
			(xy 450.099688 -63.361025) (xy 450.128203 -63.272857) (xy 450.14642 -63.230252) (xy 450.150237 -63.220313)
			(xy 450.150229 -63.199047) (xy 450.14642 -63.189104) (xy 450.12817 -63.146444) (xy 450.099627 -63.058151)
			(xy 450.080435 -62.967365) (xy 450.070804 -62.875074) (xy 450.07022 -62.828678) (xy 450.07071 -62.786326)
			(xy 450.078732 -62.702002) (xy 450.09474 -62.618824) (xy 450.118588 -62.537546) (xy 450.15006 -62.458905)
			(xy 450.18887 -62.383615) (xy 450.234667 -62.312359) (xy 450.260466 -62.278768) (xy 450.266974 -62.269555)
			(xy 450.271965 -62.24758) (xy 450.267127 -62.225571) (xy 450.26072 -62.216284) (xy 450.23535 -62.182857)
			(xy 450.190358 -62.112014) (xy 450.152236 -62.037249) (xy 450.121324 -61.959226) (xy 450.097897 -61.878639)
			(xy 450.082163 -61.796204) (xy 450.074261 -61.712654) (xy 450.073776 -61.670692) (xy 450.0744 -61.62429)
			(xy 450.084091 -61.531992) (xy 450.103345 -61.441207) (xy 450.131954 -61.352922) (xy 450.15023 -61.310266)
			(xy 450.154044 -61.300326) (xy 450.154041 -61.27906) (xy 450.15023 -61.269118) (xy 450.131965 -61.226458)
			(xy 450.103373 -61.13817) (xy 450.084116 -61.047387) (xy 450.074405 -60.955093) (xy 450.073776 -60.908692)
			(xy 450.07428 -60.866331) (xy 450.082333 -60.781994) (xy 450.098367 -60.698804) (xy 450.122235 -60.617514)
			(xy 450.153723 -60.538862) (xy 450.192545 -60.463559) (xy 450.238348 -60.392287) (xy 450.290719 -60.325691)
			(xy 450.349184 -60.264376) (xy 450.413212 -60.208895) (xy 450.482224 -60.159752) (xy 450.555594 -60.117392)
			(xy 450.632659 -60.082197) (xy 450.712721 -60.054488) (xy 450.795054 -60.034514) (xy 450.878913 -60.022457)
			(xy 450.963538 -60.018426) (xy 451.048163 -60.022457) (xy 451.132022 -60.034514) (xy 451.214355 -60.054488)
			(xy 451.294417 -60.082197) (xy 451.371482 -60.117392) (xy 451.444852 -60.159752) (xy 451.513864 -60.208895)
			(xy 451.577892 -60.264376) (xy 451.636357 -60.325691) (xy 451.688728 -60.392287) (xy 451.734531 -60.463559)
			(xy 451.773353 -60.538862) (xy 451.804841 -60.617514) (xy 451.828709 -60.698804) (xy 451.844743 -60.781994)
			(xy 451.852796 -60.866331) (xy 451.8533 -60.908692) (xy 451.852672 -60.955094) (xy 451.842983 -61.047391)
			(xy 451.82373 -61.138177) (xy 451.795122 -61.226462) (xy 451.776846 -61.269118) (xy 451.773043 -61.279061)
			(xy 451.77304 -61.300324) (xy 451.776846 -61.310266) (xy 451.795104 -61.352928) (xy 451.823699 -61.441216)
			(xy 451.842957 -61.531998) (xy 451.852671 -61.624291) (xy 451.8533 -61.670692) (xy 451.85276 -61.713048)
			(xy 451.844682 -61.797373) (xy 451.828627 -61.880549) (xy 451.80474 -61.961823) (xy 451.773237 -62.040459)
			(xy 451.734404 -62.115746) (xy 451.688592 -62.187001) (xy 451.6628 -62.220602) (xy 451.656312 -62.22983)
			(xy 451.651306 -62.251796) (xy 451.656139 -62.273802) (xy 451.662546 -62.283086) (xy 451.687884 -62.316528)
			(xy 451.73283 -62.387384) (xy 451.770908 -62.462155) (xy 451.801781 -62.540178) (xy 451.825174 -62.62076)
			(xy 451.84088 -62.703186) (xy 451.84876 -62.786724) (xy 451.849236 -62.828678) (xy 451.848643 -62.875073)
			(xy 451.839001 -62.967361) (xy 451.819807 -63.058145) (xy 451.791272 -63.146439) (xy 451.773036 -63.189104)
			(xy 451.769242 -63.19905) (xy 451.769234 -63.22031) (xy 451.773036 -63.230252) (xy 451.791253 -63.272857)
			(xy 451.819771 -63.361024) (xy 451.838965 -63.451679) (xy 451.848627 -63.543838) (xy 451.849236 -63.59017)
			(xy 451.849236 -63.590678) (xy 452.22922 -63.590678) (xy 452.229828 -63.544283) (xy 452.239465 -63.451995)
			(xy 452.258654 -63.361212) (xy 452.287185 -63.272917) (xy 452.30542 -63.230252) (xy 452.309237 -63.220313)
			(xy 452.309229 -63.199047) (xy 452.30542 -63.189104) (xy 452.28717 -63.146444) (xy 452.258627 -63.058151)
			(xy 452.239435 -62.967365) (xy 452.229804 -62.875074) (xy 452.22922 -62.828678) (xy 452.22971 -62.786326)
			(xy 452.237732 -62.702002) (xy 452.25374 -62.618824) (xy 452.277588 -62.537546) (xy 452.30906 -62.458905)
			(xy 452.34787 -62.383615) (xy 452.393667 -62.312359) (xy 452.419466 -62.278768) (xy 452.425974 -62.269555)
			(xy 452.430965 -62.24758) (xy 452.426127 -62.225571) (xy 452.41972 -62.216284) (xy 452.39435 -62.182857)
			(xy 452.349358 -62.112014) (xy 452.311236 -62.037249) (xy 452.280324 -61.959226) (xy 452.256897 -61.878639)
			(xy 452.241163 -61.796204) (xy 452.233261 -61.712654) (xy 452.232776 -61.670692) (xy 452.2334 -61.62429)
			(xy 452.243091 -61.531992) (xy 452.262345 -61.441207) (xy 452.290954 -61.352922) (xy 452.30923 -61.310266)
			(xy 452.313044 -61.300326) (xy 452.313041 -61.27906) (xy 452.30923 -61.269118) (xy 452.290965 -61.226458)
			(xy 452.262373 -61.13817) (xy 452.243116 -61.047387) (xy 452.233405 -60.955093) (xy 452.232776 -60.908692)
			(xy 452.23328 -60.866331) (xy 452.241333 -60.781994) (xy 452.257367 -60.698804) (xy 452.281235 -60.617514)
			(xy 452.312723 -60.538862) (xy 452.351545 -60.463559) (xy 452.397348 -60.392287) (xy 452.449719 -60.325691)
			(xy 452.508184 -60.264376) (xy 452.572212 -60.208895) (xy 452.641224 -60.159752) (xy 452.714594 -60.117392)
			(xy 452.791659 -60.082197) (xy 452.871721 -60.054488) (xy 452.954054 -60.034514) (xy 453.037913 -60.022457)
			(xy 453.122538 -60.018426) (xy 453.207163 -60.022457) (xy 453.291022 -60.034514) (xy 453.373355 -60.054488)
			(xy 453.453417 -60.082197) (xy 453.530482 -60.117392) (xy 453.603852 -60.159752) (xy 453.672864 -60.208895)
			(xy 453.736892 -60.264376) (xy 453.795357 -60.325691) (xy 453.847728 -60.392287) (xy 453.893531 -60.463559)
			(xy 453.932353 -60.538862) (xy 453.963841 -60.617514) (xy 453.987709 -60.698804) (xy 454.003743 -60.781994)
			(xy 454.011796 -60.866331) (xy 454.0123 -60.908692) (xy 454.010776 -60.958222) (xy 454.010695 -60.967088)
			(xy 454.015852 -60.98404) (xy 454.02645 -60.998239) (xy 454.033636 -61.003434) (xy 454.118726 -61.059314)
			(xy 454.145396 -61.060838) (xy 454.157842 -61.054488) (xy 454.195079 -61.036277) (xy 454.272274 -61.006058)
			(xy 454.351944 -60.983149) (xy 454.4334 -60.967749) (xy 454.515935 -60.959992) (xy 454.557384 -60.959492)
			(xy 454.5584 -60.959492) (xy 454.599502 -60.959967) (xy 454.681357 -60.967552) (xy 454.762162 -60.982657)
			(xy 454.841229 -61.005153) (xy 454.917883 -61.034849) (xy 454.99147 -61.071491) (xy 455.061362 -61.114766)
			(xy 455.126963 -61.164306) (xy 455.187713 -61.219687) (xy 455.243094 -61.280437) (xy 455.292634 -61.346038)
			(xy 455.335909 -61.41593) (xy 455.372551 -61.489517) (xy 455.402247 -61.566171) (xy 455.424743 -61.645238)
			(xy 455.439848 -61.726043) (xy 455.447433 -61.807898) (xy 455.447908 -61.849) (xy 455.447908 -61.849508)
			(xy 455.447389 -61.893272) (xy 455.438814 -61.980378) (xy 455.421718 -62.066219) (xy 455.396267 -62.149965)
			(xy 455.362707 -62.230803) (xy 455.342498 -62.269624) (xy 455.337171 -62.280977) (xy 455.337171 -62.306023)
			(xy 455.342498 -62.317376) (xy 455.362692 -62.356204) (xy 455.396232 -62.437047) (xy 455.421677 -62.520792)
			(xy 455.438782 -62.606629) (xy 455.447381 -62.69373) (xy 455.447908 -62.737492) (xy 455.447908 -62.738)
			(xy 455.447433 -62.779102) (xy 455.439848 -62.860957) (xy 455.424743 -62.941762) (xy 455.402247 -63.020829)
			(xy 455.372551 -63.097483) (xy 455.335909 -63.17107) (xy 455.292634 -63.240962) (xy 455.243094 -63.306563)
			(xy 455.187713 -63.367313) (xy 455.126963 -63.422694) (xy 455.061362 -63.472234) (xy 454.99147 -63.515509)
			(xy 454.917883 -63.552151) (xy 454.841229 -63.581847) (xy 454.762162 -63.604343) (xy 454.681357 -63.619448)
			(xy 454.599502 -63.627033) (xy 454.5584 -63.627508) (xy 454.557638 -63.627508) (xy 454.515903 -63.627003)
			(xy 454.432803 -63.619162) (xy 454.350805 -63.603562) (xy 454.27063 -63.580343) (xy 454.192986 -63.549708)
			(xy 454.155556 -63.531242) (xy 454.143872 -63.525146) (xy 454.117964 -63.526162) (xy 454.021444 -63.583058)
			(xy 454.008236 -63.60541) (xy 454.007982 -63.618618) (xy 454.006156 -63.661393) (xy 453.995269 -63.746321)
			(xy 453.976273 -63.82981) (xy 453.949343 -63.911087) (xy 453.914728 -63.989401) (xy 453.87275 -64.064028)
			(xy 453.823796 -64.134275) (xy 453.768319 -64.199495) (xy 453.706833 -64.259083) (xy 453.639906 -64.312488)
			(xy 453.568158 -64.359215) (xy 453.492253 -64.398833) (xy 453.412892 -64.430975) (xy 453.33081 -64.455344)
			(xy 453.246767 -64.471714) (xy 453.161539 -64.479933) (xy 453.118728 -64.48044) (xy 453.077619 -64.479921)
			(xy 452.995751 -64.472336) (xy 452.914932 -64.457228) (xy 452.835853 -64.434727) (xy 452.759188 -64.405023)
			(xy 452.685591 -64.368372) (xy 452.61569 -64.325084) (xy 452.550082 -64.275531) (xy 452.489328 -64.220135)
			(xy 452.433945 -64.159368) (xy 452.384406 -64.09375) (xy 452.341134 -64.02384) (xy 452.304498 -63.950235)
			(xy 452.274812 -63.873563) (xy 452.252327 -63.794479) (xy 452.237237 -63.713657) (xy 452.22967 -63.631787)
			(xy 452.22922 -63.590678) (xy 451.849236 -63.590678) (xy 451.848732 -63.633026) (xy 451.840681 -63.71734)
			(xy 451.824652 -63.800506) (xy 451.800791 -63.881773) (xy 451.769312 -63.960403) (xy 451.730501 -64.035684)
			(xy 451.684711 -64.106936) (xy 451.632355 -64.173512) (xy 451.573907 -64.23481) (xy 451.509897 -64.290275)
			(xy 451.440905 -64.339404) (xy 451.367555 -64.381753) (xy 451.290512 -64.416937) (xy 451.210473 -64.444639)
			(xy 451.128164 -64.464607) (xy 451.044329 -64.47666) (xy 450.959728 -64.480691) (xy 450.875127 -64.47666)
			(xy 450.791292 -64.464607) (xy 450.708983 -64.444639) (xy 450.628944 -64.416937) (xy 450.551901 -64.381753)
			(xy 450.478551 -64.339404) (xy 450.409559 -64.290275) (xy 450.345549 -64.23481) (xy 450.287101 -64.173512)
			(xy 450.234745 -64.106936) (xy 450.188955 -64.035684) (xy 450.150144 -63.960403) (xy 450.118665 -63.881773)
			(xy 450.094804 -63.800506) (xy 450.078775 -63.71734) (xy 450.070724 -63.633026) (xy 450.07022 -63.590678)
			(xy 449.563067 -63.590678) (xy 449.562732 -63.618802) (xy 449.554681 -63.703116) (xy 449.538652 -63.786282)
			(xy 449.514791 -63.867549) (xy 449.483312 -63.946179) (xy 449.444501 -64.02146) (xy 449.398711 -64.092712)
			(xy 449.346355 -64.159288) (xy 449.287907 -64.220586) (xy 449.223897 -64.276051) (xy 449.154905 -64.32518)
			(xy 449.081555 -64.367529) (xy 449.004512 -64.402713) (xy 448.924473 -64.430415) (xy 448.842164 -64.450383)
			(xy 448.758329 -64.462436) (xy 448.673728 -64.466467) (xy 448.589127 -64.462436) (xy 448.505292 -64.450383)
			(xy 448.422983 -64.430415) (xy 448.342944 -64.402713) (xy 448.265901 -64.367529) (xy 448.192551 -64.32518)
			(xy 448.123559 -64.276051) (xy 448.059549 -64.220586) (xy 448.001101 -64.159288) (xy 447.948745 -64.092712)
			(xy 447.902955 -64.02146) (xy 447.864144 -63.946179) (xy 447.832665 -63.867549) (xy 447.808804 -63.786282)
			(xy 447.792775 -63.703116) (xy 447.784724 -63.618802) (xy 447.78422 -63.576454) (xy 445.794465 -63.576454)
			(xy 445.795514 -63.588685) (xy 445.795908 -63.627) (xy 445.79554 -63.665316) (xy 445.789008 -63.74167)
			(xy 445.775923 -63.817177) (xy 445.756383 -63.891276) (xy 445.743838 -63.927482) (xy 445.741252 -63.935798)
			(xy 445.741252 -63.953202) (xy 445.743838 -63.961518) (xy 445.756358 -63.997732) (xy 445.77588 -64.071832)
			(xy 445.788965 -64.147336) (xy 445.795514 -64.223685) (xy 445.795908 -64.262) (xy 445.79554 -64.300316)
			(xy 445.789008 -64.37667) (xy 445.775923 -64.452177) (xy 445.756383 -64.526276) (xy 445.743838 -64.562482)
			(xy 445.741252 -64.570798) (xy 445.741252 -64.588202) (xy 445.743838 -64.596518) (xy 445.756358 -64.632732)
			(xy 445.77588 -64.706832) (xy 445.788965 -64.782336) (xy 445.795514 -64.858685) (xy 445.795908 -64.897)
			(xy 445.79554 -64.935316) (xy 445.789008 -65.01167) (xy 445.775923 -65.087177) (xy 445.756383 -65.161276)
			(xy 445.743838 -65.197482) (xy 445.741252 -65.205798) (xy 445.741252 -65.223202) (xy 445.743838 -65.231518)
			(xy 445.756329 -65.267641) (xy 445.775819 -65.341553) (xy 445.788903 -65.416864) (xy 445.795485 -65.493019)
			(xy 445.795908 -65.531238) (xy 445.795908 -65.532) (xy 445.795404 -65.574348) (xy 445.787353 -65.658662)
			(xy 445.771324 -65.741828) (xy 445.747463 -65.823095) (xy 445.715984 -65.901725) (xy 445.677173 -65.977006)
			(xy 445.631383 -66.048258) (xy 445.579027 -66.114834) (xy 445.520579 -66.176132) (xy 445.456569 -66.231597)
			(xy 445.387577 -66.280726) (xy 445.314227 -66.323075) (xy 445.237184 -66.358259) (xy 445.157145 -66.385961)
			(xy 445.074836 -66.405929) (xy 444.991001 -66.417982) (xy 444.9064 -66.422013) (xy 444.821799 -66.417982)
			(xy 444.737964 -66.405929) (xy 444.655655 -66.385961) (xy 444.575616 -66.358259) (xy 444.498573 -66.323075)
			(xy 444.425223 -66.280726) (xy 444.356231 -66.231597) (xy 444.292221 -66.176132) (xy 444.233773 -66.114834)
			(xy 444.181417 -66.048258) (xy 444.135627 -65.977006) (xy 444.096816 -65.901725) (xy 444.065337 -65.823095)
			(xy 444.041476 -65.741828) (xy 444.025447 -65.658662) (xy 444.017396 -65.574348) (xy 444.016892 -65.532)
			(xy 443.001908 -65.532) (xy 443.001404 -65.574348) (xy 442.993353 -65.658662) (xy 442.977324 -65.741828)
			(xy 442.953463 -65.823095) (xy 442.921984 -65.901725) (xy 442.883173 -65.977006) (xy 442.837383 -66.048258)
			(xy 442.785027 -66.114834) (xy 442.726579 -66.176132) (xy 442.662569 -66.231597) (xy 442.593577 -66.280726)
			(xy 442.520227 -66.323075) (xy 442.443184 -66.358259) (xy 442.363145 -66.385961) (xy 442.280836 -66.405929)
			(xy 442.197001 -66.417982) (xy 442.1124 -66.422013) (xy 442.027799 -66.417982) (xy 441.943964 -66.405929)
			(xy 441.861655 -66.385961) (xy 441.781616 -66.358259) (xy 441.704573 -66.323075) (xy 441.631223 -66.280726)
			(xy 441.562231 -66.231597) (xy 441.498221 -66.176132) (xy 441.439773 -66.114834) (xy 441.387417 -66.048258)
			(xy 441.341627 -65.977006) (xy 441.302816 -65.901725) (xy 441.271337 -65.823095) (xy 441.247476 -65.741828)
			(xy 441.231447 -65.658662) (xy 441.223396 -65.574348) (xy 441.222892 -65.532) (xy 426.924911 -65.532)
			(xy 426.84212 -65.56165) (xy 426.637836 -65.626351) (xy 426.431288 -65.683414) (xy 426.222761 -65.732759)
			(xy 426.012545 -65.77432) (xy 425.800928 -65.808039) (xy 425.588205 -65.833868) (xy 425.374669 -65.851772)
			(xy 425.160615 -65.861727) (xy 424.946338 -65.863719) (xy 424.732136 -65.857745) (xy 424.518304 -65.843813)
			(xy 424.305137 -65.821942) (xy 424.092931 -65.792163) (xy 423.881978 -65.754517) (xy 423.67257 -65.709056)
			(xy 423.464997 -65.655842) (xy 423.259545 -65.59495) (xy 423.056499 -65.526463) (xy 422.856138 -65.450476)
			(xy 422.65874 -65.367095) (xy 422.464578 -65.276433) (xy 422.273921 -65.178618) (xy 422.08703 -65.073783)
			(xy 421.904166 -64.962074) (xy 421.72558 -64.843645) (xy 421.55152 -64.71866) (xy 421.382225 -64.587291)
			(xy 421.217931 -64.449721) (xy 421.058863 -64.306138) (xy 420.905243 -64.156743) (xy 420.757281 -64.00174)
			(xy 420.615184 -63.841345) (xy 420.479146 -63.675779) (xy 420.349357 -63.505271) (xy 420.225995 -63.330056)
			(xy 420.109231 -63.150377) (xy 419.999226 -62.966483) (xy 419.896133 -62.778626) (xy 419.800093 -62.587067)
			(xy 419.711241 -62.392071) (xy 419.629697 -62.193907) (xy 419.555576 -61.992849) (xy 419.48898 -61.789174)
			(xy 419.43 -61.583165) (xy 419.378718 -61.375107) (xy 419.335205 -61.165285) (xy 419.299521 -60.953992)
			(xy 419.271716 -60.741518) (xy 419.251827 -60.528157) (xy 419.239883 -60.314205) (xy 419.2359 -60.099956)
			(xy 402.6154 -60.099956) (xy 402.6154 -73.809606) (xy 402.615858 -73.819484) (xy 402.623298 -73.837786)
			(xy 402.629878 -73.845166) (xy 402.630132 -73.84542) (xy 405.858726 -77.074014) (xy 405.859234 -77.074522)
			(xy 405.866613 -77.081111) (xy 405.884912 -77.088573) (xy 405.894794 -77.089) (xy 419.543484 -77.089)
		)
		(stroke
			(width 0)
			(type solid)
		)
		(fill yes)
		(layer "In4.Cu")
		(net "P52V_FAN")
	)
	(gr_arc
		(start 4.99999 0)
		(mid 1.464463 -1.464463)
		(end 0 -4.99999)
		(stroke
			(width 2.032)
			(type default)
		)
		(layer "In4.Cu")
	)
	(gr_line
		(start 4.99999 0)
		(end 434.999892 0)
		(stroke
			(width 2.032)
			(type default)
		)
		(layer "In4.Cu")
	)
	(gr_line
		(start 21.70557 -158.315406)
		(end 23.212552 -156.808424)
		(stroke
			(width 1.016)
			(type default)
		)
		(layer "In4.Cu")
	)
	(gr_line
		(start 23.212552 -156.808424)
		(end 24.736552 -158.332424)
		(stroke
			(width 1.016)
			(type default)
		)
		(layer "In4.Cu")
	)
	(gr_line
		(start 23.212552 -44.961048)
		(end 23.212552 -158.299912)
		(stroke
			(width 1.016)
			(type default)
		)
		(layer "In4.Cu")
	)
	(gr_line
		(start 25.999948 -158.299912)
		(end 4.99999 -158.299912)
		(stroke
			(width 2.032)
			(type default)
		)
		(layer "In4.Cu")
	)
	(gr_line
		(start 30.999938 -166.649908)
		(end 30.999938 -163.299902)
		(stroke
			(width 2.032)
			(type default)
		)
		(layer "In4.Cu")
	)
	(gr_arc
		(start 30.999938 -166.649908)
		(mid 32.4644 -170.185437)
		(end 35.999928 -171.649898)
		(stroke
			(width 2.032)
			(type default)
		)
		(layer "In4.Cu")
	)
	(gr_arc
		(start 30.999938 -163.299902)
		(mid 29.535475 -159.764375)
		(end 25.999948 -158.299912)
		(stroke
			(width 2.032)
			(type default)
		)
		(layer "In4.Cu")
	)
	(gr_circle
		(center 34.1884 -38.1)
		(end 35.0774 -38.1)
		(stroke
			(width 0.2)
			(type default)
		)
		(fill no)
		(layer "In4.Cu")
	)
	(gr_line
		(start 34.6456 -33.528)
		(end 23.212552 -44.961048)
		(stroke
			(width 1.016)
			(type default)
		)
		(layer "In4.Cu")
	)
	(gr_circle
		(center 39.625016 -168.82999)
		(end 40.83812 -168.82999)
		(stroke
			(width 0.2)
			(type default)
		)
		(fill no)
		(layer "In4.Cu")
	)
	(gr_circle
		(center 39.625016 -166.829994)
		(end 40.83812 -166.829994)
		(stroke
			(width 0.2)
			(type default)
		)
		(fill no)
		(layer "In4.Cu")
	)
	(gr_circle
		(center 39.625016 -164.829998)
		(end 40.83812 -164.829998)
		(stroke
			(width 0.2)
			(type default)
		)
		(fill no)
		(layer "In4.Cu")
	)
	(gr_circle
		(center 39.625016 -162.830002)
		(end 40.83812 -162.830002)
		(stroke
			(width 0.2)
			(type default)
		)
		(fill no)
		(layer "In4.Cu")
	)
	(gr_circle
		(center 39.625016 -160.830006)
		(end 40.83812 -160.830006)
		(stroke
			(width 0.2)
			(type default)
		)
		(fill no)
		(layer "In4.Cu")
	)
	(gr_circle
		(center 39.625016 -158.83001)
		(end 40.83812 -158.83001)
		(stroke
			(width 0.2)
			(type default)
		)
		(fill no)
		(layer "In4.Cu")
	)
	(gr_circle
		(center 39.625016 -156.830014)
		(end 40.83812 -156.830014)
		(stroke
			(width 0.2)
			(type default)
		)
		(fill no)
		(layer "In4.Cu")
	)
	(gr_circle
		(center 39.625016 -154.830018)
		(end 40.83812 -154.830018)
		(stroke
			(width 0.2)
			(type default)
		)
		(fill no)
		(layer "In4.Cu")
	)
	(gr_circle
		(center 39.625016 -152.830022)
		(end 40.83812 -152.830022)
		(stroke
			(width 0.2)
			(type default)
		)
		(fill no)
		(layer "In4.Cu")
	)
	(gr_circle
		(center 40.609012 -167.972994)
		(end 41.822116 -167.972994)
		(stroke
			(width 0.2)
			(type default)
		)
		(fill no)
		(layer "In4.Cu")
	)
	(gr_circle
		(center 40.609012 -165.972998)
		(end 41.822116 -165.972998)
		(stroke
			(width 0.2)
			(type default)
		)
		(fill no)
		(layer "In4.Cu")
	)
	(gr_circle
		(center 40.609012 -163.973002)
		(end 41.822116 -163.973002)
		(stroke
			(width 0.2)
			(type default)
		)
		(fill no)
		(layer "In4.Cu")
	)
	(gr_circle
		(center 40.609012 -161.973006)
		(end 41.822116 -161.973006)
		(stroke
			(width 0.2)
			(type default)
		)
		(fill no)
		(layer "In4.Cu")
	)
	(gr_circle
		(center 40.609012 -159.97301)
		(end 41.822116 -159.97301)
		(stroke
			(width 0.2)
			(type default)
		)
		(fill no)
		(layer "In4.Cu")
	)
	(gr_circle
		(center 40.609012 -157.973014)
		(end 41.822116 -157.973014)
		(stroke
			(width 0.2)
			(type default)
		)
		(fill no)
		(layer "In4.Cu")
	)
	(gr_circle
		(center 40.609012 -155.973018)
		(end 41.822116 -155.973018)
		(stroke
			(width 0.2)
			(type default)
		)
		(fill no)
		(layer "In4.Cu")
	)
	(gr_circle
		(center 40.609012 -153.973022)
		(end 41.822116 -153.973022)
		(stroke
			(width 0.2)
			(type default)
		)
		(fill no)
		(layer "In4.Cu")
	)
	(gr_circle
		(center 41.625012 -168.82999)
		(end 42.838116 -168.82999)
		(stroke
			(width 0.2)
			(type default)
		)
		(fill no)
		(layer "In4.Cu")
	)
	(gr_circle
		(center 41.625012 -166.829994)
		(end 42.838116 -166.829994)
		(stroke
			(width 0.2)
			(type default)
		)
		(fill no)
		(layer "In4.Cu")
	)
	(gr_circle
		(center 41.625012 -164.829998)
		(end 42.838116 -164.829998)
		(stroke
			(width 0.2)
			(type default)
		)
		(fill no)
		(layer "In4.Cu")
	)
	(gr_circle
		(center 41.625012 -162.830002)
		(end 42.838116 -162.830002)
		(stroke
			(width 0.2)
			(type default)
		)
		(fill no)
		(layer "In4.Cu")
	)
	(gr_circle
		(center 41.625012 -160.830006)
		(end 42.838116 -160.830006)
		(stroke
			(width 0.2)
			(type default)
		)
		(fill no)
		(layer "In4.Cu")
	)
	(gr_circle
		(center 41.625012 -158.83001)
		(end 42.838116 -158.83001)
		(stroke
			(width 0.2)
			(type default)
		)
		(fill no)
		(layer "In4.Cu")
	)
	(gr_circle
		(center 41.625012 -156.830014)
		(end 42.838116 -156.830014)
		(stroke
			(width 0.2)
			(type default)
		)
		(fill no)
		(layer "In4.Cu")
	)
	(gr_circle
		(center 41.625012 -154.830018)
		(end 42.838116 -154.830018)
		(stroke
			(width 0.2)
			(type default)
		)
		(fill no)
		(layer "In4.Cu")
	)
	(gr_circle
		(center 41.625012 -152.830022)
		(end 42.838116 -152.830022)
		(stroke
			(width 0.2)
			(type default)
		)
		(fill no)
		(layer "In4.Cu")
	)
	(gr_circle
		(center 42.36339 -132.199888)
		(end 43.88739 -132.199888)
		(stroke
			(width 0.2)
			(type default)
		)
		(fill no)
		(layer "In4.Cu")
	)
	(gr_circle
		(center 42.36339 -111.879888)
		(end 43.88739 -111.879888)
		(stroke
			(width 0.2)
			(type default)
		)
		(fill no)
		(layer "In4.Cu")
	)
	(gr_circle
		(center 42.36339 -91.559888)
		(end 43.88739 -91.559888)
		(stroke
			(width 0.2)
			(type default)
		)
		(fill no)
		(layer "In4.Cu")
	)
	(gr_circle
		(center 42.36339 -71.239888)
		(end 43.88739 -71.239888)
		(stroke
			(width 0.2)
			(type default)
		)
		(fill no)
		(layer "In4.Cu")
	)
	(gr_circle
		(center 42.36339 -50.919888)
		(end 43.88739 -50.919888)
		(stroke
			(width 0.2)
			(type default)
		)
		(fill no)
		(layer "In4.Cu")
	)
	(gr_circle
		(center 48.800004 -168.82999)
		(end 50.013108 -168.82999)
		(stroke
			(width 0.2)
			(type default)
		)
		(fill no)
		(layer "In4.Cu")
	)
	(gr_circle
		(center 48.800004 -166.829994)
		(end 50.013108 -166.829994)
		(stroke
			(width 0.2)
			(type default)
		)
		(fill no)
		(layer "In4.Cu")
	)
	(gr_circle
		(center 48.800004 -164.829998)
		(end 50.013108 -164.829998)
		(stroke
			(width 0.2)
			(type default)
		)
		(fill no)
		(layer "In4.Cu")
	)
	(gr_circle
		(center 49.911 -167.591994)
		(end 51.124104 -167.591994)
		(stroke
			(width 0.2)
			(type default)
		)
		(fill no)
		(layer "In4.Cu")
	)
	(gr_circle
		(center 49.911 -165.591998)
		(end 51.124104 -165.591998)
		(stroke
			(width 0.2)
			(type default)
		)
		(fill no)
		(layer "In4.Cu")
	)
	(gr_circle
		(center 50.8 -168.82999)
		(end 52.013104 -168.82999)
		(stroke
			(width 0.2)
			(type default)
		)
		(fill no)
		(layer "In4.Cu")
	)
	(gr_circle
		(center 50.8 -166.829994)
		(end 52.013104 -166.829994)
		(stroke
			(width 0.2)
			(type default)
		)
		(fill no)
		(layer "In4.Cu")
	)
	(gr_circle
		(center 50.8 -164.829998)
		(end 52.013104 -164.829998)
		(stroke
			(width 0.2)
			(type default)
		)
		(fill no)
		(layer "In4.Cu")
	)
	(gr_circle
		(center 54.799992 -168.82999)
		(end 56.013096 -168.82999)
		(stroke
			(width 0.2)
			(type default)
		)
		(fill no)
		(layer "In4.Cu")
	)
	(gr_circle
		(center 54.799992 -166.829994)
		(end 56.013096 -166.829994)
		(stroke
			(width 0.2)
			(type default)
		)
		(fill no)
		(layer "In4.Cu")
	)
	(gr_circle
		(center 54.799992 -164.829998)
		(end 56.013096 -164.829998)
		(stroke
			(width 0.2)
			(type default)
		)
		(fill no)
		(layer "In4.Cu")
	)
	(gr_circle
		(center 55.88 -167.591994)
		(end 57.093104 -167.591994)
		(stroke
			(width 0.2)
			(type default)
		)
		(fill no)
		(layer "In4.Cu")
	)
	(gr_circle
		(center 55.88 -165.591998)
		(end 57.093104 -165.591998)
		(stroke
			(width 0.2)
			(type default)
		)
		(fill no)
		(layer "In4.Cu")
	)
	(gr_circle
		(center 56.799988 -168.82999)
		(end 58.013092 -168.82999)
		(stroke
			(width 0.2)
			(type default)
		)
		(fill no)
		(layer "In4.Cu")
	)
	(gr_circle
		(center 56.799988 -166.829994)
		(end 58.013092 -166.829994)
		(stroke
			(width 0.2)
			(type default)
		)
		(fill no)
		(layer "In4.Cu")
	)
	(gr_circle
		(center 56.799988 -164.829998)
		(end 58.013092 -164.829998)
		(stroke
			(width 0.2)
			(type default)
		)
		(fill no)
		(layer "In4.Cu")
	)
	(gr_line
		(start 57.893204 -33.528)
		(end 58.562494 -32.85871)
		(stroke
			(width 1.016)
			(type default)
		)
		(layer "In4.Cu")
	)
	(gr_line
		(start 58.562494 -32.85871)
		(end 58.562494 -0.292862)
		(stroke
			(width 1.524)
			(type default)
		)
		(layer "In4.Cu")
	)
	(gr_line
		(start 58.562494 -32.85871)
		(end 59.231784 -33.528)
		(stroke
			(width 1.016)
			(type default)
		)
		(layer "In4.Cu")
	)
	(gr_line
		(start 58.562494 -1.78435)
		(end 57.038494 -0.26035)
		(stroke
			(width 1.016)
			(type default)
		)
		(layer "In4.Cu")
	)
	(gr_line
		(start 60.069476 -0.277368)
		(end 58.562494 -1.78435)
		(stroke
			(width 1.016)
			(type default)
		)
		(layer "In4.Cu")
	)
	(gr_circle
		(center 61.92139 -132.199888)
		(end 63.44539 -132.199888)
		(stroke
			(width 0.2)
			(type default)
		)
		(fill no)
		(layer "In4.Cu")
	)
	(gr_circle
		(center 61.92139 -111.879888)
		(end 63.44539 -111.879888)
		(stroke
			(width 0.2)
			(type default)
		)
		(fill no)
		(layer "In4.Cu")
	)
	(gr_circle
		(center 61.92139 -91.559888)
		(end 63.44539 -91.559888)
		(stroke
			(width 0.2)
			(type default)
		)
		(fill no)
		(layer "In4.Cu")
	)
	(gr_circle
		(center 61.92139 -71.239888)
		(end 63.44539 -71.239888)
		(stroke
			(width 0.2)
			(type default)
		)
		(fill no)
		(layer "In4.Cu")
	)
	(gr_circle
		(center 61.92139 -50.919888)
		(end 63.44539 -50.919888)
		(stroke
			(width 0.2)
			(type default)
		)
		(fill no)
		(layer "In4.Cu")
	)
	(gr_circle
		(center 63.000128 -168.82999)
		(end 64.213232 -168.82999)
		(stroke
			(width 0.2)
			(type default)
		)
		(fill no)
		(layer "In4.Cu")
	)
	(gr_circle
		(center 63.000128 -166.829994)
		(end 64.213232 -166.829994)
		(stroke
			(width 0.2)
			(type default)
		)
		(fill no)
		(layer "In4.Cu")
	)
	(gr_circle
		(center 63.000128 -164.829998)
		(end 64.213232 -164.829998)
		(stroke
			(width 0.2)
			(type default)
		)
		(fill no)
		(layer "In4.Cu")
	)
	(gr_circle
		(center 63.719964 -5.290058)
		(end 64.933068 -5.290058)
		(stroke
			(width 0.2)
			(type default)
		)
		(fill no)
		(layer "In4.Cu")
	)
	(gr_circle
		(center 64.008 -167.718994)
		(end 65.221104 -167.718994)
		(stroke
			(width 0.2)
			(type default)
		)
		(fill no)
		(layer "In4.Cu")
	)
	(gr_circle
		(center 64.008 -165.718998)
		(end 65.221104 -165.718998)
		(stroke
			(width 0.2)
			(type default)
		)
		(fill no)
		(layer "In4.Cu")
	)
	(gr_circle
		(center 65.000124 -168.82999)
		(end 66.213228 -168.82999)
		(stroke
			(width 0.2)
			(type default)
		)
		(fill no)
		(layer "In4.Cu")
	)
	(gr_circle
		(center 65.000124 -166.829994)
		(end 66.213228 -166.829994)
		(stroke
			(width 0.2)
			(type default)
		)
		(fill no)
		(layer "In4.Cu")
	)
	(gr_circle
		(center 65.000124 -164.829998)
		(end 66.213228 -164.829998)
		(stroke
			(width 0.2)
			(type default)
		)
		(fill no)
		(layer "In4.Cu")
	)
	(gr_circle
		(center 65.729104 -169.97299)
		(end 66.942208 -169.97299)
		(stroke
			(width 0.2)
			(type default)
		)
		(fill no)
		(layer "In4.Cu")
	)
	(gr_circle
		(center 66.259964 -5.290058)
		(end 67.473068 -5.290058)
		(stroke
			(width 0.2)
			(type default)
		)
		(fill no)
		(layer "In4.Cu")
	)
	(gr_circle
		(center 66.999104 -169.97299)
		(end 68.212208 -169.97299)
		(stroke
			(width 0.2)
			(type default)
		)
		(fill no)
		(layer "In4.Cu")
	)
	(gr_circle
		(center 68.396104 -170.09999)
		(end 69.609208 -170.09999)
		(stroke
			(width 0.2)
			(type default)
		)
		(fill no)
		(layer "In4.Cu")
	)
	(gr_circle
		(center 69.000116 -168.82999)
		(end 70.21322 -168.82999)
		(stroke
			(width 0.2)
			(type default)
		)
		(fill no)
		(layer "In4.Cu")
	)
	(gr_circle
		(center 69.000116 -166.829994)
		(end 70.21322 -166.829994)
		(stroke
			(width 0.2)
			(type default)
		)
		(fill no)
		(layer "In4.Cu")
	)
	(gr_circle
		(center 69.000116 -164.829998)
		(end 70.21322 -164.829998)
		(stroke
			(width 0.2)
			(type default)
		)
		(fill no)
		(layer "In4.Cu")
	)
	(gr_circle
		(center 69.760084 -4.575048)
		(end 70.973188 -4.575048)
		(stroke
			(width 0.2)
			(type default)
		)
		(fill no)
		(layer "In4.Cu")
	)
	(gr_circle
		(center 69.760084 -2.035048)
		(end 70.973188 -2.035048)
		(stroke
			(width 0.2)
			(type default)
		)
		(fill no)
		(layer "In4.Cu")
	)
	(gr_circle
		(center 69.85 -167.718994)
		(end 71.063104 -167.718994)
		(stroke
			(width 0.2)
			(type default)
		)
		(fill no)
		(layer "In4.Cu")
	)
	(gr_circle
		(center 69.85 -165.718998)
		(end 71.063104 -165.718998)
		(stroke
			(width 0.2)
			(type default)
		)
		(fill no)
		(layer "In4.Cu")
	)
	(gr_circle
		(center 70.809104 -1.57099)
		(end 72.022208 -1.57099)
		(stroke
			(width 0.2)
			(type default)
		)
		(fill no)
		(layer "In4.Cu")
	)
	(gr_circle
		(center 71.000112 -168.82999)
		(end 72.213216 -168.82999)
		(stroke
			(width 0.2)
			(type default)
		)
		(fill no)
		(layer "In4.Cu")
	)
	(gr_circle
		(center 71.000112 -166.829994)
		(end 72.213216 -166.829994)
		(stroke
			(width 0.2)
			(type default)
		)
		(fill no)
		(layer "In4.Cu")
	)
	(gr_circle
		(center 71.000112 -164.829998)
		(end 72.213216 -164.829998)
		(stroke
			(width 0.2)
			(type default)
		)
		(fill no)
		(layer "In4.Cu")
	)
	(gr_circle
		(center 71.030084 -5.845048)
		(end 72.243188 -5.845048)
		(stroke
			(width 0.2)
			(type default)
		)
		(fill no)
		(layer "In4.Cu")
	)
	(gr_circle
		(center 71.030084 -3.305048)
		(end 72.243188 -3.305048)
		(stroke
			(width 0.2)
			(type default)
		)
		(fill no)
		(layer "In4.Cu")
	)
	(gr_circle
		(center 71.157084 -4.575048)
		(end 72.370188 -4.575048)
		(stroke
			(width 0.2)
			(type default)
		)
		(fill no)
		(layer "In4.Cu")
	)
	(gr_circle
		(center 72.173084 -3.559048)
		(end 73.386188 -3.559048)
		(stroke
			(width 0.2)
			(type default)
		)
		(fill no)
		(layer "In4.Cu")
	)
	(gr_circle
		(center 72.300084 -4.575048)
		(end 73.513188 -4.575048)
		(stroke
			(width 0.2)
			(type default)
		)
		(fill no)
		(layer "In4.Cu")
	)
	(gr_circle
		(center 72.300084 -2.035048)
		(end 73.513188 -2.035048)
		(stroke
			(width 0.2)
			(type default)
		)
		(fill no)
		(layer "In4.Cu")
	)
	(gr_line
		(start 73.5076 -33.528)
		(end 34.6456 -33.528)
		(stroke
			(width 1.016)
			(type default)
		)
		(layer "In4.Cu")
	)
	(gr_circle
		(center 73.570084 -5.845048)
		(end 74.783188 -5.845048)
		(stroke
			(width 0.2)
			(type default)
		)
		(fill no)
		(layer "In4.Cu")
	)
	(gr_circle
		(center 73.570084 -3.305048)
		(end 74.783188 -3.305048)
		(stroke
			(width 0.2)
			(type default)
		)
		(fill no)
		(layer "In4.Cu")
	)
	(gr_circle
		(center 73.603104 -1.44399)
		(end 74.816208 -1.44399)
		(stroke
			(width 0.2)
			(type default)
		)
		(fill no)
		(layer "In4.Cu")
	)
	(gr_line
		(start 75.000104 -171.649898)
		(end 35.999928 -171.649898)
		(stroke
			(width 2.032)
			(type default)
		)
		(layer "In4.Cu")
	)
	(gr_arc
		(start 75.000104 -171.649898)
		(mid 78.535631 -170.185434)
		(end 80.000094 -166.649908)
		(stroke
			(width 2.032)
			(type default)
		)
		(layer "In4.Cu")
	)
	(gr_circle
		(center 75.000104 -168.82999)
		(end 76.213208 -168.82999)
		(stroke
			(width 0.2)
			(type default)
		)
		(fill no)
		(layer "In4.Cu")
	)
	(gr_circle
		(center 75.000104 -166.829994)
		(end 76.213208 -166.829994)
		(stroke
			(width 0.2)
			(type default)
		)
		(fill no)
		(layer "In4.Cu")
	)
	(gr_circle
		(center 75.000104 -164.829998)
		(end 76.213208 -164.829998)
		(stroke
			(width 0.2)
			(type default)
		)
		(fill no)
		(layer "In4.Cu")
	)
	(gr_circle
		(center 75.819 -167.845994)
		(end 77.032104 -167.845994)
		(stroke
			(width 0.2)
			(type default)
		)
		(fill no)
		(layer "In4.Cu")
	)
	(gr_circle
		(center 75.819 -165.845998)
		(end 77.032104 -165.845998)
		(stroke
			(width 0.2)
			(type default)
		)
		(fill no)
		(layer "In4.Cu")
	)
	(gr_circle
		(center 76.016104 -169.71899)
		(end 77.229208 -169.71899)
		(stroke
			(width 0.2)
			(type default)
		)
		(fill no)
		(layer "In4.Cu")
	)
	(gr_circle
		(center 77.0001 -168.82999)
		(end 78.213204 -168.82999)
		(stroke
			(width 0.2)
			(type default)
		)
		(fill no)
		(layer "In4.Cu")
	)
	(gr_circle
		(center 77.0001 -166.829994)
		(end 78.213204 -166.829994)
		(stroke
			(width 0.2)
			(type default)
		)
		(fill no)
		(layer "In4.Cu")
	)
	(gr_circle
		(center 77.0001 -164.829998)
		(end 78.213204 -164.829998)
		(stroke
			(width 0.2)
			(type default)
		)
		(fill no)
		(layer "In4.Cu")
	)
	(gr_circle
		(center 79.950564 -9.959594)
		(end 80.839564 -9.959594)
		(stroke
			(width 0.2)
			(type default)
		)
		(fill no)
		(layer "In4.Cu")
	)
	(gr_line
		(start 80.000094 -161.299906)
		(end 80.000094 -166.649908)
		(stroke
			(width 2.032)
			(type default)
		)
		(layer "In4.Cu")
	)
	(gr_circle
		(center 80.518 -18.91665)
		(end 81.407 -18.91665)
		(stroke
			(width 0.2)
			(type default)
		)
		(fill no)
		(layer "In4.Cu")
	)
	(gr_circle
		(center 80.518 -16.383)
		(end 81.407 -16.383)
		(stroke
			(width 0.2)
			(type default)
		)
		(fill no)
		(layer "In4.Cu")
	)
	(gr_circle
		(center 80.518 -14.732)
		(end 81.407 -14.732)
		(stroke
			(width 0.2)
			(type default)
		)
		(fill no)
		(layer "In4.Cu")
	)
	(gr_circle
		(center 80.712564 -9.959594)
		(end 81.601564 -9.959594)
		(stroke
			(width 0.2)
			(type default)
		)
		(fill no)
		(layer "In4.Cu")
	)
	(gr_circle
		(center 81.474564 -9.959594)
		(end 82.363564 -9.959594)
		(stroke
			(width 0.2)
			(type default)
		)
		(fill no)
		(layer "In4.Cu")
	)
	(gr_circle
		(center 81.534 -16.002)
		(end 82.423 -16.002)
		(stroke
			(width 0.2)
			(type default)
		)
		(fill no)
		(layer "In4.Cu")
	)
	(gr_circle
		(center 81.661 -18.91665)
		(end 82.55 -18.91665)
		(stroke
			(width 0.2)
			(type default)
		)
		(fill no)
		(layer "In4.Cu")
	)
	(gr_circle
		(center 81.661 -16.891)
		(end 82.55 -16.891)
		(stroke
			(width 0.2)
			(type default)
		)
		(fill no)
		(layer "In4.Cu")
	)
	(gr_circle
		(center 82.236564 -9.959594)
		(end 83.125564 -9.959594)
		(stroke
			(width 0.2)
			(type default)
		)
		(fill no)
		(layer "In4.Cu")
	)
	(gr_circle
		(center 82.296 -19.558)
		(end 83.185 -19.558)
		(stroke
			(width 0.2)
			(type default)
		)
		(fill no)
		(layer "In4.Cu")
	)
	(gr_circle
		(center 82.5754 -16.256)
		(end 83.4644 -16.256)
		(stroke
			(width 0.2)
			(type default)
		)
		(fill no)
		(layer "In4.Cu")
	)
	(gr_circle
		(center 82.804 -18.916904)
		(end 83.693 -18.916904)
		(stroke
			(width 0.2)
			(type default)
		)
		(fill no)
		(layer "In4.Cu")
	)
	(gr_arc
		(start 83.000088 -158.299912)
		(mid 80.878772 -159.17859)
		(end 80.000094 -161.299906)
		(stroke
			(width 2.032)
			(type default)
		)
		(layer "In4.Cu")
	)
	(gr_arc
		(start 83.000088 -158.299912)
		(mid 80.945191 -159.245009)
		(end 80.000094 -161.299906)
		(stroke
			(width 2.032)
			(type default)
		)
		(layer "In4.Cu")
	)
	(gr_line
		(start 83.49996 -158.299912)
		(end 83.000088 -158.299912)
		(stroke
			(width 2.032)
			(type default)
		)
		(layer "In4.Cu")
	)
	(gr_arc
		(start 83.49996 -158.299912)
		(mid 87.035488 -156.835449)
		(end 88.49995 -153.299922)
		(stroke
			(width 2.032)
			(type default)
		)
		(layer "In4.Cu")
	)
	(gr_circle
		(center 83.947 -18.916904)
		(end 84.836 -18.916904)
		(stroke
			(width 0.2)
			(type default)
		)
		(fill no)
		(layer "In4.Cu")
	)
	(gr_circle
		(center 84.455 -16.0782)
		(end 85.344 -16.0782)
		(stroke
			(width 0.2)
			(type default)
		)
		(fill no)
		(layer "In4.Cu")
	)
	(gr_line
		(start 88.49995 -110.499906)
		(end 88.49995 -153.299922)
		(stroke
			(width 2.032)
			(type default)
		)
		(layer "In4.Cu")
	)
	(gr_circle
		(center 93.774768 -9.757918)
		(end 94.663768 -9.757918)
		(stroke
			(width 0.2)
			(type default)
		)
		(fill no)
		(layer "In4.Cu")
	)
	(gr_circle
		(center 94.536768 -9.757918)
		(end 95.425768 -9.757918)
		(stroke
			(width 0.2)
			(type default)
		)
		(fill no)
		(layer "In4.Cu")
	)
	(gr_circle
		(center 95.298768 -9.757918)
		(end 96.187768 -9.757918)
		(stroke
			(width 0.2)
			(type default)
		)
		(fill no)
		(layer "In4.Cu")
	)
	(gr_arc
		(start 96.000062 -103.000048)
		(mid 90.696772 -105.19669)
		(end 88.49995 -110.499906)
		(stroke
			(width 2.032)
			(type default)
		)
		(layer "In4.Cu")
	)
	(gr_line
		(start 96.000062 -103.000048)
		(end 114.705384 -103.000048)
		(stroke
			(width 2.032)
			(type default)
		)
		(layer "In4.Cu")
	)
	(gr_circle
		(center 96.060768 -9.757918)
		(end 96.949768 -9.757918)
		(stroke
			(width 0.2)
			(type default)
		)
		(fill no)
		(layer "In4.Cu")
	)
	(gr_line
		(start 98.289618 -8.745982)
		(end 73.5076 -33.528)
		(stroke
			(width 1.016)
			(type default)
		)
		(layer "In4.Cu")
	)
	(gr_circle
		(center 103.6574 -57.023)
		(end 104.5464 -57.023)
		(stroke
			(width 0.2)
			(type default)
		)
		(fill no)
		(layer "In4.Cu")
	)
	(gr_circle
		(center 103.6574 -45.7454)
		(end 104.5464 -45.7454)
		(stroke
			(width 0.2)
			(type default)
		)
		(fill no)
		(layer "In4.Cu")
	)
	(gr_circle
		(center 108.782358 -42.432224)
		(end 109.671358 -42.432224)
		(stroke
			(width 0.2)
			(type default)
		)
		(fill no)
		(layer "In4.Cu")
	)
	(gr_circle
		(center 109.374432 -53.692806)
		(end 110.263432 -53.692806)
		(stroke
			(width 0.2)
			(type default)
		)
		(fill no)
		(layer "In4.Cu")
	)
	(gr_circle
		(center 111.2774 -54.483)
		(end 112.1664 -54.483)
		(stroke
			(width 0.2)
			(type default)
		)
		(fill no)
		(layer "In4.Cu")
	)
	(gr_circle
		(center 111.2774 -43.18)
		(end 112.1664 -43.18)
		(stroke
			(width 0.2)
			(type default)
		)
		(fill no)
		(layer "In4.Cu")
	)
	(gr_circle
		(center 112.252252 -78.6638)
		(end 113.141252 -78.6638)
		(stroke
			(width 0.2)
			(type default)
		)
		(fill no)
		(layer "In4.Cu")
	)
	(gr_circle
		(center 112.252252 -67.3862)
		(end 113.141252 -67.3862)
		(stroke
			(width 0.2)
			(type default)
		)
		(fill no)
		(layer "In4.Cu")
	)
	(gr_circle
		(center 112.252252 -56.1086)
		(end 113.141252 -56.1086)
		(stroke
			(width 0.2)
			(type default)
		)
		(fill no)
		(layer "In4.Cu")
	)
	(gr_circle
		(center 112.252252 -44.831)
		(end 113.141252 -44.831)
		(stroke
			(width 0.2)
			(type default)
		)
		(fill no)
		(layer "In4.Cu")
	)
	(gr_circle
		(center 112.252252 -33.5534)
		(end 113.141252 -33.5534)
		(stroke
			(width 0.2)
			(type default)
		)
		(fill no)
		(layer "In4.Cu")
	)
	(gr_circle
		(center 112.252252 -22.2758)
		(end 113.141252 -22.2758)
		(stroke
			(width 0.2)
			(type default)
		)
		(fill no)
		(layer "In4.Cu")
	)
	(gr_line
		(start 114.705384 -103.000048)
		(end 114.705384 -85.1281)
		(stroke
			(width 1.016)
			(type default)
		)
		(layer "In4.Cu")
	)
	(gr_line
		(start 114.705384 -85.1281)
		(end 123.9012 -85.1281)
		(stroke
			(width 1.016)
			(type default)
		)
		(layer "In4.Cu")
	)
	(gr_line
		(start 122.8344 -79.883)
		(end 123.4694 -80.518)
		(stroke
			(width 1.016)
			(type default)
		)
		(layer "In4.Cu")
	)
	(gr_line
		(start 122.8344 -46.863)
		(end 122.8344 -79.883)
		(stroke
			(width 1.016)
			(type default)
		)
		(layer "In4.Cu")
	)
	(gr_line
		(start 122.8344 -46.863)
		(end 122.8344 -8.745982)
		(stroke
			(width 1.016)
			(type default)
		)
		(layer "In4.Cu")
	)
	(gr_line
		(start 122.8344 -13.081)
		(end 123.4694 -12.446)
		(stroke
			(width 1.016)
			(type default)
		)
		(layer "In4.Cu")
	)
	(gr_line
		(start 122.8344 -8.745982)
		(end 161.50971 -8.745982)
		(stroke
			(width 1.016)
			(type default)
		)
		(layer "In4.Cu")
	)
	(gr_line
		(start 123.3424 -46.355)
		(end 122.8344 -46.863)
		(stroke
			(width 1.016)
			(type default)
		)
		(layer "In4.Cu")
	)
	(gr_line
		(start 123.3424 -46.355)
		(end 122.8344 -45.847)
		(stroke
			(width 1.016)
			(type default)
		)
		(layer "In4.Cu")
	)
	(gr_line
		(start 123.598432 -8.745982)
		(end 98.289618 -8.745982)
		(stroke
			(width 1.016)
			(type default)
		)
		(layer "In4.Cu")
	)
	(gr_line
		(start 123.9012 -85.1281)
		(end 126.7587 -87.9856)
		(stroke
			(width 1.016)
			(type default)
		)
		(layer "In4.Cu")
	)
	(gr_line
		(start 126.7587 -87.9856)
		(end 133.1976 -87.9856)
		(stroke
			(width 1.016)
			(type default)
		)
		(layer "In4.Cu")
	)
	(gr_line
		(start 127.274574 -8.745982)
		(end 127.293878 -8.726678)
		(stroke
			(width 1.016)
			(type default)
		)
		(layer "In4.Cu")
	)
	(gr_circle
		(center 128.602486 -83.566)
		(end 129.491486 -83.566)
		(stroke
			(width 0.2)
			(type default)
		)
		(fill no)
		(layer "In4.Cu")
	)
	(gr_circle
		(center 128.602486 -81.788)
		(end 129.491486 -81.788)
		(stroke
			(width 0.2)
			(type default)
		)
		(fill no)
		(layer "In4.Cu")
	)
	(gr_circle
		(center 131.421886 -81.788)
		(end 132.310886 -81.788)
		(stroke
			(width 0.2)
			(type default)
		)
		(fill no)
		(layer "In4.Cu")
	)
	(gr_circle
		(center 131.42214 -83.566)
		(end 132.31114 -83.566)
		(stroke
			(width 0.2)
			(type default)
		)
		(fill no)
		(layer "In4.Cu")
	)
	(gr_line
		(start 133.1976 -87.9856)
		(end 136.0551 -85.1281)
		(stroke
			(width 1.016)
			(type default)
		)
		(layer "In4.Cu")
	)
	(gr_line
		(start 136.0551 -85.1281)
		(end 185.1279 -85.1281)
		(stroke
			(width 1.016)
			(type default)
		)
		(layer "In4.Cu")
	)
	(gr_line
		(start 136.23925 -80.518)
		(end 123.4694 -80.518)
		(stroke
			(width 1.016)
			(type default)
		)
		(layer "In4.Cu")
	)
	(gr_line
		(start 136.86663 -79.89062)
		(end 136.23925 -80.518)
		(stroke
			(width 1.016)
			(type default)
		)
		(layer "In4.Cu")
	)
	(gr_line
		(start 136.86663 -68.303902)
		(end 136.86663 -79.89062)
		(stroke
			(width 1.016)
			(type default)
		)
		(layer "In4.Cu")
	)
	(gr_line
		(start 137.855706 -67.314826)
		(end 136.86663 -68.303902)
		(stroke
			(width 1.016)
			(type default)
		)
		(layer "In4.Cu")
	)
	(gr_line
		(start 137.855706 -67.314826)
		(end 148.668232 -67.314826)
		(stroke
			(width 1.016)
			(type default)
		)
		(layer "In4.Cu")
	)
	(gr_line
		(start 138.049 -38.862)
		(end 139.1666 -39.9796)
		(stroke
			(width 1.016)
			(type default)
		)
		(layer "In4.Cu")
	)
	(gr_line
		(start 138.049 -33.8328)
		(end 138.049 -38.862)
		(stroke
			(width 1.016)
			(type default)
		)
		(layer "In4.Cu")
	)
	(gr_line
		(start 138.2268 -38.2524)
		(end 147.066 -38.2524)
		(stroke
			(width 1.016)
			(type default)
		)
		(layer "In4.Cu")
	)
	(gr_line
		(start 138.2268 -37.6682)
		(end 147.066 -37.6682)
		(stroke
			(width 1.016)
			(type default)
		)
		(layer "In4.Cu")
	)
	(gr_line
		(start 138.2522 -37.0586)
		(end 147.0914 -37.0586)
		(stroke
			(width 1.016)
			(type default)
		)
		(layer "In4.Cu")
	)
	(gr_line
		(start 138.2522 -34.8742)
		(end 147.0914 -34.8742)
		(stroke
			(width 1.016)
			(type default)
		)
		(layer "In4.Cu")
	)
	(gr_line
		(start 138.2776 -36.3474)
		(end 147.1168 -36.3474)
		(stroke
			(width 1.016)
			(type default)
		)
		(layer "In4.Cu")
	)
	(gr_line
		(start 138.303 -35.6616)
		(end 147.1422 -35.6616)
		(stroke
			(width 1.016)
			(type default)
		)
		(layer "In4.Cu")
	)
	(gr_line
		(start 138.34872 -33.53308)
		(end 138.049 -33.8328)
		(stroke
			(width 1.016)
			(type default)
		)
		(layer "In4.Cu")
	)
	(gr_line
		(start 138.3538 -34.2392)
		(end 147.193 -34.2392)
		(stroke
			(width 1.016)
			(type default)
		)
		(layer "In4.Cu")
	)
	(gr_line
		(start 138.3792 -38.7604)
		(end 147.2184 -38.7604)
		(stroke
			(width 1.016)
			(type default)
		)
		(layer "In4.Cu")
	)
	(gr_line
		(start 138.6078 -34.2646)
		(end 138.6078 -39.2938)
		(stroke
			(width 1.016)
			(type default)
		)
		(layer "In4.Cu")
	)
	(gr_line
		(start 139.0904 -34.5694)
		(end 139.0904 -39.5986)
		(stroke
			(width 1.016)
			(type default)
		)
		(layer "In4.Cu")
	)
	(gr_line
		(start 139.1666 -39.9796)
		(end 141.7066 -39.9796)
		(stroke
			(width 1.016)
			(type default)
		)
		(layer "In4.Cu")
	)
	(gr_line
		(start 141.7066 -39.9796)
		(end 142.6464 -40.9194)
		(stroke
			(width 1.016)
			(type default)
		)
		(layer "In4.Cu")
	)
	(gr_line
		(start 141.8844 -12.446)
		(end 142.6464 -13.208)
		(stroke
			(width 1.016)
			(type default)
		)
		(layer "In4.Cu")
	)
	(gr_line
		(start 142.3924 -46.355)
		(end 123.3424 -46.355)
		(stroke
			(width 1.016)
			(type default)
		)
		(layer "In4.Cu")
	)
	(gr_line
		(start 142.3924 -46.355)
		(end 142.6464 -46.609)
		(stroke
			(width 1.016)
			(type default)
		)
		(layer "In4.Cu")
	)
	(gr_line
		(start 142.621 -32.6644)
		(end 141.5034 -33.782)
		(stroke
			(width 1.016)
			(type default)
		)
		(layer "In4.Cu")
	)
	(gr_line
		(start 142.621 -32.6644)
		(end 143.7386 -33.782)
		(stroke
			(width 1.016)
			(type default)
		)
		(layer "In4.Cu")
	)
	(gr_line
		(start 142.6464 -47.498)
		(end 141.5288 -46.3804)
		(stroke
			(width 1.016)
			(type default)
		)
		(layer "In4.Cu")
	)
	(gr_line
		(start 142.6464 -45.1612)
		(end 141.5288 -46.2788)
		(stroke
			(width 1.016)
			(type default)
		)
		(layer "In4.Cu")
	)
	(gr_line
		(start 142.6464 -33.909)
		(end 142.6464 -67.437)
		(stroke
			(width 1.016)
			(type default)
		)
		(layer "In4.Cu")
	)
	(gr_line
		(start 142.6464 -33.53308)
		(end 138.34872 -33.53308)
		(stroke
			(width 1.016)
			(type default)
		)
		(layer "In4.Cu")
	)
	(gr_line
		(start 142.6464 -33.53308)
		(end 147.35048 -33.53308)
		(stroke
			(width 1.016)
			(type default)
		)
		(layer "In4.Cu")
	)
	(gr_line
		(start 142.6464 -13.208)
		(end 142.6464 -33.53308)
		(stroke
			(width 1.016)
			(type default)
		)
		(layer "In4.Cu")
	)
	(gr_line
		(start 143.4084 -12.446)
		(end 142.6464 -13.208)
		(stroke
			(width 1.016)
			(type default)
		)
		(layer "In4.Cu")
	)
	(gr_circle
		(center 143.533114 -76.858368)
		(end 144.422114 -76.858368)
		(stroke
			(width 0.2)
			(type default)
		)
		(fill no)
		(layer "In4.Cu")
	)
	(gr_line
		(start 143.5862 -39.9796)
		(end 142.6464 -40.9194)
		(stroke
			(width 1.016)
			(type default)
		)
		(layer "In4.Cu")
	)
	(gr_line
		(start 144.4244 -39.3192)
		(end 139.3952 -39.3192)
		(stroke
			(width 1.016)
			(type default)
		)
		(layer "In4.Cu")
	)
	(gr_circle
		(center 144.892522 -76.886308)
		(end 145.781522 -76.886308)
		(stroke
			(width 0.2)
			(type default)
		)
		(fill no)
		(layer "In4.Cu")
	)
	(gr_circle
		(center 145.11655 -74.360278)
		(end 146.00555 -74.360278)
		(stroke
			(width 0.2)
			(type default)
		)
		(fill no)
		(layer "In4.Cu")
	)
	(gr_circle
		(center 145.171668 -73.42251)
		(end 146.060668 -73.42251)
		(stroke
			(width 0.2)
			(type default)
		)
		(fill no)
		(layer "In4.Cu")
	)
	(gr_line
		(start 145.5928 -39.8272)
		(end 140.5636 -39.8272)
		(stroke
			(width 1.016)
			(type default)
		)
		(layer "In4.Cu")
	)
	(gr_line
		(start 146.05 -34.544)
		(end 146.05 -39.5732)
		(stroke
			(width 1.016)
			(type default)
		)
		(layer "In4.Cu")
	)
	(gr_line
		(start 146.2024 -39.4208)
		(end 141.1732 -39.4208)
		(stroke
			(width 1.016)
			(type default)
		)
		(layer "In4.Cu")
	)
	(gr_line
		(start 146.2532 -39.9796)
		(end 143.5862 -39.9796)
		(stroke
			(width 1.016)
			(type default)
		)
		(layer "In4.Cu")
	)
	(gr_line
		(start 146.6596 -34.1884)
		(end 146.6596 -39.2176)
		(stroke
			(width 1.016)
			(type default)
		)
		(layer "In4.Cu")
	)
	(gr_line
		(start 147.2692 -33.8582)
		(end 147.2692 -38.8874)
		(stroke
			(width 1.016)
			(type default)
		)
		(layer "In4.Cu")
	)
	(gr_line
		(start 147.35048 -33.53308)
		(end 147.8534 -34.036)
		(stroke
			(width 1.016)
			(type default)
		)
		(layer "In4.Cu")
	)
	(gr_line
		(start 147.8534 -38.3794)
		(end 146.2532 -39.9796)
		(stroke
			(width 1.016)
			(type default)
		)
		(layer "In4.Cu")
	)
	(gr_line
		(start 147.8534 -34.036)
		(end 147.8534 -38.3794)
		(stroke
			(width 1.016)
			(type default)
		)
		(layer "In4.Cu")
	)
	(gr_line
		(start 148.668232 -67.314826)
		(end 149.184614 -66.798444)
		(stroke
			(width 1.016)
			(type default)
		)
		(layer "In4.Cu")
	)
	(gr_line
		(start 149.184614 -66.798444)
		(end 149.184614 -59.603386)
		(stroke
			(width 1.016)
			(type default)
		)
		(layer "In4.Cu")
	)
	(gr_line
		(start 149.184614 -59.603386)
		(end 149.5806 -59.2074)
		(stroke
			(width 1.016)
			(type default)
		)
		(layer "In4.Cu")
	)
	(gr_line
		(start 149.5806 -59.2074)
		(end 152.040336 -59.2074)
		(stroke
			(width 1.016)
			(type default)
		)
		(layer "In4.Cu")
	)
	(gr_circle
		(center 149.935692 -71.85406)
		(end 150.824692 -71.85406)
		(stroke
			(width 0.2)
			(type default)
		)
		(fill no)
		(layer "In4.Cu")
	)
	(gr_circle
		(center 149.935692 -70.353936)
		(end 150.824692 -70.353936)
		(stroke
			(width 0.2)
			(type default)
		)
		(fill no)
		(layer "In4.Cu")
	)
	(gr_circle
		(center 150.033736 -79.7052)
		(end 150.922736 -79.7052)
		(stroke
			(width 0.2)
			(type default)
		)
		(fill no)
		(layer "In4.Cu")
	)
	(gr_circle
		(center 150.033736 -78.9432)
		(end 150.922736 -78.9432)
		(stroke
			(width 0.2)
			(type default)
		)
		(fill no)
		(layer "In4.Cu")
	)
	(gr_line
		(start 152.040336 -59.2074)
		(end 152.608026 -59.77509)
		(stroke
			(width 1.016)
			(type default)
		)
		(layer "In4.Cu")
	)
	(gr_line
		(start 152.608026 -75.422252)
		(end 153.385774 -76.2)
		(stroke
			(width 1.016)
			(type default)
		)
		(layer "In4.Cu")
	)
	(gr_line
		(start 152.608026 -63.375032)
		(end 160.61309 -55.369968)
		(stroke
			(width 1.016)
			(type default)
		)
		(layer "In4.Cu")
	)
	(gr_line
		(start 152.608026 -59.77509)
		(end 152.608026 -75.422252)
		(stroke
			(width 1.016)
			(type default)
		)
		(layer "In4.Cu")
	)
	(gr_circle
		(center 152.82545 -77.61605)
		(end 153.71445 -77.61605)
		(stroke
			(width 0.2)
			(type default)
		)
		(fill no)
		(layer "In4.Cu")
	)
	(gr_line
		(start 153.385774 -76.2)
		(end 164.973 -76.2)
		(stroke
			(width 1.016)
			(type default)
		)
		(layer "In4.Cu")
	)
	(gr_circle
		(center 154.497786 -77.47)
		(end 155.386786 -77.47)
		(stroke
			(width 0.2)
			(type default)
		)
		(fill no)
		(layer "In4.Cu")
	)
	(gr_circle
		(center 156.637736 -78.22565)
		(end 157.526736 -78.22565)
		(stroke
			(width 0.2)
			(type default)
		)
		(fill no)
		(layer "In4.Cu")
	)
	(gr_line
		(start 156.980382 -12.446)
		(end 123.4694 -12.446)
		(stroke
			(width 1.016)
			(type default)
		)
		(layer "In4.Cu")
	)
	(gr_circle
		(center 158.034736 -78.232)
		(end 158.923736 -78.232)
		(stroke
			(width 0.2)
			(type default)
		)
		(fill no)
		(layer "In4.Cu")
	)
	(gr_circle
		(center 158.369 -96.266)
		(end 159.258 -96.266)
		(stroke
			(width 0.2)
			(type default)
		)
		(fill no)
		(layer "In4.Cu")
	)
	(gr_line
		(start 160.461198 -8.745982)
		(end 127.274574 -8.745982)
		(stroke
			(width 1.016)
			(type default)
		)
		(layer "In4.Cu")
	)
	(gr_line
		(start 160.461198 -8.745982)
		(end 182.918862 -8.745982)
		(stroke
			(width 1.016)
			(type default)
		)
		(layer "In4.Cu")
	)
	(gr_circle
		(center 160.575244 -86.084918)
		(end 161.464244 -86.084918)
		(stroke
			(width 0.2)
			(type default)
		)
		(fill no)
		(layer "In4.Cu")
	)
	(gr_line
		(start 160.61309 -55.369968)
		(end 175.611282 -55.369968)
		(stroke
			(width 1.016)
			(type default)
		)
		(layer "In4.Cu")
	)
	(gr_line
		(start 160.6804 -27.182318)
		(end 161.946082 -28.448)
		(stroke
			(width 1.016)
			(type default)
		)
		(layer "In4.Cu")
	)
	(gr_line
		(start 160.6804 -16.146018)
		(end 156.980382 -12.446)
		(stroke
			(width 1.016)
			(type default)
		)
		(layer "In4.Cu")
	)
	(gr_line
		(start 160.6804 -16.146018)
		(end 160.6804 -27.182318)
		(stroke
			(width 1.016)
			(type default)
		)
		(layer "In4.Cu")
	)
	(gr_line
		(start 161.490406 -8.726678)
		(end 161.50971 -8.745982)
		(stroke
			(width 1.016)
			(type default)
		)
		(layer "In4.Cu")
	)
	(gr_line
		(start 161.946082 -28.448)
		(end 209.1944 -28.448)
		(stroke
			(width 1.016)
			(type default)
		)
		(layer "In4.Cu")
	)
	(gr_circle
		(center 164.860986 -79.756)
		(end 165.749986 -79.756)
		(stroke
			(width 0.2)
			(type default)
		)
		(fill no)
		(layer "In4.Cu")
	)
	(gr_line
		(start 164.973 -76.2)
		(end 165.608 -75.565)
		(stroke
			(width 1.016)
			(type default)
		)
		(layer "In4.Cu")
	)
	(gr_line
		(start 165.608 -59.944)
		(end 165.608 -75.565)
		(stroke
			(width 1.016)
			(type default)
		)
		(layer "In4.Cu")
	)
	(gr_circle
		(center 166.1414 -66.802)
		(end 167.0304 -66.802)
		(stroke
			(width 0.2)
			(type default)
		)
		(fill no)
		(layer "In4.Cu")
	)
	(gr_line
		(start 166.141654 -59.410346)
		(end 165.608 -59.944)
		(stroke
			(width 1.016)
			(type default)
		)
		(layer "In4.Cu")
	)
	(gr_circle
		(center 166.943786 -66.802)
		(end 167.832786 -66.802)
		(stroke
			(width 0.2)
			(type default)
		)
		(fill no)
		(layer "In4.Cu")
	)
	(gr_circle
		(center 167.005 -83.83905)
		(end 167.894 -83.83905)
		(stroke
			(width 0.2)
			(type default)
		)
		(fill no)
		(layer "In4.Cu")
	)
	(gr_circle
		(center 167.005 -83.03895)
		(end 167.894 -83.03895)
		(stroke
			(width 0.2)
			(type default)
		)
		(fill no)
		(layer "In4.Cu")
	)
	(gr_circle
		(center 167.36695 -81.28)
		(end 168.25595 -81.28)
		(stroke
			(width 0.2)
			(type default)
		)
		(fill no)
		(layer "In4.Cu")
	)
	(gr_circle
		(center 167.386 -72.136)
		(end 168.275 -72.136)
		(stroke
			(width 0.2)
			(type default)
		)
		(fill no)
		(layer "In4.Cu")
	)
	(gr_circle
		(center 167.813736 -66.675)
		(end 168.702736 -66.675)
		(stroke
			(width 0.2)
			(type default)
		)
		(fill no)
		(layer "In4.Cu")
	)
	(gr_line
		(start 168.021 -75.692)
		(end 168.021 -70.072758)
		(stroke
			(width 1.016)
			(type default)
		)
		(layer "In4.Cu")
	)
	(gr_line
		(start 168.021 -70.072758)
		(end 170.281346 -67.812412)
		(stroke
			(width 1.016)
			(type default)
		)
		(layer "In4.Cu")
	)
	(gr_circle
		(center 168.16705 -81.28)
		(end 169.05605 -81.28)
		(stroke
			(width 0.2)
			(type default)
		)
		(fill no)
		(layer "In4.Cu")
	)
	(gr_circle
		(center 168.1734 -77.343)
		(end 169.0624 -77.343)
		(stroke
			(width 0.2)
			(type default)
		)
		(fill no)
		(layer "In4.Cu")
	)
	(gr_circle
		(center 168.17975 -78.359)
		(end 169.06875 -78.359)
		(stroke
			(width 0.2)
			(type default)
		)
		(fill no)
		(layer "In4.Cu")
	)
	(gr_circle
		(center 168.529 -79.121)
		(end 169.418 -79.121)
		(stroke
			(width 0.2)
			(type default)
		)
		(fill no)
		(layer "In4.Cu")
	)
	(gr_line
		(start 168.589452 -76.260452)
		(end 168.021 -75.692)
		(stroke
			(width 1.016)
			(type default)
		)
		(layer "In4.Cu")
	)
	(gr_line
		(start 169.577512 -59.410346)
		(end 166.141654 -59.410346)
		(stroke
			(width 1.016)
			(type default)
		)
		(layer "In4.Cu")
	)
	(gr_circle
		(center 169.672 -79.121)
		(end 170.561 -79.121)
		(stroke
			(width 0.2)
			(type default)
		)
		(fill no)
		(layer "In4.Cu")
	)
	(gr_line
		(start 170.281346 -67.812412)
		(end 170.281346 -60.11418)
		(stroke
			(width 1.016)
			(type default)
		)
		(layer "In4.Cu")
	)
	(gr_line
		(start 170.281346 -60.11418)
		(end 169.577512 -59.410346)
		(stroke
			(width 1.016)
			(type default)
		)
		(layer "In4.Cu")
	)
	(gr_circle
		(center 170.434 -80.20304)
		(end 171.323 -80.20304)
		(stroke
			(width 0.2)
			(type default)
		)
		(fill no)
		(layer "In4.Cu")
	)
	(gr_circle
		(center 171.4754 -77.343)
		(end 172.3644 -77.343)
		(stroke
			(width 0.2)
			(type default)
		)
		(fill no)
		(layer "In4.Cu")
	)
	(gr_line
		(start 172.174662 -50.696622)
		(end 172.583348 -51.105308)
		(stroke
			(width 1.016)
			(type default)
		)
		(layer "In4.Cu")
	)
	(gr_line
		(start 172.174662 -43.570398)
		(end 172.174662 -50.696622)
		(stroke
			(width 1.016)
			(type default)
		)
		(layer "In4.Cu")
	)
	(gr_line
		(start 172.583348 -51.105308)
		(end 173.980348 -51.105308)
		(stroke
			(width 1.016)
			(type default)
		)
		(layer "In4.Cu")
	)
	(gr_line
		(start 173.915832 -41.829228)
		(end 172.174662 -43.570398)
		(stroke
			(width 1.016)
			(type default)
		)
		(layer "In4.Cu")
	)
	(gr_line
		(start 175.611282 -55.369968)
		(end 176.302162 -54.679088)
		(stroke
			(width 1.016)
			(type default)
		)
		(layer "In4.Cu")
	)
	(gr_circle
		(center 175.706786 -78.486)
		(end 176.595786 -78.486)
		(stroke
			(width 0.2)
			(type default)
		)
		(fill no)
		(layer "In4.Cu")
	)
	(gr_line
		(start 176.302162 -54.679088)
		(end 176.302162 -53.427122)
		(stroke
			(width 1.016)
			(type default)
		)
		(layer "In4.Cu")
	)
	(gr_line
		(start 176.302162 -53.427122)
		(end 173.980348 -51.105308)
		(stroke
			(width 1.016)
			(type default)
		)
		(layer "In4.Cu")
	)
	(gr_circle
		(center 178.87696 -46.99)
		(end 179.76596 -46.99)
		(stroke
			(width 0.2)
			(type default)
		)
		(fill no)
		(layer "In4.Cu")
	)
	(gr_line
		(start 179.735226 -103.000048)
		(end 114.705384 -103.000048)
		(stroke
			(width 2.032)
			(type default)
		)
		(layer "In4.Cu")
	)
	(gr_line
		(start 179.735226 -103.000048)
		(end 264.668 -103.000048)
		(stroke
			(width 2.032)
			(type default)
		)
		(layer "In4.Cu")
	)
	(gr_circle
		(center 180.5686 -82.3214)
		(end 181.4576 -82.3214)
		(stroke
			(width 0.2)
			(type default)
		)
		(fill no)
		(layer "In4.Cu")
	)
	(gr_line
		(start 182.1434 -50.894996)
		(end 182.1434 -50.419)
		(stroke
			(width 1.016)
			(type default)
		)
		(layer "In4.Cu")
	)
	(gr_line
		(start 182.1434 -50.419)
		(end 182.1434 -47.879)
		(stroke
			(width 1.016)
			(type default)
		)
		(layer "In4.Cu")
	)
	(gr_line
		(start 182.1434 -47.879)
		(end 182.1434 -46.609)
		(stroke
			(width 1.016)
			(type default)
		)
		(layer "In4.Cu")
	)
	(gr_line
		(start 182.1434 -46.609)
		(end 185.8264 -42.926)
		(stroke
			(width 1.016)
			(type default)
		)
		(layer "In4.Cu")
	)
	(gr_circle
		(center 182.215536 -69.4436)
		(end 183.104536 -69.4436)
		(stroke
			(width 0.2)
			(type default)
		)
		(fill no)
		(layer "In4.Cu")
	)
	(gr_circle
		(center 182.753 -80.137)
		(end 183.642 -80.137)
		(stroke
			(width 0.2)
			(type default)
		)
		(fill no)
		(layer "In4.Cu")
	)
	(gr_line
		(start 182.815484 -51.56708)
		(end 182.1434 -50.894996)
		(stroke
			(width 1.016)
			(type default)
		)
		(layer "In4.Cu")
	)
	(gr_line
		(start 182.918862 -8.745982)
		(end 255.633982 -8.745982)
		(stroke
			(width 1.016)
			(type default)
		)
		(layer "In4.Cu")
	)
	(gr_line
		(start 182.946548 -76.260452)
		(end 168.589452 -76.260452)
		(stroke
			(width 1.016)
			(type default)
		)
		(layer "In4.Cu")
	)
	(gr_line
		(start 183.261 -75.946)
		(end 182.946548 -76.260452)
		(stroke
			(width 1.016)
			(type default)
		)
		(layer "In4.Cu")
	)
	(gr_line
		(start 183.261 -68.072)
		(end 183.261 -75.946)
		(stroke
			(width 1.016)
			(type default)
		)
		(layer "In4.Cu")
	)
	(gr_circle
		(center 183.62295 -76.073)
		(end 184.51195 -76.073)
		(stroke
			(width 0.2)
			(type default)
		)
		(fill no)
		(layer "In4.Cu")
	)
	(gr_line
		(start 183.896 -67.437)
		(end 183.261 -68.072)
		(stroke
			(width 1.016)
			(type default)
		)
		(layer "In4.Cu")
	)
	(gr_circle
		(center 184.15 -74.295)
		(end 185.039 -74.295)
		(stroke
			(width 0.2)
			(type default)
		)
		(fill no)
		(layer "In4.Cu")
	)
	(gr_circle
		(center 184.42305 -76.09205)
		(end 185.31205 -76.09205)
		(stroke
			(width 0.2)
			(type default)
		)
		(fill no)
		(layer "In4.Cu")
	)
	(gr_line
		(start 185.1279 -85.1281)
		(end 186.817 -83.439)
		(stroke
			(width 1.016)
			(type default)
		)
		(layer "In4.Cu")
	)
	(gr_line
		(start 185.801 -67.437)
		(end 183.896 -67.437)
		(stroke
			(width 1.016)
			(type default)
		)
		(layer "In4.Cu")
	)
	(gr_line
		(start 185.8264 -42.926)
		(end 189.847982 -42.926)
		(stroke
			(width 1.016)
			(type default)
		)
		(layer "In4.Cu")
	)
	(gr_circle
		(center 186.563 -78.88605)
		(end 187.452 -78.88605)
		(stroke
			(width 0.2)
			(type default)
		)
		(fill no)
		(layer "In4.Cu")
	)
	(gr_circle
		(center 186.563 -78.08595)
		(end 187.452 -78.08595)
		(stroke
			(width 0.2)
			(type default)
		)
		(fill no)
		(layer "In4.Cu")
	)
	(gr_line
		(start 186.817 -83.439)
		(end 186.817 -68.453)
		(stroke
			(width 1.016)
			(type default)
		)
		(layer "In4.Cu")
	)
	(gr_line
		(start 186.817 -68.453)
		(end 185.801 -67.437)
		(stroke
			(width 1.016)
			(type default)
		)
		(layer "In4.Cu")
	)
	(gr_line
		(start 189.847982 -42.926)
		(end 193.576448 -46.654466)
		(stroke
			(width 1.016)
			(type default)
		)
		(layer "In4.Cu")
	)
	(gr_line
		(start 191.747394 -41.829228)
		(end 173.915832 -41.829228)
		(stroke
			(width 1.016)
			(type default)
		)
		(layer "In4.Cu")
	)
	(gr_line
		(start 193.031618 -51.56708)
		(end 182.815484 -51.56708)
		(stroke
			(width 1.016)
			(type default)
		)
		(layer "In4.Cu")
	)
	(gr_line
		(start 193.576448 -51.02225)
		(end 193.031618 -51.56708)
		(stroke
			(width 1.016)
			(type default)
		)
		(layer "In4.Cu")
	)
	(gr_line
		(start 193.576448 -47.879)
		(end 193.576448 -51.02225)
		(stroke
			(width 1.016)
			(type default)
		)
		(layer "In4.Cu")
	)
	(gr_line
		(start 193.576448 -46.654466)
		(end 193.576448 -47.879)
		(stroke
			(width 1.016)
			(type default)
		)
		(layer "In4.Cu")
	)
	(gr_line
		(start 197.797166 -47.879)
		(end 191.747394 -41.829228)
		(stroke
			(width 1.016)
			(type default)
		)
		(layer "In4.Cu")
	)
	(gr_circle
		(center 208.810098 -51.049936)
		(end 210.20913 -51.049936)
		(stroke
			(width 0.2)
			(type default)
		)
		(fill no)
		(layer "In4.Cu")
	)
	(gr_line
		(start 209.1944 -28.448)
		(end 210.9724 -30.226)
		(stroke
			(width 1.016)
			(type default)
		)
		(layer "In4.Cu")
	)
	(gr_line
		(start 210.0834 -47.879)
		(end 197.797166 -47.879)
		(stroke
			(width 1.016)
			(type default)
		)
		(layer "In4.Cu")
	)
	(gr_line
		(start 210.9724 -46.99)
		(end 210.0834 -47.879)
		(stroke
			(width 1.016)
			(type default)
		)
		(layer "In4.Cu")
	)
	(gr_line
		(start 210.9724 -30.226)
		(end 210.9724 -46.99)
		(stroke
			(width 1.016)
			(type default)
		)
		(layer "In4.Cu")
	)
	(gr_circle
		(center 219.1004 -7.493)
		(end 219.9894 -7.493)
		(stroke
			(width 0.2)
			(type default)
		)
		(fill no)
		(layer "In4.Cu")
	)
	(gr_circle
		(center 220.2434 -8.001)
		(end 221.1324 -8.001)
		(stroke
			(width 0.2)
			(type default)
		)
		(fill no)
		(layer "In4.Cu")
	)
	(gr_circle
		(center 220.2434 -7.112)
		(end 221.1324 -7.112)
		(stroke
			(width 0.2)
			(type default)
		)
		(fill no)
		(layer "In4.Cu")
	)
	(gr_circle
		(center 221.115382 -7.856728)
		(end 222.004382 -7.856728)
		(stroke
			(width 0.2)
			(type default)
		)
		(fill no)
		(layer "In4.Cu")
	)
	(gr_circle
		(center 221.623382 -7.475728)
		(end 222.512382 -7.475728)
		(stroke
			(width 0.2)
			(type default)
		)
		(fill no)
		(layer "In4.Cu")
	)
	(gr_line
		(start 229.362 -46.99)
		(end 230.251 -47.879)
		(stroke
			(width 1.016)
			(type default)
		)
		(layer "In4.Cu")
	)
	(gr_line
		(start 229.362 -30.226)
		(end 229.362 -46.99)
		(stroke
			(width 1.016)
			(type default)
		)
		(layer "In4.Cu")
	)
	(gr_line
		(start 230.251 -47.879)
		(end 242.963954 -47.879)
		(stroke
			(width 1.016)
			(type default)
		)
		(layer "In4.Cu")
	)
	(gr_line
		(start 231.14 -28.448)
		(end 229.362 -30.226)
		(stroke
			(width 1.016)
			(type default)
		)
		(layer "In4.Cu")
	)
	(gr_circle
		(center 238.810038 -51.049936)
		(end 240.20907 -51.049936)
		(stroke
			(width 0.2)
			(type default)
		)
		(fill no)
		(layer "In4.Cu")
	)
	(gr_line
		(start 242.963954 -47.879)
		(end 248.993406 -41.849548)
		(stroke
			(width 1.016)
			(type default)
		)
		(layer "In4.Cu")
	)
	(gr_line
		(start 246.757952 -51.02225)
		(end 247.302782 -51.56708)
		(stroke
			(width 1.016)
			(type default)
		)
		(layer "In4.Cu")
	)
	(gr_line
		(start 246.757952 -47.879)
		(end 246.757952 -51.02225)
		(stroke
			(width 1.016)
			(type default)
		)
		(layer "In4.Cu")
	)
	(gr_line
		(start 246.757952 -46.654466)
		(end 246.757952 -47.879)
		(stroke
			(width 1.016)
			(type default)
		)
		(layer "In4.Cu")
	)
	(gr_line
		(start 247.302782 -51.56708)
		(end 257.518916 -51.56708)
		(stroke
			(width 1.016)
			(type default)
		)
		(layer "In4.Cu")
	)
	(gr_line
		(start 248.993406 -41.849548)
		(end 255.895348 -41.849548)
		(stroke
			(width 1.016)
			(type default)
		)
		(layer "In4.Cu")
	)
	(gr_line
		(start 250.486418 -42.926)
		(end 246.757952 -46.654466)
		(stroke
			(width 1.016)
			(type default)
		)
		(layer "In4.Cu")
	)
	(gr_line
		(start 254.508 -42.926)
		(end 250.486418 -42.926)
		(stroke
			(width 1.016)
			(type default)
		)
		(layer "In4.Cu")
	)
	(gr_line
		(start 255.524 -8.636)
		(end 255.633982 -8.745982)
		(stroke
			(width 1.016)
			(type default)
		)
		(layer "In4.Cu")
	)
	(gr_line
		(start 255.633982 -8.745982)
		(end 258.462018 -8.745982)
		(stroke
			(width 1.016)
			(type default)
		)
		(layer "In4.Cu")
	)
	(gr_line
		(start 255.895348 -41.849548)
		(end 258.5212 -44.4754)
		(stroke
			(width 1.016)
			(type default)
		)
		(layer "In4.Cu")
	)
	(gr_line
		(start 257.048 -8.636)
		(end 279.654 -8.636)
		(stroke
			(width 1.016)
			(type default)
		)
		(layer "In4.Cu")
	)
	(gr_line
		(start 257.518916 -51.56708)
		(end 258.191 -50.894996)
		(stroke
			(width 1.016)
			(type default)
		)
		(layer "In4.Cu")
	)
	(gr_line
		(start 258.191 -50.894996)
		(end 258.191 -50.419)
		(stroke
			(width 1.016)
			(type default)
		)
		(layer "In4.Cu")
	)
	(gr_line
		(start 258.191 -50.419)
		(end 258.191 -47.879)
		(stroke
			(width 1.016)
			(type default)
		)
		(layer "In4.Cu")
	)
	(gr_line
		(start 258.191 -47.879)
		(end 258.191 -46.609)
		(stroke
			(width 1.016)
			(type default)
		)
		(layer "In4.Cu")
	)
	(gr_line
		(start 258.191 -46.609)
		(end 254.508 -42.926)
		(stroke
			(width 1.016)
			(type default)
		)
		(layer "In4.Cu")
	)
	(gr_line
		(start 258.462018 -8.745982)
		(end 258.572 -8.636)
		(stroke
			(width 1.016)
			(type default)
		)
		(layer "In4.Cu")
	)
	(gr_line
		(start 258.5212 -44.4754)
		(end 267.97 -44.4754)
		(stroke
			(width 1.016)
			(type default)
		)
		(layer "In4.Cu")
	)
	(gr_circle
		(center 260.2484 -46.99)
		(end 261.1374 -46.99)
		(stroke
			(width 0.2)
			(type default)
		)
		(fill no)
		(layer "In4.Cu")
	)
	(gr_line
		(start 260.51383 -85.493606)
		(end 260.51383 -58.30951)
		(stroke
			(width 1.016)
			(type default)
		)
		(layer "In4.Cu")
	)
	(gr_line
		(start 260.51383 -58.30951)
		(end 261.77748 -57.04586)
		(stroke
			(width 1.016)
			(type default)
		)
		(layer "In4.Cu")
	)
	(gr_line
		(start 261.77748 -57.04586)
		(end 272.766536 -57.04586)
		(stroke
			(width 1.016)
			(type default)
		)
		(layer "In4.Cu")
	)
	(gr_circle
		(center 262.72744 -64.516)
		(end 263.61644 -64.516)
		(stroke
			(width 0.2)
			(type default)
		)
		(fill no)
		(layer "In4.Cu")
	)
	(gr_circle
		(center 263.0805 -74.739246)
		(end 263.9695 -74.739246)
		(stroke
			(width 0.2)
			(type default)
		)
		(fill no)
		(layer "In4.Cu")
	)
	(gr_line
		(start 263.66343 -88.643206)
		(end 260.51383 -85.493606)
		(stroke
			(width 1.016)
			(type default)
		)
		(layer "In4.Cu")
	)
	(gr_circle
		(center 264.8712 -69.34708)
		(end 265.7602 -69.34708)
		(stroke
			(width 0.2)
			(type default)
		)
		(fill no)
		(layer "In4.Cu")
	)
	(gr_circle
		(center 265.4046 -70.7644)
		(end 266.2936 -70.7644)
		(stroke
			(width 0.2)
			(type default)
		)
		(fill no)
		(layer "In4.Cu")
	)
	(gr_circle
		(center 267.2588 -73.8886)
		(end 268.1478 -73.8886)
		(stroke
			(width 0.2)
			(type default)
		)
		(fill no)
		(layer "In4.Cu")
	)
	(gr_line
		(start 267.97 -44.4754)
		(end 282.2956 -58.801)
		(stroke
			(width 1.016)
			(type default)
		)
		(layer "In4.Cu")
	)
	(gr_circle
		(center 268.0462 -73.8886)
		(end 268.9352 -73.8886)
		(stroke
			(width 0.2)
			(type default)
		)
		(fill no)
		(layer "In4.Cu")
	)
	(gr_circle
		(center 268.1224 -71.0184)
		(end 269.0114 -71.0184)
		(stroke
			(width 0.2)
			(type default)
		)
		(fill no)
		(layer "In4.Cu")
	)
	(gr_circle
		(center 268.1224 -68.199)
		(end 269.0114 -68.199)
		(stroke
			(width 0.2)
			(type default)
		)
		(fill no)
		(layer "In4.Cu")
	)
	(gr_line
		(start 268.831822 -72.353678)
		(end 270.59128 -74.113136)
		(stroke
			(width 1.016)
			(type default)
		)
		(layer "In4.Cu")
	)
	(gr_line
		(start 268.831822 -67.394836)
		(end 268.831822 -72.353678)
		(stroke
			(width 1.016)
			(type default)
		)
		(layer "In4.Cu")
	)
	(gr_circle
		(center 269.9004 -77.47)
		(end 270.7894 -77.47)
		(stroke
			(width 0.2)
			(type default)
		)
		(fill no)
		(layer "In4.Cu")
	)
	(gr_circle
		(center 270.0782 -86.233)
		(end 270.9672 -86.233)
		(stroke
			(width 0.2)
			(type default)
		)
		(fill no)
		(layer "In4.Cu")
	)
	(gr_circle
		(center 270.4084 -82.296)
		(end 271.2974 -82.296)
		(stroke
			(width 0.2)
			(type default)
		)
		(fill no)
		(layer "In4.Cu")
	)
	(gr_line
		(start 270.59128 -74.113136)
		(end 310.72201 -74.113136)
		(stroke
			(width 1.016)
			(type default)
		)
		(layer "In4.Cu")
	)
	(gr_circle
		(center 270.7132 -86.233)
		(end 271.6022 -86.233)
		(stroke
			(width 0.2)
			(type default)
		)
		(fill no)
		(layer "In4.Cu")
	)
	(gr_circle
		(center 271.02435 -77.21092)
		(end 271.91335 -77.21092)
		(stroke
			(width 0.2)
			(type default)
		)
		(fill no)
		(layer "In4.Cu")
	)
	(gr_circle
		(center 271.82445 -77.21092)
		(end 272.71345 -77.21092)
		(stroke
			(width 0.2)
			(type default)
		)
		(fill no)
		(layer "In4.Cu")
	)
	(gr_circle
		(center 271.91335 -61.722)
		(end 272.80235 -61.722)
		(stroke
			(width 0.2)
			(type default)
		)
		(fill no)
		(layer "In4.Cu")
	)
	(gr_circle
		(center 272.1102 -86.233)
		(end 272.9992 -86.233)
		(stroke
			(width 0.2)
			(type default)
		)
		(fill no)
		(layer "In4.Cu")
	)
	(gr_circle
		(center 272.4404 -82.296)
		(end 273.3294 -82.296)
		(stroke
			(width 0.2)
			(type default)
		)
		(fill no)
		(layer "In4.Cu")
	)
	(gr_circle
		(center 272.7452 -86.233)
		(end 273.6342 -86.233)
		(stroke
			(width 0.2)
			(type default)
		)
		(fill no)
		(layer "In4.Cu")
	)
	(gr_line
		(start 272.766536 -57.04586)
		(end 273.422364 -57.701688)
		(stroke
			(width 1.016)
			(type default)
		)
		(layer "In4.Cu")
	)
	(gr_line
		(start 273.422364 -62.804294)
		(end 268.831822 -67.394836)
		(stroke
			(width 1.016)
			(type default)
		)
		(layer "In4.Cu")
	)
	(gr_line
		(start 273.422364 -57.701688)
		(end 273.422364 -62.804294)
		(stroke
			(width 1.016)
			(type default)
		)
		(layer "In4.Cu")
	)
	(gr_circle
		(center 274.1422 -86.233)
		(end 275.0312 -86.233)
		(stroke
			(width 0.2)
			(type default)
		)
		(fill no)
		(layer "In4.Cu")
	)
	(gr_circle
		(center 274.4724 -82.296)
		(end 275.3614 -82.296)
		(stroke
			(width 0.2)
			(type default)
		)
		(fill no)
		(layer "In4.Cu")
	)
	(gr_circle
		(center 274.4724 -74.676)
		(end 275.3614 -74.676)
		(stroke
			(width 0.2)
			(type default)
		)
		(fill no)
		(layer "In4.Cu")
	)
	(gr_circle
		(center 274.7772 -86.233)
		(end 275.6662 -86.233)
		(stroke
			(width 0.2)
			(type default)
		)
		(fill no)
		(layer "In4.Cu")
	)
	(gr_circle
		(center 276.0472 -86.233)
		(end 276.9362 -86.233)
		(stroke
			(width 0.2)
			(type default)
		)
		(fill no)
		(layer "In4.Cu")
	)
	(gr_circle
		(center 276.6822 -86.233)
		(end 277.5712 -86.233)
		(stroke
			(width 0.2)
			(type default)
		)
		(fill no)
		(layer "In4.Cu")
	)
	(gr_line
		(start 278.388318 -28.448)
		(end 231.14 -28.448)
		(stroke
			(width 1.016)
			(type default)
		)
		(layer "In4.Cu")
	)
	(gr_line
		(start 279.654 -27.182318)
		(end 278.388318 -28.448)
		(stroke
			(width 1.016)
			(type default)
		)
		(layer "In4.Cu")
	)
	(gr_line
		(start 279.654 -16.146018)
		(end 279.654 -27.182318)
		(stroke
			(width 1.016)
			(type default)
		)
		(layer "In4.Cu")
	)
	(gr_circle
		(center 280.0604 -75.184)
		(end 280.9494 -75.184)
		(stroke
			(width 0.2)
			(type default)
		)
		(fill no)
		(layer "In4.Cu")
	)
	(gr_line
		(start 280.416 -8.636)
		(end 279.654 -8.636)
		(stroke
			(width 1.016)
			(type default)
		)
		(layer "In4.Cu")
	)
	(gr_line
		(start 280.416 -8.636)
		(end 281.051 -8.636)
		(stroke
			(width 1.016)
			(type default)
		)
		(layer "In4.Cu")
	)
	(gr_circle
		(center 282.2194 -76.327)
		(end 283.1084 -76.327)
		(stroke
			(width 0.2)
			(type default)
		)
		(fill no)
		(layer "In4.Cu")
	)
	(gr_line
		(start 282.2956 -58.801)
		(end 293.3954 -58.801)
		(stroke
			(width 1.016)
			(type default)
		)
		(layer "In4.Cu")
	)
	(gr_circle
		(center 282.448 -75.184)
		(end 283.337 -75.184)
		(stroke
			(width 0.2)
			(type default)
		)
		(fill no)
		(layer "In4.Cu")
	)
	(gr_line
		(start 283.354018 -12.446)
		(end 279.654 -16.146018)
		(stroke
			(width 1.016)
			(type default)
		)
		(layer "In4.Cu")
	)
	(gr_line
		(start 283.354018 -12.446)
		(end 313.814206 -12.446)
		(stroke
			(width 1.016)
			(type default)
		)
		(layer "In4.Cu")
	)
	(gr_circle
		(center 284.7594 -76.327)
		(end 285.6484 -76.327)
		(stroke
			(width 0.2)
			(type default)
		)
		(fill no)
		(layer "In4.Cu")
	)
	(gr_circle
		(center 284.7594 -75.184)
		(end 285.6484 -75.184)
		(stroke
			(width 0.2)
			(type default)
		)
		(fill no)
		(layer "In4.Cu")
	)
	(gr_circle
		(center 285.2674 -81.915)
		(end 286.1564 -81.915)
		(stroke
			(width 0.2)
			(type default)
		)
		(fill no)
		(layer "In4.Cu")
	)
	(gr_circle
		(center 285.2674 -81.153)
		(end 286.1564 -81.153)
		(stroke
			(width 0.2)
			(type default)
		)
		(fill no)
		(layer "In4.Cu")
	)
	(gr_circle
		(center 287.0454 -77.514196)
		(end 287.9344 -77.514196)
		(stroke
			(width 0.2)
			(type default)
		)
		(fill no)
		(layer "In4.Cu")
	)
	(gr_circle
		(center 287.14954 -78.16088)
		(end 288.03854 -78.16088)
		(stroke
			(width 0.2)
			(type default)
		)
		(fill no)
		(layer "In4.Cu")
	)
	(gr_circle
		(center 289.9664 -79.461106)
		(end 290.8554 -79.461106)
		(stroke
			(width 0.2)
			(type default)
		)
		(fill no)
		(layer "In4.Cu")
	)
	(gr_circle
		(center 289.9664 -77.510894)
		(end 290.8554 -77.510894)
		(stroke
			(width 0.2)
			(type default)
		)
		(fill no)
		(layer "In4.Cu")
	)
	(gr_circle
		(center 290.3474 -81.915)
		(end 291.2364 -81.915)
		(stroke
			(width 0.2)
			(type default)
		)
		(fill no)
		(layer "In4.Cu")
	)
	(gr_circle
		(center 290.3474 -81.28)
		(end 291.2364 -81.28)
		(stroke
			(width 0.2)
			(type default)
		)
		(fill no)
		(layer "In4.Cu")
	)
	(gr_circle
		(center 291.338 -86.995)
		(end 292.227 -86.995)
		(stroke
			(width 0.2)
			(type default)
		)
		(fill no)
		(layer "In4.Cu")
	)
	(gr_circle
		(center 292.989 -86.995)
		(end 293.878 -86.995)
		(stroke
			(width 0.2)
			(type default)
		)
		(fill no)
		(layer "In4.Cu")
	)
	(gr_circle
		(center 293.2684 -81.5467)
		(end 294.1574 -81.5467)
		(stroke
			(width 0.2)
			(type default)
		)
		(fill no)
		(layer "In4.Cu")
	)
	(gr_line
		(start 293.3954 -58.801)
		(end 296.545 -61.9506)
		(stroke
			(width 1.016)
			(type default)
		)
		(layer "In4.Cu")
	)
	(gr_circle
		(center 293.913052 -76.962)
		(end 294.802052 -76.962)
		(stroke
			(width 0.2)
			(type default)
		)
		(fill no)
		(layer "In4.Cu")
	)
	(gr_circle
		(center 294.0812 -79.2607)
		(end 294.9702 -79.2607)
		(stroke
			(width 0.2)
			(type default)
		)
		(fill no)
		(layer "In4.Cu")
	)
	(gr_circle
		(center 295.25595 -86.487)
		(end 296.14495 -86.487)
		(stroke
			(width 0.2)
			(type default)
		)
		(fill no)
		(layer "In4.Cu")
	)
	(gr_circle
		(center 296.05605 -86.487)
		(end 296.94505 -86.487)
		(stroke
			(width 0.2)
			(type default)
		)
		(fill no)
		(layer "In4.Cu")
	)
	(gr_line
		(start 296.545 -65.532)
		(end 298.35729 -67.34429)
		(stroke
			(width 1.016)
			(type default)
		)
		(layer "In4.Cu")
	)
	(gr_line
		(start 296.545 -61.9506)
		(end 296.545 -65.532)
		(stroke
			(width 1.016)
			(type default)
		)
		(layer "In4.Cu")
	)
	(gr_line
		(start 298.35729 -67.34429)
		(end 309.808372 -67.34429)
		(stroke
			(width 1.016)
			(type default)
		)
		(layer "In4.Cu")
	)
	(gr_line
		(start 299.168312 -38.996112)
		(end 300.6852 -40.513)
		(stroke
			(width 1.016)
			(type default)
		)
		(layer "In4.Cu")
	)
	(gr_line
		(start 299.168312 -33.576768)
		(end 299.168312 -38.996112)
		(stroke
			(width 1.016)
			(type default)
		)
		(layer "In4.Cu")
	)
	(gr_line
		(start 299.265086 -33.479994)
		(end 299.168312 -33.576768)
		(stroke
			(width 1.016)
			(type default)
		)
		(layer "In4.Cu")
	)
	(gr_line
		(start 300.446694 -34.461958)
		(end 300.126654 -34.781998)
		(stroke
			(width 2.54)
			(type default)
		)
		(layer "In4.Cu")
	)
	(gr_line
		(start 300.6852 -40.513)
		(end 303.4792 -40.513)
		(stroke
			(width 1.016)
			(type default)
		)
		(layer "In4.Cu")
	)
	(gr_line
		(start 302.078136 -36.06165)
		(end 301.822104 -36.317682)
		(stroke
			(width 2.54)
			(type default)
		)
		(layer "In4.Cu")
	)
	(gr_line
		(start 303.101756 -37.821108)
		(end 303.069752 -37.853112)
		(stroke
			(width 2.54)
			(type default)
		)
		(layer "In4.Cu")
	)
	(gr_line
		(start 303.391316 -40.2844)
		(end 305.5366 -40.2844)
		(stroke
			(width 1.016)
			(type default)
		)
		(layer "In4.Cu")
	)
	(gr_line
		(start 303.4792 -40.513)
		(end 304.8 -41.8338)
		(stroke
			(width 1.016)
			(type default)
		)
		(layer "In4.Cu")
	)
	(gr_line
		(start 304.038 -12.446)
		(end 304.8 -13.208)
		(stroke
			(width 1.016)
			(type default)
		)
		(layer "In4.Cu")
	)
	(gr_circle
		(center 304.070258 -79.823056)
		(end 304.959258 -79.823056)
		(stroke
			(width 0.2)
			(type default)
		)
		(fill no)
		(layer "In4.Cu")
	)
	(gr_line
		(start 304.546 -39.053516)
		(end 304.546 -41.1988)
		(stroke
			(width 1.016)
			(type default)
		)
		(layer "In4.Cu")
	)
	(gr_line
		(start 304.779934 -32.938466)
		(end 303.7586 -33.9598)
		(stroke
			(width 1.016)
			(type default)
		)
		(layer "In4.Cu")
	)
	(gr_line
		(start 304.794666 -32.938466)
		(end 305.816 -33.9598)
		(stroke
			(width 1.016)
			(type default)
		)
		(layer "In4.Cu")
	)
	(gr_line
		(start 304.8 -67.065144)
		(end 305.079146 -67.34429)
		(stroke
			(width 1.016)
			(type default)
		)
		(layer "In4.Cu")
	)
	(gr_line
		(start 304.8 -33.909)
		(end 304.8 -67.065144)
		(stroke
			(width 1.016)
			(type default)
		)
		(layer "In4.Cu")
	)
	(gr_line
		(start 304.8 -33.479994)
		(end 299.265086 -33.479994)
		(stroke
			(width 1.016)
			(type default)
		)
		(layer "In4.Cu")
	)
	(gr_line
		(start 304.8 -33.479994)
		(end 309.723028 -33.479994)
		(stroke
			(width 1.016)
			(type default)
		)
		(layer "In4.Cu")
	)
	(gr_line
		(start 304.8 -13.208)
		(end 304.8 -33.479994)
		(stroke
			(width 1.016)
			(type default)
		)
		(layer "In4.Cu")
	)
	(gr_circle
		(center 305.063398 -81.003648)
		(end 305.952398 -81.003648)
		(stroke
			(width 0.2)
			(type default)
		)
		(fill no)
		(layer "In4.Cu")
	)
	(gr_line
		(start 305.562 -12.446)
		(end 304.8 -13.208)
		(stroke
			(width 1.016)
			(type default)
		)
		(layer "In4.Cu")
	)
	(gr_line
		(start 305.6128 -40.513)
		(end 304.8 -41.3258)
		(stroke
			(width 1.016)
			(type default)
		)
		(layer "In4.Cu")
	)
	(gr_line
		(start 305.6636 -46.2534)
		(end 304.8508 -45.4406)
		(stroke
			(width 1.016)
			(type default)
		)
		(layer "In4.Cu")
	)
	(gr_line
		(start 306.076858 -37.821108)
		(end 303.101756 -37.821108)
		(stroke
			(width 2.54)
			(type default)
		)
		(layer "In4.Cu")
	)
	(gr_line
		(start 306.17287 -37.91712)
		(end 306.076858 -37.821108)
		(stroke
			(width 2.54)
			(type default)
		)
		(layer "In4.Cu")
	)
	(gr_line
		(start 307.388514 -36.06165)
		(end 302.078136 -36.06165)
		(stroke
			(width 2.54)
			(type default)
		)
		(layer "In4.Cu")
	)
	(gr_line
		(start 307.836316 -36.509452)
		(end 307.388514 -36.06165)
		(stroke
			(width 2.54)
			(type default)
		)
		(layer "In4.Cu")
	)
	(gr_line
		(start 308.3052 -37.5412)
		(end 300.083728 -37.5412)
		(stroke
			(width 2.54)
			(type default)
		)
		(layer "In4.Cu")
	)
	(gr_line
		(start 308.3306 -36.068)
		(end 300.109128 -36.068)
		(stroke
			(width 2.54)
			(type default)
		)
		(layer "In4.Cu")
	)
	(gr_line
		(start 308.5592 -38.7858)
		(end 300.337728 -38.7858)
		(stroke
			(width 2.54)
			(type default)
		)
		(layer "In4.Cu")
	)
	(gr_line
		(start 308.668166 -34.461958)
		(end 300.446694 -34.461958)
		(stroke
			(width 2.54)
			(type default)
		)
		(layer "In4.Cu")
	)
	(gr_line
		(start 309.1688 -39.2938)
		(end 300.947328 -39.2938)
		(stroke
			(width 2.54)
			(type default)
		)
		(layer "In4.Cu")
	)
	(gr_line
		(start 309.2704 -40.513)
		(end 305.6128 -40.513)
		(stroke
			(width 1.016)
			(type default)
		)
		(layer "In4.Cu")
	)
	(gr_line
		(start 309.448962 -34.323528)
		(end 309.448962 -38.861238)
		(stroke
			(width 1.016)
			(type default)
		)
		(layer "In4.Cu")
	)
	(gr_line
		(start 309.627778 -35.42157)
		(end 308.668166 -34.461958)
		(stroke
			(width 2.54)
			(type default)
		)
		(layer "In4.Cu")
	)
	(gr_line
		(start 309.723028 -33.479994)
		(end 310.744362 -34.501328)
		(stroke
			(width 1.016)
			(type default)
		)
		(layer "In4.Cu")
	)
	(gr_line
		(start 309.804562 -34.425128)
		(end 309.804562 -38.962838)
		(stroke
			(width 1.016)
			(type default)
		)
		(layer "In4.Cu")
	)
	(gr_line
		(start 309.808372 -67.34429)
		(end 310.72201 -68.257928)
		(stroke
			(width 1.016)
			(type default)
		)
		(layer "In4.Cu")
	)
	(gr_line
		(start 310.236362 -34.501328)
		(end 310.236362 -39.039038)
		(stroke
			(width 1.016)
			(type default)
		)
		(layer "In4.Cu")
	)
	(gr_line
		(start 310.72201 -79.844646)
		(end 311.395364 -80.518)
		(stroke
			(width 1.016)
			(type default)
		)
		(layer "In4.Cu")
	)
	(gr_line
		(start 310.72201 -68.257928)
		(end 310.72201 -79.844646)
		(stroke
			(width 1.016)
			(type default)
		)
		(layer "In4.Cu")
	)
	(gr_line
		(start 310.744362 -39.039038)
		(end 309.2704 -40.513)
		(stroke
			(width 1.016)
			(type default)
		)
		(layer "In4.Cu")
	)
	(gr_line
		(start 310.744362 -34.501328)
		(end 310.744362 -39.039038)
		(stroke
			(width 1.016)
			(type default)
		)
		(layer "In4.Cu")
	)
	(gr_line
		(start 311.395364 -80.518)
		(end 323.977 -80.518)
		(stroke
			(width 1.016)
			(type default)
		)
		(layer "In4.Cu")
	)
	(gr_line
		(start 313.814206 -12.446)
		(end 323.977 -12.446)
		(stroke
			(width 1.016)
			(type default)
		)
		(layer "In4.Cu")
	)
	(gr_line
		(start 314.073286 -12.446)
		(end 313.814206 -12.446)
		(stroke
			(width 1.016)
			(type default)
		)
		(layer "In4.Cu")
	)
	(gr_circle
		(center 316.197996 -83.82)
		(end 317.086996 -83.82)
		(stroke
			(width 0.2)
			(type default)
		)
		(fill no)
		(layer "In4.Cu")
	)
	(gr_circle
		(center 319.01765 -85.598)
		(end 319.90665 -85.598)
		(stroke
			(width 0.2)
			(type default)
		)
		(fill no)
		(layer "In4.Cu")
	)
	(gr_circle
		(center 319.01765 -83.82)
		(end 319.90665 -83.82)
		(stroke
			(width 0.2)
			(type default)
		)
		(fill no)
		(layer "In4.Cu")
	)
	(gr_line
		(start 323.142356 -8.636)
		(end 281.051 -8.636)
		(stroke
			(width 1.016)
			(type default)
		)
		(layer "In4.Cu")
	)
	(gr_line
		(start 323.977 -80.518)
		(end 324.612 -79.883)
		(stroke
			(width 1.016)
			(type default)
		)
		(layer "In4.Cu")
	)
	(gr_line
		(start 324.104 -46.355)
		(end 305.010058 -46.355)
		(stroke
			(width 1.016)
			(type default)
		)
		(layer "In4.Cu")
	)
	(gr_line
		(start 324.104 -46.355)
		(end 324.612 -45.847)
		(stroke
			(width 1.016)
			(type default)
		)
		(layer "In4.Cu")
	)
	(gr_line
		(start 324.612 -79.883)
		(end 324.612 -46.863)
		(stroke
			(width 1.016)
			(type default)
		)
		(layer "In4.Cu")
	)
	(gr_line
		(start 324.612 -46.863)
		(end 324.104 -46.355)
		(stroke
			(width 1.016)
			(type default)
		)
		(layer "In4.Cu")
	)
	(gr_line
		(start 324.612 -46.863)
		(end 324.612 -10.105644)
		(stroke
			(width 1.016)
			(type default)
		)
		(layer "In4.Cu")
	)
	(gr_line
		(start 324.612 -13.081)
		(end 323.977 -12.446)
		(stroke
			(width 1.016)
			(type default)
		)
		(layer "In4.Cu")
	)
	(gr_line
		(start 324.612 -10.105644)
		(end 323.142356 -8.636)
		(stroke
			(width 1.016)
			(type default)
		)
		(layer "In4.Cu")
	)
	(gr_line
		(start 324.612 -10.105644)
		(end 324.612 -10.030206)
		(stroke
			(width 1.016)
			(type default)
		)
		(layer "In4.Cu")
	)
	(gr_line
		(start 328.9808 -102.99827)
		(end 328.9808 -88.643206)
		(stroke
			(width 1.016)
			(type default)
		)
		(layer "In4.Cu")
	)
	(gr_line
		(start 328.9808 -102.99827)
		(end 328.982578 -103.000048)
		(stroke
			(width 1.016)
			(type default)
		)
		(layer "In4.Cu")
	)
	(gr_line
		(start 328.9808 -88.643206)
		(end 263.66343 -88.643206)
		(stroke
			(width 1.016)
			(type default)
		)
		(layer "In4.Cu")
	)
	(gr_line
		(start 330.101956 -15.5956)
		(end 324.612 -10.105644)
		(stroke
			(width 1.016)
			(type default)
		)
		(layer "In4.Cu")
	)
	(gr_circle
		(center 332.070964 -9.774428)
		(end 332.959964 -9.774428)
		(stroke
			(width 0.2)
			(type default)
		)
		(fill no)
		(layer "In4.Cu")
	)
	(gr_circle
		(center 332.832964 -9.774428)
		(end 333.721964 -9.774428)
		(stroke
			(width 0.2)
			(type default)
		)
		(fill no)
		(layer "In4.Cu")
	)
	(gr_circle
		(center 333.594964 -9.774428)
		(end 334.483964 -9.774428)
		(stroke
			(width 0.2)
			(type default)
		)
		(fill no)
		(layer "In4.Cu")
	)
	(gr_circle
		(center 334.356964 -9.774428)
		(end 335.245964 -9.774428)
		(stroke
			(width 0.2)
			(type default)
		)
		(fill no)
		(layer "In4.Cu")
	)
	(gr_circle
		(center 335.367884 -73.6346)
		(end 336.256884 -73.6346)
		(stroke
			(width 0.2)
			(type default)
		)
		(fill no)
		(layer "In4.Cu")
	)
	(gr_circle
		(center 335.367884 -62.357)
		(end 336.256884 -62.357)
		(stroke
			(width 0.2)
			(type default)
		)
		(fill no)
		(layer "In4.Cu")
	)
	(gr_circle
		(center 335.367884 -51.0794)
		(end 336.256884 -51.0794)
		(stroke
			(width 0.2)
			(type default)
		)
		(fill no)
		(layer "In4.Cu")
	)
	(gr_circle
		(center 335.367884 -39.8018)
		(end 336.256884 -39.8018)
		(stroke
			(width 0.2)
			(type default)
		)
		(fill no)
		(layer "In4.Cu")
	)
	(gr_circle
		(center 335.367884 -28.5242)
		(end 336.256884 -28.5242)
		(stroke
			(width 0.2)
			(type default)
		)
		(fill no)
		(layer "In4.Cu")
	)
	(gr_circle
		(center 335.367884 -17.2466)
		(end 336.256884 -17.2466)
		(stroke
			(width 0.2)
			(type default)
		)
		(fill no)
		(layer "In4.Cu")
	)
	(gr_circle
		(center 336.3214 -49.5046)
		(end 337.2104 -49.5046)
		(stroke
			(width 0.2)
			(type default)
		)
		(fill no)
		(layer "In4.Cu")
	)
	(gr_circle
		(center 336.3214 -38.227)
		(end 337.2104 -38.227)
		(stroke
			(width 0.2)
			(type default)
		)
		(fill no)
		(layer "In4.Cu")
	)
	(gr_circle
		(center 338.498434 -48.423576)
		(end 339.387434 -48.423576)
		(stroke
			(width 0.2)
			(type default)
		)
		(fill no)
		(layer "In4.Cu")
	)
	(gr_circle
		(center 338.87156 -37.247068)
		(end 339.76056 -37.247068)
		(stroke
			(width 0.2)
			(type default)
		)
		(fill no)
		(layer "In4.Cu")
	)
	(gr_circle
		(center 342.72474 -9.878822)
		(end 343.61374 -9.878822)
		(stroke
			(width 0.2)
			(type default)
		)
		(fill no)
		(layer "In4.Cu")
	)
	(gr_circle
		(center 343.48674 -9.878822)
		(end 344.37574 -9.878822)
		(stroke
			(width 0.2)
			(type default)
		)
		(fill no)
		(layer "In4.Cu")
	)
	(gr_line
		(start 344.000074 -103.000048)
		(end 96.000062 -103.000048)
		(stroke
			(width 2.032)
			(type default)
		)
		(layer "In4.Cu")
	)
	(gr_line
		(start 344.000074 -103.000048)
		(end 264.668 -103.000048)
		(stroke
			(width 2.032)
			(type default)
		)
		(layer "In4.Cu")
	)
	(gr_circle
		(center 344.17 -51.9176)
		(end 345.059 -51.9176)
		(stroke
			(width 0.2)
			(type default)
		)
		(fill no)
		(layer "In4.Cu")
	)
	(gr_circle
		(center 344.1954 -40.64)
		(end 345.0844 -40.64)
		(stroke
			(width 0.2)
			(type default)
		)
		(fill no)
		(layer "In4.Cu")
	)
	(gr_circle
		(center 344.24874 -9.878822)
		(end 345.13774 -9.878822)
		(stroke
			(width 0.2)
			(type default)
		)
		(fill no)
		(layer "In4.Cu")
	)
	(gr_circle
		(center 345.01074 -9.878822)
		(end 345.89974 -9.878822)
		(stroke
			(width 0.2)
			(type default)
		)
		(fill no)
		(layer "In4.Cu")
	)
	(gr_line
		(start 351.499932 -153.299922)
		(end 351.499932 -110.499906)
		(stroke
			(width 2.032)
			(type default)
		)
		(layer "In4.Cu")
	)
	(gr_arc
		(start 351.499932 -153.299922)
		(mid 352.964404 -156.835427)
		(end 356.499922 -158.299912)
		(stroke
			(width 2.032)
			(type default)
		)
		(layer "In4.Cu")
	)
	(gr_arc
		(start 351.499932 -110.499906)
		(mid 349.303274 -105.196706)
		(end 344.000074 -103.000048)
		(stroke
			(width 2.032)
			(type default)
		)
		(layer "In4.Cu")
	)
	(gr_line
		(start 353.8982 -15.5956)
		(end 330.101956 -15.5956)
		(stroke
			(width 1.016)
			(type default)
		)
		(layer "In4.Cu")
	)
	(gr_line
		(start 357.000048 -158.299912)
		(end 356.499922 -158.299912)
		(stroke
			(width 2.032)
			(type default)
		)
		(layer "In4.Cu")
	)
	(gr_circle
		(center 359.74274 -10.282174)
		(end 360.63174 -10.282174)
		(stroke
			(width 0.2)
			(type default)
		)
		(fill no)
		(layer "In4.Cu")
	)
	(gr_line
		(start 360.000042 -166.649908)
		(end 360.000042 -161.299906)
		(stroke
			(width 2.032)
			(type default)
		)
		(layer "In4.Cu")
	)
	(gr_arc
		(start 360.000042 -166.649908)
		(mid 361.46451 -170.185418)
		(end 365.000032 -171.649898)
		(stroke
			(width 2.032)
			(type default)
		)
		(layer "In4.Cu")
	)
	(gr_arc
		(start 360.000042 -161.299906)
		(mid 359.121364 -159.17859)
		(end 357.000048 -158.299912)
		(stroke
			(width 2.032)
			(type default)
		)
		(layer "In4.Cu")
	)
	(gr_circle
		(center 360.50474 -10.282174)
		(end 361.39374 -10.282174)
		(stroke
			(width 0.2)
			(type default)
		)
		(fill no)
		(layer "In4.Cu")
	)
	(gr_circle
		(center 361.26674 -10.282174)
		(end 362.15574 -10.282174)
		(stroke
			(width 0.2)
			(type default)
		)
		(fill no)
		(layer "In4.Cu")
	)
	(gr_circle
		(center 362.02874 -10.282174)
		(end 362.91774 -10.282174)
		(stroke
			(width 0.2)
			(type default)
		)
		(fill no)
		(layer "In4.Cu")
	)
	(gr_circle
		(center 363.000036 -168.82999)
		(end 364.21314 -168.82999)
		(stroke
			(width 0.2)
			(type default)
		)
		(fill no)
		(layer "In4.Cu")
	)
	(gr_circle
		(center 363.000036 -166.829994)
		(end 364.21314 -166.829994)
		(stroke
			(width 0.2)
			(type default)
		)
		(fill no)
		(layer "In4.Cu")
	)
	(gr_circle
		(center 363.000036 -164.829998)
		(end 364.21314 -164.829998)
		(stroke
			(width 0.2)
			(type default)
		)
		(fill no)
		(layer "In4.Cu")
	)
	(gr_circle
		(center 363.984032 -167.718994)
		(end 365.197136 -167.718994)
		(stroke
			(width 0.2)
			(type default)
		)
		(fill no)
		(layer "In4.Cu")
	)
	(gr_circle
		(center 363.984032 -165.718998)
		(end 365.197136 -165.718998)
		(stroke
			(width 0.2)
			(type default)
		)
		(fill no)
		(layer "In4.Cu")
	)
	(gr_circle
		(center 365.000032 -168.82999)
		(end 366.213136 -168.82999)
		(stroke
			(width 0.2)
			(type default)
		)
		(fill no)
		(layer "In4.Cu")
	)
	(gr_circle
		(center 365.000032 -166.829994)
		(end 366.213136 -166.829994)
		(stroke
			(width 0.2)
			(type default)
		)
		(fill no)
		(layer "In4.Cu")
	)
	(gr_circle
		(center 365.000032 -164.829998)
		(end 366.213136 -164.829998)
		(stroke
			(width 0.2)
			(type default)
		)
		(fill no)
		(layer "In4.Cu")
	)
	(gr_circle
		(center 366.119918 -5.290058)
		(end 367.333022 -5.290058)
		(stroke
			(width 0.2)
			(type default)
		)
		(fill no)
		(layer "In4.Cu")
	)
	(gr_circle
		(center 368.659918 -5.290058)
		(end 369.873022 -5.290058)
		(stroke
			(width 0.2)
			(type default)
		)
		(fill no)
		(layer "In4.Cu")
	)
	(gr_circle
		(center 369.000024 -168.82999)
		(end 370.213128 -168.82999)
		(stroke
			(width 0.2)
			(type default)
		)
		(fill no)
		(layer "In4.Cu")
	)
	(gr_circle
		(center 369.000024 -166.829994)
		(end 370.213128 -166.829994)
		(stroke
			(width 0.2)
			(type default)
		)
		(fill no)
		(layer "In4.Cu")
	)
	(gr_circle
		(center 369.000024 -164.829998)
		(end 370.213128 -164.829998)
		(stroke
			(width 0.2)
			(type default)
		)
		(fill no)
		(layer "In4.Cu")
	)
	(gr_circle
		(center 369.953032 -167.591994)
		(end 371.166136 -167.591994)
		(stroke
			(width 0.2)
			(type default)
		)
		(fill no)
		(layer "In4.Cu")
	)
	(gr_circle
		(center 369.953032 -165.591998)
		(end 371.166136 -165.591998)
		(stroke
			(width 0.2)
			(type default)
		)
		(fill no)
		(layer "In4.Cu")
	)
	(gr_line
		(start 370.3066 -32.004)
		(end 353.8982 -15.5956)
		(stroke
			(width 1.016)
			(type default)
		)
		(layer "In4.Cu")
	)
	(gr_circle
		(center 371.00002 -168.82999)
		(end 372.213124 -168.82999)
		(stroke
			(width 0.2)
			(type default)
		)
		(fill no)
		(layer "In4.Cu")
	)
	(gr_circle
		(center 371.00002 -166.829994)
		(end 372.213124 -166.829994)
		(stroke
			(width 0.2)
			(type default)
		)
		(fill no)
		(layer "In4.Cu")
	)
	(gr_circle
		(center 371.00002 -164.829998)
		(end 372.213124 -164.829998)
		(stroke
			(width 0.2)
			(type default)
		)
		(fill no)
		(layer "In4.Cu")
	)
	(gr_circle
		(center 372.160038 -4.575048)
		(end 373.373142 -4.575048)
		(stroke
			(width 0.2)
			(type default)
		)
		(fill no)
		(layer "In4.Cu")
	)
	(gr_circle
		(center 372.160038 -2.035048)
		(end 373.373142 -2.035048)
		(stroke
			(width 0.2)
			(type default)
		)
		(fill no)
		(layer "In4.Cu")
	)
	(gr_circle
		(center 373.430038 -5.845048)
		(end 374.643142 -5.845048)
		(stroke
			(width 0.2)
			(type default)
		)
		(fill no)
		(layer "In4.Cu")
	)
	(gr_circle
		(center 373.430038 -3.305048)
		(end 374.643142 -3.305048)
		(stroke
			(width 0.2)
			(type default)
		)
		(fill no)
		(layer "In4.Cu")
	)
	(gr_circle
		(center 373.430038 -1.527048)
		(end 374.643142 -1.527048)
		(stroke
			(width 0.2)
			(type default)
		)
		(fill no)
		(layer "In4.Cu")
	)
	(gr_circle
		(center 373.811038 -4.575048)
		(end 375.024142 -4.575048)
		(stroke
			(width 0.2)
			(type default)
		)
		(fill no)
		(layer "In4.Cu")
	)
	(gr_circle
		(center 374.700038 -4.575048)
		(end 375.913142 -4.575048)
		(stroke
			(width 0.2)
			(type default)
		)
		(fill no)
		(layer "In4.Cu")
	)
	(gr_circle
		(center 374.700038 -2.035048)
		(end 375.913142 -2.035048)
		(stroke
			(width 0.2)
			(type default)
		)
		(fill no)
		(layer "In4.Cu")
	)
	(gr_circle
		(center 374.954038 -3.305048)
		(end 376.167142 -3.305048)
		(stroke
			(width 0.2)
			(type default)
		)
		(fill no)
		(layer "In4.Cu")
	)
	(gr_circle
		(center 375.000012 -168.82999)
		(end 376.213116 -168.82999)
		(stroke
			(width 0.2)
			(type default)
		)
		(fill no)
		(layer "In4.Cu")
	)
	(gr_circle
		(center 375.000012 -166.829994)
		(end 376.213116 -166.829994)
		(stroke
			(width 0.2)
			(type default)
		)
		(fill no)
		(layer "In4.Cu")
	)
	(gr_circle
		(center 375.000012 -164.829998)
		(end 376.213116 -164.829998)
		(stroke
			(width 0.2)
			(type default)
		)
		(fill no)
		(layer "In4.Cu")
	)
	(gr_circle
		(center 375.843038 -1.527048)
		(end 377.056142 -1.527048)
		(stroke
			(width 0.2)
			(type default)
		)
		(fill no)
		(layer "In4.Cu")
	)
	(gr_circle
		(center 375.970038 -5.845048)
		(end 377.183142 -5.845048)
		(stroke
			(width 0.2)
			(type default)
		)
		(fill no)
		(layer "In4.Cu")
	)
	(gr_circle
		(center 375.970038 -3.305048)
		(end 377.183142 -3.305048)
		(stroke
			(width 0.2)
			(type default)
		)
		(fill no)
		(layer "In4.Cu")
	)
	(gr_circle
		(center 376.049032 -167.591994)
		(end 377.262136 -167.591994)
		(stroke
			(width 0.2)
			(type default)
		)
		(fill no)
		(layer "In4.Cu")
	)
	(gr_circle
		(center 376.049032 -165.591998)
		(end 377.262136 -165.591998)
		(stroke
			(width 0.2)
			(type default)
		)
		(fill no)
		(layer "In4.Cu")
	)
	(gr_circle
		(center 377.000008 -168.82999)
		(end 378.213112 -168.82999)
		(stroke
			(width 0.2)
			(type default)
		)
		(fill no)
		(layer "In4.Cu")
	)
	(gr_circle
		(center 377.000008 -166.829994)
		(end 378.213112 -166.829994)
		(stroke
			(width 0.2)
			(type default)
		)
		(fill no)
		(layer "In4.Cu")
	)
	(gr_circle
		(center 377.000008 -164.829998)
		(end 378.213112 -164.829998)
		(stroke
			(width 0.2)
			(type default)
		)
		(fill no)
		(layer "In4.Cu")
	)
	(gr_circle
		(center 377.240038 -1.654048)
		(end 378.453142 -1.654048)
		(stroke
			(width 0.2)
			(type default)
		)
		(fill no)
		(layer "In4.Cu")
	)
	(gr_circle
		(center 378.079 -132.199888)
		(end 379.603 -132.199888)
		(stroke
			(width 0.2)
			(type default)
		)
		(fill no)
		(layer "In4.Cu")
	)
	(gr_circle
		(center 378.079 -111.879888)
		(end 379.603 -111.879888)
		(stroke
			(width 0.2)
			(type default)
		)
		(fill no)
		(layer "In4.Cu")
	)
	(gr_circle
		(center 378.079 -91.559888)
		(end 379.603 -91.559888)
		(stroke
			(width 0.2)
			(type default)
		)
		(fill no)
		(layer "In4.Cu")
	)
	(gr_circle
		(center 378.079 -71.239888)
		(end 379.603 -71.239888)
		(stroke
			(width 0.2)
			(type default)
		)
		(fill no)
		(layer "In4.Cu")
	)
	(gr_circle
		(center 378.079 -50.919888)
		(end 379.603 -50.919888)
		(stroke
			(width 0.2)
			(type default)
		)
		(fill no)
		(layer "In4.Cu")
	)
	(gr_circle
		(center 378.46 -21.336)
		(end 379.349 -21.336)
		(stroke
			(width 0.2)
			(type default)
		)
		(fill no)
		(layer "In4.Cu")
	)
	(gr_circle
		(center 378.46 -20.447)
		(end 379.349 -20.447)
		(stroke
			(width 0.2)
			(type default)
		)
		(fill no)
		(layer "In4.Cu")
	)
	(gr_circle
		(center 378.517912 -16.891)
		(end 379.406912 -16.891)
		(stroke
			(width 0.2)
			(type default)
		)
		(fill no)
		(layer "In4.Cu")
	)
	(gr_circle
		(center 379.660912 -21.209)
		(end 380.549912 -21.209)
		(stroke
			(width 0.2)
			(type default)
		)
		(fill no)
		(layer "In4.Cu")
	)
	(gr_circle
		(center 379.660912 -16.891)
		(end 380.549912 -16.891)
		(stroke
			(width 0.2)
			(type default)
		)
		(fill no)
		(layer "In4.Cu")
	)
	(gr_circle
		(center 380.53772 -16.129)
		(end 381.42672 -16.129)
		(stroke
			(width 0.2)
			(type default)
		)
		(fill no)
		(layer "In4.Cu")
	)
	(gr_circle
		(center 380.803912 -18.923)
		(end 381.692912 -18.923)
		(stroke
			(width 0.2)
			(type default)
		)
		(fill no)
		(layer "In4.Cu")
	)
	(gr_circle
		(center 381.946912 -18.917158)
		(end 382.835912 -18.917158)
		(stroke
			(width 0.2)
			(type default)
		)
		(fill no)
		(layer "In4.Cu")
	)
	(gr_circle
		(center 382.2954 -16.383)
		(end 383.1844 -16.383)
		(stroke
			(width 0.2)
			(type default)
		)
		(fill no)
		(layer "In4.Cu")
	)
	(gr_circle
		(center 383.199894 -168.82999)
		(end 384.412998 -168.82999)
		(stroke
			(width 0.2)
			(type default)
		)
		(fill no)
		(layer "In4.Cu")
	)
	(gr_circle
		(center 383.199894 -166.829994)
		(end 384.412998 -166.829994)
		(stroke
			(width 0.2)
			(type default)
		)
		(fill no)
		(layer "In4.Cu")
	)
	(gr_circle
		(center 383.199894 -164.829998)
		(end 384.412998 -164.829998)
		(stroke
			(width 0.2)
			(type default)
		)
		(fill no)
		(layer "In4.Cu")
	)
	(gr_circle
		(center 384.177032 -167.845994)
		(end 385.390136 -167.845994)
		(stroke
			(width 0.2)
			(type default)
		)
		(fill no)
		(layer "In4.Cu")
	)
	(gr_circle
		(center 384.177032 -165.845998)
		(end 385.390136 -165.845998)
		(stroke
			(width 0.2)
			(type default)
		)
		(fill no)
		(layer "In4.Cu")
	)
	(gr_circle
		(center 385.19989 -168.82999)
		(end 386.412994 -168.82999)
		(stroke
			(width 0.2)
			(type default)
		)
		(fill no)
		(layer "In4.Cu")
	)
	(gr_circle
		(center 385.19989 -166.829994)
		(end 386.412994 -166.829994)
		(stroke
			(width 0.2)
			(type default)
		)
		(fill no)
		(layer "In4.Cu")
	)
	(gr_circle
		(center 385.19989 -164.829998)
		(end 386.412994 -164.829998)
		(stroke
			(width 0.2)
			(type default)
		)
		(fill no)
		(layer "In4.Cu")
	)
	(gr_circle
		(center 387.2484 -28.321)
		(end 388.1374 -28.321)
		(stroke
			(width 0.2)
			(type default)
		)
		(fill no)
		(layer "In4.Cu")
	)
	(gr_circle
		(center 387.8834 -27.559)
		(end 388.7724 -27.559)
		(stroke
			(width 0.2)
			(type default)
		)
		(fill no)
		(layer "In4.Cu")
	)
	(gr_circle
		(center 387.8834 -25.12695)
		(end 388.7724 -25.12695)
		(stroke
			(width 0.2)
			(type default)
		)
		(fill no)
		(layer "In4.Cu")
	)
	(gr_circle
		(center 389.0264 -24.623014)
		(end 389.9154 -24.623014)
		(stroke
			(width 0.2)
			(type default)
		)
		(fill no)
		(layer "In4.Cu")
	)
	(gr_circle
		(center 389.199882 -168.82999)
		(end 390.412986 -168.82999)
		(stroke
			(width 0.2)
			(type default)
		)
		(fill no)
		(layer "In4.Cu")
	)
	(gr_circle
		(center 389.199882 -166.829994)
		(end 390.412986 -166.829994)
		(stroke
			(width 0.2)
			(type default)
		)
		(fill no)
		(layer "In4.Cu")
	)
	(gr_circle
		(center 389.199882 -164.829998)
		(end 390.412986 -164.829998)
		(stroke
			(width 0.2)
			(type default)
		)
		(fill no)
		(layer "In4.Cu")
	)
	(gr_line
		(start 389.471154 -32.004)
		(end 370.3066 -32.004)
		(stroke
			(width 1.016)
			(type default)
		)
		(layer "In4.Cu")
	)
	(gr_line
		(start 389.560308 -32.004)
		(end 389.471154 -32.004)
		(stroke
			(width 1.016)
			(type default)
		)
		(layer "In4.Cu")
	)
	(gr_circle
		(center 390.273032 -167.718994)
		(end 391.486136 -167.718994)
		(stroke
			(width 0.2)
			(type default)
		)
		(fill no)
		(layer "In4.Cu")
	)
	(gr_circle
		(center 390.273032 -165.718998)
		(end 391.486136 -165.718998)
		(stroke
			(width 0.2)
			(type default)
		)
		(fill no)
		(layer "In4.Cu")
	)
	(gr_circle
		(center 391.199878 -168.82999)
		(end 392.412982 -168.82999)
		(stroke
			(width 0.2)
			(type default)
		)
		(fill no)
		(layer "In4.Cu")
	)
	(gr_circle
		(center 391.199878 -166.829994)
		(end 392.412982 -166.829994)
		(stroke
			(width 0.2)
			(type default)
		)
		(fill no)
		(layer "In4.Cu")
	)
	(gr_circle
		(center 391.199878 -164.829998)
		(end 392.412982 -164.829998)
		(stroke
			(width 0.2)
			(type default)
		)
		(fill no)
		(layer "In4.Cu")
	)
	(gr_circle
		(center 393.954 -24.511)
		(end 394.843 -24.511)
		(stroke
			(width 0.2)
			(type default)
		)
		(fill no)
		(layer "In4.Cu")
	)
	(gr_circle
		(center 397.637 -132.199888)
		(end 399.161 -132.199888)
		(stroke
			(width 0.2)
			(type default)
		)
		(fill no)
		(layer "In4.Cu")
	)
	(gr_circle
		(center 397.637 -111.879888)
		(end 399.161 -111.879888)
		(stroke
			(width 0.2)
			(type default)
		)
		(fill no)
		(layer "In4.Cu")
	)
	(gr_circle
		(center 397.637 -91.559888)
		(end 399.161 -91.559888)
		(stroke
			(width 0.2)
			(type default)
		)
		(fill no)
		(layer "In4.Cu")
	)
	(gr_circle
		(center 397.637 -71.239888)
		(end 399.161 -71.239888)
		(stroke
			(width 0.2)
			(type default)
		)
		(fill no)
		(layer "In4.Cu")
	)
	(gr_circle
		(center 397.637 -50.919888)
		(end 399.161 -50.919888)
		(stroke
			(width 0.2)
			(type default)
		)
		(fill no)
		(layer "In4.Cu")
	)
	(gr_circle
		(center 398.145 -17.018)
		(end 399.034 -17.018)
		(stroke
			(width 0.2)
			(type default)
		)
		(fill no)
		(layer "In4.Cu")
	)
	(gr_line
		(start 402.1074 -74.041)
		(end 402.1074 -44.551092)
		(stroke
			(width 1.016)
			(type default)
		)
		(layer "In4.Cu")
	)
	(gr_line
		(start 402.1074 -44.551092)
		(end 389.560308 -32.004)
		(stroke
			(width 1.016)
			(type default)
		)
		(layer "In4.Cu")
	)
	(gr_circle
		(center 403.125178 -168.82999)
		(end 404.338282 -168.82999)
		(stroke
			(width 0.2)
			(type default)
		)
		(fill no)
		(layer "In4.Cu")
	)
	(gr_circle
		(center 403.125178 -166.829994)
		(end 404.338282 -166.829994)
		(stroke
			(width 0.2)
			(type default)
		)
		(fill no)
		(layer "In4.Cu")
	)
	(gr_circle
		(center 403.125178 -164.829998)
		(end 404.338282 -164.829998)
		(stroke
			(width 0.2)
			(type default)
		)
		(fill no)
		(layer "In4.Cu")
	)
	(gr_circle
		(center 403.125178 -162.830002)
		(end 404.338282 -162.830002)
		(stroke
			(width 0.2)
			(type default)
		)
		(fill no)
		(layer "In4.Cu")
	)
	(gr_circle
		(center 403.125178 -160.830006)
		(end 404.338282 -160.830006)
		(stroke
			(width 0.2)
			(type default)
		)
		(fill no)
		(layer "In4.Cu")
	)
	(gr_circle
		(center 403.125178 -158.83001)
		(end 404.338282 -158.83001)
		(stroke
			(width 0.2)
			(type default)
		)
		(fill no)
		(layer "In4.Cu")
	)
	(gr_circle
		(center 403.125178 -156.830014)
		(end 404.338282 -156.830014)
		(stroke
			(width 0.2)
			(type default)
		)
		(fill no)
		(layer "In4.Cu")
	)
	(gr_circle
		(center 403.125178 -154.830018)
		(end 404.338282 -154.830018)
		(stroke
			(width 0.2)
			(type default)
		)
		(fill no)
		(layer "In4.Cu")
	)
	(gr_circle
		(center 403.125178 -152.830022)
		(end 404.338282 -152.830022)
		(stroke
			(width 0.2)
			(type default)
		)
		(fill no)
		(layer "In4.Cu")
	)
	(gr_circle
		(center 403.982174 -169.97299)
		(end 405.195278 -169.97299)
		(stroke
			(width 0.2)
			(type default)
		)
		(fill no)
		(layer "In4.Cu")
	)
	(gr_line
		(start 403.999954 -171.649898)
		(end 365.000032 -171.649898)
		(stroke
			(width 2.032)
			(type default)
		)
		(layer "In4.Cu")
	)
	(gr_arc
		(start 403.999954 -171.649898)
		(mid 407.535513 -170.185452)
		(end 408.999944 -166.649908)
		(stroke
			(width 2.032)
			(type default)
		)
		(layer "In4.Cu")
	)
	(gr_circle
		(center 404.141178 -167.972994)
		(end 405.354282 -167.972994)
		(stroke
			(width 0.2)
			(type default)
		)
		(fill no)
		(layer "In4.Cu")
	)
	(gr_circle
		(center 404.141178 -165.972998)
		(end 405.354282 -165.972998)
		(stroke
			(width 0.2)
			(type default)
		)
		(fill no)
		(layer "In4.Cu")
	)
	(gr_circle
		(center 404.141178 -163.973002)
		(end 405.354282 -163.973002)
		(stroke
			(width 0.2)
			(type default)
		)
		(fill no)
		(layer "In4.Cu")
	)
	(gr_circle
		(center 404.141178 -161.973006)
		(end 405.354282 -161.973006)
		(stroke
			(width 0.2)
			(type default)
		)
		(fill no)
		(layer "In4.Cu")
	)
	(gr_circle
		(center 404.141178 -159.97301)
		(end 405.354282 -159.97301)
		(stroke
			(width 0.2)
			(type default)
		)
		(fill no)
		(layer "In4.Cu")
	)
	(gr_circle
		(center 404.141178 -157.973014)
		(end 405.354282 -157.973014)
		(stroke
			(width 0.2)
			(type default)
		)
		(fill no)
		(layer "In4.Cu")
	)
	(gr_circle
		(center 404.141178 -155.973018)
		(end 405.354282 -155.973018)
		(stroke
			(width 0.2)
			(type default)
		)
		(fill no)
		(layer "In4.Cu")
	)
	(gr_circle
		(center 404.141178 -153.973022)
		(end 405.354282 -153.973022)
		(stroke
			(width 0.2)
			(type default)
		)
		(fill no)
		(layer "In4.Cu")
	)
	(gr_circle
		(center 405.11222 -29.21)
		(end 406.00122 -29.21)
		(stroke
			(width 0.2)
			(type default)
		)
		(fill no)
		(layer "In4.Cu")
	)
	(gr_circle
		(center 405.125174 -169.71899)
		(end 406.338278 -169.71899)
		(stroke
			(width 0.2)
			(type default)
		)
		(fill no)
		(layer "In4.Cu")
	)
	(gr_circle
		(center 405.125174 -168.82999)
		(end 406.338278 -168.82999)
		(stroke
			(width 0.2)
			(type default)
		)
		(fill no)
		(layer "In4.Cu")
	)
	(gr_circle
		(center 405.125174 -166.829994)
		(end 406.338278 -166.829994)
		(stroke
			(width 0.2)
			(type default)
		)
		(fill no)
		(layer "In4.Cu")
	)
	(gr_circle
		(center 405.125174 -164.829998)
		(end 406.338278 -164.829998)
		(stroke
			(width 0.2)
			(type default)
		)
		(fill no)
		(layer "In4.Cu")
	)
	(gr_circle
		(center 405.125174 -162.830002)
		(end 406.338278 -162.830002)
		(stroke
			(width 0.2)
			(type default)
		)
		(fill no)
		(layer "In4.Cu")
	)
	(gr_circle
		(center 405.125174 -160.830006)
		(end 406.338278 -160.830006)
		(stroke
			(width 0.2)
			(type default)
		)
		(fill no)
		(layer "In4.Cu")
	)
	(gr_circle
		(center 405.125174 -158.83001)
		(end 406.338278 -158.83001)
		(stroke
			(width 0.2)
			(type default)
		)
		(fill no)
		(layer "In4.Cu")
	)
	(gr_circle
		(center 405.125174 -156.830014)
		(end 406.338278 -156.830014)
		(stroke
			(width 0.2)
			(type default)
		)
		(fill no)
		(layer "In4.Cu")
	)
	(gr_circle
		(center 405.125174 -154.830018)
		(end 406.338278 -154.830018)
		(stroke
			(width 0.2)
			(type default)
		)
		(fill no)
		(layer "In4.Cu")
	)
	(gr_circle
		(center 405.125174 -152.830022)
		(end 406.338278 -152.830022)
		(stroke
			(width 0.2)
			(type default)
		)
		(fill no)
		(layer "In4.Cu")
	)
	(gr_line
		(start 405.6634 -77.597)
		(end 402.1074 -74.041)
		(stroke
			(width 1.016)
			(type default)
		)
		(layer "In4.Cu")
	)
	(gr_circle
		(center 405.6634 -36.83)
		(end 406.5524 -36.83)
		(stroke
			(width 0.2)
			(type default)
		)
		(fill no)
		(layer "In4.Cu")
	)
	(gr_circle
		(center 405.6634 -32.004)
		(end 406.5524 -32.004)
		(stroke
			(width 0.2)
			(type default)
		)
		(fill no)
		(layer "In4.Cu")
	)
	(gr_circle
		(center 406.9334 -22.606)
		(end 407.8224 -22.606)
		(stroke
			(width 0.2)
			(type default)
		)
		(fill no)
		(layer "In4.Cu")
	)
	(gr_circle
		(center 406.9334 -21.717)
		(end 407.8224 -21.717)
		(stroke
			(width 0.2)
			(type default)
		)
		(fill no)
		(layer "In4.Cu")
	)
	(gr_circle
		(center 406.9334 -20.828)
		(end 407.8224 -20.828)
		(stroke
			(width 0.2)
			(type default)
		)
		(fill no)
		(layer "In4.Cu")
	)
	(gr_circle
		(center 406.9334 -17.653)
		(end 407.8224 -17.653)
		(stroke
			(width 0.2)
			(type default)
		)
		(fill no)
		(layer "In4.Cu")
	)
	(gr_circle
		(center 406.9334 -16.764)
		(end 407.8224 -16.764)
		(stroke
			(width 0.2)
			(type default)
		)
		(fill no)
		(layer "In4.Cu")
	)
	(gr_circle
		(center 406.9334 -15.875)
		(end 407.8224 -15.875)
		(stroke
			(width 0.2)
			(type default)
		)
		(fill no)
		(layer "In4.Cu")
	)
	(gr_circle
		(center 407.9494 -22.606)
		(end 408.8384 -22.606)
		(stroke
			(width 0.2)
			(type default)
		)
		(fill no)
		(layer "In4.Cu")
	)
	(gr_circle
		(center 407.9494 -21.717)
		(end 408.8384 -21.717)
		(stroke
			(width 0.2)
			(type default)
		)
		(fill no)
		(layer "In4.Cu")
	)
	(gr_circle
		(center 407.9494 -20.828)
		(end 408.8384 -20.828)
		(stroke
			(width 0.2)
			(type default)
		)
		(fill no)
		(layer "In4.Cu")
	)
	(gr_circle
		(center 407.9494 -17.653)
		(end 408.8384 -17.653)
		(stroke
			(width 0.2)
			(type default)
		)
		(fill no)
		(layer "In4.Cu")
	)
	(gr_circle
		(center 407.9494 -16.764)
		(end 408.8384 -16.764)
		(stroke
			(width 0.2)
			(type default)
		)
		(fill no)
		(layer "In4.Cu")
	)
	(gr_circle
		(center 407.9494 -15.875)
		(end 408.8384 -15.875)
		(stroke
			(width 0.2)
			(type default)
		)
		(fill no)
		(layer "In4.Cu")
	)
	(gr_circle
		(center 408.7114 -22.606)
		(end 409.6004 -22.606)
		(stroke
			(width 0.2)
			(type default)
		)
		(fill no)
		(layer "In4.Cu")
	)
	(gr_circle
		(center 408.7114 -21.717)
		(end 409.6004 -21.717)
		(stroke
			(width 0.2)
			(type default)
		)
		(fill no)
		(layer "In4.Cu")
	)
	(gr_circle
		(center 408.7114 -20.828)
		(end 409.6004 -20.828)
		(stroke
			(width 0.2)
			(type default)
		)
		(fill no)
		(layer "In4.Cu")
	)
	(gr_circle
		(center 408.7114 -17.653)
		(end 409.6004 -17.653)
		(stroke
			(width 0.2)
			(type default)
		)
		(fill no)
		(layer "In4.Cu")
	)
	(gr_circle
		(center 408.7114 -16.764)
		(end 409.6004 -16.764)
		(stroke
			(width 0.2)
			(type default)
		)
		(fill no)
		(layer "In4.Cu")
	)
	(gr_circle
		(center 408.7114 -15.875)
		(end 409.6004 -15.875)
		(stroke
			(width 0.2)
			(type default)
		)
		(fill no)
		(layer "In4.Cu")
	)
	(gr_line
		(start 408.999944 -163.299902)
		(end 408.999944 -166.649908)
		(stroke
			(width 2.032)
			(type default)
		)
		(layer "In4.Cu")
	)
	(gr_circle
		(center 409.9814 -33.02)
		(end 410.8704 -33.02)
		(stroke
			(width 0.2)
			(type default)
		)
		(fill no)
		(layer "In4.Cu")
	)
	(gr_circle
		(center 409.9814 -31.75)
		(end 410.8704 -31.75)
		(stroke
			(width 0.2)
			(type default)
		)
		(fill no)
		(layer "In4.Cu")
	)
	(gr_circle
		(center 409.9814 -30.48)
		(end 410.8704 -30.48)
		(stroke
			(width 0.2)
			(type default)
		)
		(fill no)
		(layer "In4.Cu")
	)
	(gr_circle
		(center 409.9814 -29.21)
		(end 410.8704 -29.21)
		(stroke
			(width 0.2)
			(type default)
		)
		(fill no)
		(layer "In4.Cu")
	)
	(gr_circle
		(center 409.9814 -27.94)
		(end 410.8704 -27.94)
		(stroke
			(width 0.2)
			(type default)
		)
		(fill no)
		(layer "In4.Cu")
	)
	(gr_circle
		(center 410.4132 -21.0058)
		(end 411.3022 -21.0058)
		(stroke
			(width 0.2)
			(type default)
		)
		(fill no)
		(layer "In4.Cu")
	)
	(gr_circle
		(center 410.4132 -20.2438)
		(end 411.3022 -20.2438)
		(stroke
			(width 0.2)
			(type default)
		)
		(fill no)
		(layer "In4.Cu")
	)
	(gr_circle
		(center 410.4132 -19.4818)
		(end 411.3022 -19.4818)
		(stroke
			(width 0.2)
			(type default)
		)
		(fill no)
		(layer "In4.Cu")
	)
	(gr_circle
		(center 410.9974 -37.82695)
		(end 411.8864 -37.82695)
		(stroke
			(width 0.2)
			(type default)
		)
		(fill no)
		(layer "In4.Cu")
	)
	(gr_circle
		(center 411.1752 -21.0058)
		(end 412.0642 -21.0058)
		(stroke
			(width 0.2)
			(type default)
		)
		(fill no)
		(layer "In4.Cu")
	)
	(gr_circle
		(center 411.1752 -20.2438)
		(end 412.0642 -20.2438)
		(stroke
			(width 0.2)
			(type default)
		)
		(fill no)
		(layer "In4.Cu")
	)
	(gr_circle
		(center 411.1752 -19.4818)
		(end 412.0642 -19.4818)
		(stroke
			(width 0.2)
			(type default)
		)
		(fill no)
		(layer "In4.Cu")
	)
	(gr_circle
		(center 412.0134 -39.606474)
		(end 412.9024 -39.606474)
		(stroke
			(width 0.2)
			(type default)
		)
		(fill no)
		(layer "In4.Cu")
	)
	(gr_circle
		(center 412.06293 -30.21076)
		(end 412.95193 -30.21076)
		(stroke
			(width 0.2)
			(type default)
		)
		(fill no)
		(layer "In4.Cu")
	)
	(gr_circle
		(center 412.06293 -29.19476)
		(end 412.95193 -29.19476)
		(stroke
			(width 0.2)
			(type default)
		)
		(fill no)
		(layer "In4.Cu")
	)
	(gr_circle
		(center 412.2674 -45.212)
		(end 413.1564 -45.212)
		(stroke
			(width 0.2)
			(type default)
		)
		(fill no)
		(layer "In4.Cu")
	)
	(gr_circle
		(center 412.2674 -43.815)
		(end 413.1564 -43.815)
		(stroke
			(width 0.2)
			(type default)
		)
		(fill no)
		(layer "In4.Cu")
	)
	(gr_circle
		(center 412.496 -48.006)
		(end 413.385 -48.006)
		(stroke
			(width 0.2)
			(type default)
		)
		(fill no)
		(layer "In4.Cu")
	)
	(gr_circle
		(center 412.623 -44.45)
		(end 413.512 -44.45)
		(stroke
			(width 0.2)
			(type default)
		)
		(fill no)
		(layer "In4.Cu")
	)
	(gr_circle
		(center 412.623 -37.084)
		(end 413.512 -37.084)
		(stroke
			(width 0.2)
			(type default)
		)
		(fill no)
		(layer "In4.Cu")
	)
	(gr_circle
		(center 412.623 -36.195)
		(end 413.512 -36.195)
		(stroke
			(width 0.2)
			(type default)
		)
		(fill no)
		(layer "In4.Cu")
	)
	(gr_circle
		(center 412.84398 -26.40076)
		(end 413.73298 -26.40076)
		(stroke
			(width 0.2)
			(type default)
		)
		(fill no)
		(layer "In4.Cu")
	)
	(gr_circle
		(center 413.004 -42.545)
		(end 413.893 -42.545)
		(stroke
			(width 0.2)
			(type default)
		)
		(fill no)
		(layer "In4.Cu")
	)
	(gr_circle
		(center 413.004 -41.529)
		(end 413.893 -41.529)
		(stroke
			(width 0.2)
			(type default)
		)
		(fill no)
		(layer "In4.Cu")
	)
	(gr_circle
		(center 413.23895 -39.624)
		(end 414.12795 -39.624)
		(stroke
			(width 0.2)
			(type default)
		)
		(fill no)
		(layer "In4.Cu")
	)
	(gr_circle
		(center 413.766 -44.45)
		(end 414.655 -44.45)
		(stroke
			(width 0.2)
			(type default)
		)
		(fill no)
		(layer "In4.Cu")
	)
	(gr_circle
		(center 413.83458 -26.47696)
		(end 414.72358 -26.47696)
		(stroke
			(width 0.2)
			(type default)
		)
		(fill no)
		(layer "In4.Cu")
	)
	(gr_arc
		(start 413.999934 -158.299912)
		(mid 410.464407 -159.764375)
		(end 408.999944 -163.299902)
		(stroke
			(width 2.032)
			(type default)
		)
		(layer "In4.Cu")
	)
	(gr_circle
		(center 414.356042 -29.24556)
		(end 415.245042 -29.24556)
		(stroke
			(width 0.2)
			(type default)
		)
		(fill no)
		(layer "In4.Cu")
	)
	(gr_circle
		(center 414.42259 -47.949358)
		(end 415.31159 -47.949358)
		(stroke
			(width 0.2)
			(type default)
		)
		(fill no)
		(layer "In4.Cu")
	)
	(gr_circle
		(center 414.613344 -27.715718)
		(end 415.502344 -27.715718)
		(stroke
			(width 0.2)
			(type default)
		)
		(fill no)
		(layer "In4.Cu")
	)
	(gr_circle
		(center 415.29 -38.84295)
		(end 416.179 -38.84295)
		(stroke
			(width 0.2)
			(type default)
		)
		(fill no)
		(layer "In4.Cu")
	)
	(gr_circle
		(center 415.6964 -44.069)
		(end 416.5854 -44.069)
		(stroke
			(width 0.2)
			(type default)
		)
		(fill no)
		(layer "In4.Cu")
	)
	(gr_circle
		(center 416.188398 -26.450036)
		(end 417.077398 -26.450036)
		(stroke
			(width 0.2)
			(type default)
		)
		(fill no)
		(layer "In4.Cu")
	)
	(gr_circle
		(center 416.231578 -33.770316)
		(end 417.120578 -33.770316)
		(stroke
			(width 0.2)
			(type default)
		)
		(fill no)
		(layer "In4.Cu")
	)
	(gr_circle
		(center 416.400488 -29.0703)
		(end 417.264088 -29.0703)
		(stroke
			(width 0.2)
			(type default)
		)
		(fill no)
		(layer "In4.Cu")
	)
	(gr_circle
		(center 416.400488 -28.4353)
		(end 417.264088 -28.4353)
		(stroke
			(width 0.2)
			(type default)
		)
		(fill no)
		(layer "In4.Cu")
	)
	(gr_circle
		(center 416.569398 -25.764236)
		(end 417.458398 -25.764236)
		(stroke
			(width 0.2)
			(type default)
		)
		(fill no)
		(layer "In4.Cu")
	)
	(gr_circle
		(center 417.050728 -31.234126)
		(end 417.939728 -31.234126)
		(stroke
			(width 0.2)
			(type default)
		)
		(fill no)
		(layer "In4.Cu")
	)
	(gr_circle
		(center 417.068 -46.863)
		(end 417.957 -46.863)
		(stroke
			(width 0.2)
			(type default)
		)
		(fill no)
		(layer "In4.Cu")
	)
	(gr_circle
		(center 417.077398 -26.450036)
		(end 417.966398 -26.450036)
		(stroke
			(width 0.2)
			(type default)
		)
		(fill no)
		(layer "In4.Cu")
	)
	(gr_line
		(start 417.086034 -158.284164)
		(end 418.593016 -156.777182)
		(stroke
			(width 1.016)
			(type default)
		)
		(layer "In4.Cu")
	)
	(gr_circle
		(center 417.30041 -29.0703)
		(end 418.16401 -29.0703)
		(stroke
			(width 0.2)
			(type default)
		)
		(fill no)
		(layer "In4.Cu")
	)
	(gr_circle
		(center 417.30041 -28.4353)
		(end 418.16401 -28.4353)
		(stroke
			(width 0.2)
			(type default)
		)
		(fill no)
		(layer "In4.Cu")
	)
	(gr_circle
		(center 417.458398 -25.764236)
		(end 418.347398 -25.764236)
		(stroke
			(width 0.2)
			(type default)
		)
		(fill no)
		(layer "In4.Cu")
	)
	(gr_circle
		(center 417.808918 -31.643574)
		(end 418.697918 -31.643574)
		(stroke
			(width 0.2)
			(type default)
		)
		(fill no)
		(layer "In4.Cu")
	)
	(gr_circle
		(center 417.83 -46.863)
		(end 418.719 -46.863)
		(stroke
			(width 0.2)
			(type default)
		)
		(fill no)
		(layer "In4.Cu")
	)
	(gr_circle
		(center 417.966398 -26.450036)
		(end 418.855398 -26.450036)
		(stroke
			(width 0.2)
			(type default)
		)
		(fill no)
		(layer "In4.Cu")
	)
	(gr_circle
		(center 418.200332 -29.0703)
		(end 419.063932 -29.0703)
		(stroke
			(width 0.2)
			(type default)
		)
		(fill no)
		(layer "In4.Cu")
	)
	(gr_circle
		(center 418.200332 -28.4353)
		(end 419.063932 -28.4353)
		(stroke
			(width 0.2)
			(type default)
		)
		(fill no)
		(layer "In4.Cu")
	)
	(gr_circle
		(center 418.347398 -25.764236)
		(end 419.236398 -25.764236)
		(stroke
			(width 0.2)
			(type default)
		)
		(fill no)
		(layer "In4.Cu")
	)
	(gr_circle
		(center 418.5412 -21.1328)
		(end 419.4302 -21.1328)
		(stroke
			(width 0.2)
			(type default)
		)
		(fill no)
		(layer "In4.Cu")
	)
	(gr_circle
		(center 418.5412 -20.3708)
		(end 419.4302 -20.3708)
		(stroke
			(width 0.2)
			(type default)
		)
		(fill no)
		(layer "In4.Cu")
	)
	(gr_circle
		(center 418.5412 -19.6088)
		(end 419.4302 -19.6088)
		(stroke
			(width 0.2)
			(type default)
		)
		(fill no)
		(layer "In4.Cu")
	)
	(gr_circle
		(center 418.550598 -30.940248)
		(end 419.439598 -30.940248)
		(stroke
			(width 0.2)
			(type default)
		)
		(fill no)
		(layer "In4.Cu")
	)
	(gr_line
		(start 418.593016 -156.777182)
		(end 420.117016 -158.301182)
		(stroke
			(width 1.016)
			(type default)
		)
		(layer "In4.Cu")
	)
	(gr_line
		(start 418.593016 -77.6478)
		(end 418.593016 -158.26867)
		(stroke
			(width 1.016)
			(type default)
		)
		(layer "In4.Cu")
	)
	(gr_line
		(start 418.6174 -78.5876)
		(end 417.666932 -77.637132)
		(stroke
			(width 1.016)
			(type default)
		)
		(layer "In4.Cu")
	)
	(gr_line
		(start 418.676074 -78.54061)
		(end 419.626542 -77.590142)
		(stroke
			(width 1.016)
			(type default)
		)
		(layer "In4.Cu")
	)
	(gr_circle
		(center 418.896038 -33.76041)
		(end 419.785038 -33.76041)
		(stroke
			(width 0.2)
			(type default)
		)
		(fill no)
		(layer "In4.Cu")
	)
	(gr_circle
		(center 418.973 -44.043092)
		(end 419.862 -44.043092)
		(stroke
			(width 0.2)
			(type default)
		)
		(fill no)
		(layer "In4.Cu")
	)
	(gr_circle
		(center 419.100508 -29.0703)
		(end 419.964108 -29.0703)
		(stroke
			(width 0.2)
			(type default)
		)
		(fill no)
		(layer "In4.Cu")
	)
	(gr_circle
		(center 419.100508 -28.4353)
		(end 419.964108 -28.4353)
		(stroke
			(width 0.2)
			(type default)
		)
		(fill no)
		(layer "In4.Cu")
	)
	(gr_circle
		(center 419.129718 -45.72)
		(end 420.018718 -45.72)
		(stroke
			(width 0.2)
			(type default)
		)
		(fill no)
		(layer "In4.Cu")
	)
	(gr_circle
		(center 419.35146 -30.996636)
		(end 420.24046 -30.996636)
		(stroke
			(width 0.2)
			(type default)
		)
		(fill no)
		(layer "In4.Cu")
	)
	(gr_circle
		(center 419.363398 -25.332436)
		(end 420.252398 -25.332436)
		(stroke
			(width 0.2)
			(type default)
		)
		(fill no)
		(layer "In4.Cu")
	)
	(gr_circle
		(center 419.43655 -31.769304)
		(end 420.32555 -31.769304)
		(stroke
			(width 0.2)
			(type default)
		)
		(fill no)
		(layer "In4.Cu")
	)
	(gr_circle
		(center 419.7604 -53.848)
		(end 420.6494 -53.848)
		(stroke
			(width 0.2)
			(type default)
		)
		(fill no)
		(layer "In4.Cu")
	)
	(gr_circle
		(center 420.116 -48.895)
		(end 421.005 -48.895)
		(stroke
			(width 0.2)
			(type default)
		)
		(fill no)
		(layer "In4.Cu")
	)
	(gr_circle
		(center 420.790878 -32.35071)
		(end 421.679878 -32.35071)
		(stroke
			(width 0.2)
			(type default)
		)
		(fill no)
		(layer "In4.Cu")
	)
	(gr_circle
		(center 420.8907 -29.65704)
		(end 421.7797 -29.65704)
		(stroke
			(width 0.2)
			(type default)
		)
		(fill no)
		(layer "In4.Cu")
	)
	(gr_circle
		(center 420.8907 -28.92044)
		(end 421.7797 -28.92044)
		(stroke
			(width 0.2)
			(type default)
		)
		(fill no)
		(layer "In4.Cu")
	)
	(gr_circle
		(center 420.8907 -26.00452)
		(end 421.7797 -26.00452)
		(stroke
			(width 0.2)
			(type default)
		)
		(fill no)
		(layer "In4.Cu")
	)
	(gr_circle
		(center 421.005 -48.641)
		(end 421.894 -48.641)
		(stroke
			(width 0.2)
			(type default)
		)
		(fill no)
		(layer "In4.Cu")
	)
	(gr_circle
		(center 421.132 -45.593)
		(end 422.021 -45.593)
		(stroke
			(width 0.2)
			(type default)
		)
		(fill no)
		(layer "In4.Cu")
	)
	(gr_circle
		(center 421.259 -35.052)
		(end 422.148 -35.052)
		(stroke
			(width 0.2)
			(type default)
		)
		(fill no)
		(layer "In4.Cu")
	)
	(gr_circle
		(center 421.64 -49.149)
		(end 422.529 -49.149)
		(stroke
			(width 0.2)
			(type default)
		)
		(fill no)
		(layer "In4.Cu")
	)
	(gr_circle
		(center 421.7035 -29.65704)
		(end 422.5925 -29.65704)
		(stroke
			(width 0.2)
			(type default)
		)
		(fill no)
		(layer "In4.Cu")
	)
	(gr_circle
		(center 421.7035 -28.92044)
		(end 422.5925 -28.92044)
		(stroke
			(width 0.2)
			(type default)
		)
		(fill no)
		(layer "In4.Cu")
	)
	(gr_circle
		(center 422.021 -50.546)
		(end 422.91 -50.546)
		(stroke
			(width 0.2)
			(type default)
		)
		(fill no)
		(layer "In4.Cu")
	)
	(gr_circle
		(center 422.148 -26.924)
		(end 423.037 -26.924)
		(stroke
			(width 0.2)
			(type default)
		)
		(fill no)
		(layer "In4.Cu")
	)
	(gr_circle
		(center 422.656 -51.435)
		(end 423.545 -51.435)
		(stroke
			(width 0.2)
			(type default)
		)
		(fill no)
		(layer "In4.Cu")
	)
	(gr_line
		(start 422.674542 -11.651742)
		(end 428.27702 -17.25422)
		(stroke
			(width 1.016)
			(type default)
		)
		(layer "In4.Cu")
	)
	(gr_line
		(start 422.674542 -1.491488)
		(end 421.150542 0.032512)
		(stroke
			(width 1.524)
			(type default)
		)
		(layer "In4.Cu")
	)
	(gr_line
		(start 422.674542 0)
		(end 422.674542 -11.651742)
		(stroke
			(width 1.016)
			(type default)
		)
		(layer "In4.Cu")
	)
	(gr_circle
		(center 423.418 -35.052)
		(end 424.307 -35.052)
		(stroke
			(width 0.2)
			(type default)
		)
		(fill no)
		(layer "In4.Cu")
	)
	(gr_circle
		(center 423.5704 -50.419)
		(end 424.4594 -50.419)
		(stroke
			(width 0.2)
			(type default)
		)
		(fill no)
		(layer "In4.Cu")
	)
	(gr_circle
		(center 423.69105 -48.133)
		(end 424.58005 -48.133)
		(stroke
			(width 0.2)
			(type default)
		)
		(fill no)
		(layer "In4.Cu")
	)
	(gr_circle
		(center 424.1292 -30.5816)
		(end 425.0182 -30.5816)
		(stroke
			(width 0.2)
			(type default)
		)
		(fill no)
		(layer "In4.Cu")
	)
	(gr_line
		(start 424.181524 0.015494)
		(end 422.674542 -1.491488)
		(stroke
			(width 1.524)
			(type default)
		)
		(layer "In4.Cu")
	)
	(gr_circle
		(center 424.7007 -46.1137)
		(end 425.5897 -46.1137)
		(stroke
			(width 0.2)
			(type default)
		)
		(fill no)
		(layer "In4.Cu")
	)
	(gr_circle
		(center 424.8912 -30.5816)
		(end 425.7802 -30.5816)
		(stroke
			(width 0.2)
			(type default)
		)
		(fill no)
		(layer "In4.Cu")
	)
	(gr_circle
		(center 425.6532 -30.5816)
		(end 426.5422 -30.5816)
		(stroke
			(width 0.2)
			(type default)
		)
		(fill no)
		(layer "In4.Cu")
	)
	(gr_circle
		(center 425.7929 -40.703754)
		(end 426.6819 -40.703754)
		(stroke
			(width 0.2)
			(type default)
		)
		(fill no)
		(layer "In4.Cu")
	)
	(gr_circle
		(center 426.510704 -49.46904)
		(end 427.399704 -49.46904)
		(stroke
			(width 0.2)
			(type default)
		)
		(fill no)
		(layer "In4.Cu")
	)
	(gr_circle
		(center 426.72 -39.751)
		(end 427.609 -39.751)
		(stroke
			(width 0.2)
			(type default)
		)
		(fill no)
		(layer "In4.Cu")
	)
	(gr_circle
		(center 427.355 -30.94355)
		(end 428.244 -30.94355)
		(stroke
			(width 0.2)
			(type default)
		)
		(fill no)
		(layer "In4.Cu")
	)
	(gr_circle
		(center 427.856904 -39.751)
		(end 428.745904 -39.751)
		(stroke
			(width 0.2)
			(type default)
		)
		(fill no)
		(layer "In4.Cu")
	)
	(gr_circle
		(center 427.99 -33.782)
		(end 428.879 -33.782)
		(stroke
			(width 0.2)
			(type default)
		)
		(fill no)
		(layer "In4.Cu")
	)
	(gr_circle
		(center 428.0154 -32.385)
		(end 428.9044 -32.385)
		(stroke
			(width 0.2)
			(type default)
		)
		(fill no)
		(layer "In4.Cu")
	)
	(gr_circle
		(center 428.23765 -47.371)
		(end 429.12665 -47.371)
		(stroke
			(width 0.2)
			(type default)
		)
		(fill no)
		(layer "In4.Cu")
	)
	(gr_circle
		(center 428.237904 -45.974)
		(end 429.126904 -45.974)
		(stroke
			(width 0.2)
			(type default)
		)
		(fill no)
		(layer "In4.Cu")
	)
	(gr_circle
		(center 428.237904 -44.577)
		(end 429.126904 -44.577)
		(stroke
			(width 0.2)
			(type default)
		)
		(fill no)
		(layer "In4.Cu")
	)
	(gr_circle
		(center 428.237904 -43.18)
		(end 429.126904 -43.18)
		(stroke
			(width 0.2)
			(type default)
		)
		(fill no)
		(layer "In4.Cu")
	)
	(gr_circle
		(center 428.237904 -41.783)
		(end 429.126904 -41.783)
		(stroke
			(width 0.2)
			(type default)
		)
		(fill no)
		(layer "In4.Cu")
	)
	(gr_circle
		(center 428.237904 -40.386)
		(end 429.126904 -40.386)
		(stroke
			(width 0.2)
			(type default)
		)
		(fill no)
		(layer "In4.Cu")
	)
	(gr_circle
		(center 428.237904 -38.989)
		(end 429.126904 -38.989)
		(stroke
			(width 0.2)
			(type default)
		)
		(fill no)
		(layer "In4.Cu")
	)
	(gr_circle
		(center 428.237904 -37.592)
		(end 429.126904 -37.592)
		(stroke
			(width 0.2)
			(type default)
		)
		(fill no)
		(layer "In4.Cu")
	)
	(gr_line
		(start 428.27702 -17.25422)
		(end 435.226968 -17.25422)
		(stroke
			(width 1.016)
			(type default)
		)
		(layer "In4.Cu")
	)
	(gr_circle
		(center 428.7774 -46.79188)
		(end 429.6664 -46.79188)
		(stroke
			(width 0.2)
			(type default)
		)
		(fill no)
		(layer "In4.Cu")
	)
	(gr_circle
		(center 428.7774 -43.95724)
		(end 429.6664 -43.95724)
		(stroke
			(width 0.2)
			(type default)
		)
		(fill no)
		(layer "In4.Cu")
	)
	(gr_circle
		(center 428.7774 -41.16324)
		(end 429.6664 -41.16324)
		(stroke
			(width 0.2)
			(type default)
		)
		(fill no)
		(layer "In4.Cu")
	)
	(gr_circle
		(center 428.7774 -36.97224)
		(end 429.6664 -36.97224)
		(stroke
			(width 0.2)
			(type default)
		)
		(fill no)
		(layer "In4.Cu")
	)
	(gr_circle
		(center 429.2854 -32.35325)
		(end 430.1744 -32.35325)
		(stroke
			(width 0.2)
			(type default)
		)
		(fill no)
		(layer "In4.Cu")
	)
	(gr_circle
		(center 429.768 -19.44878)
		(end 430.657 -19.44878)
		(stroke
			(width 0.2)
			(type default)
		)
		(fill no)
		(layer "In4.Cu")
	)
	(gr_circle
		(center 429.9204 -34.53765)
		(end 430.8094 -34.53765)
		(stroke
			(width 0.2)
			(type default)
		)
		(fill no)
		(layer "In4.Cu")
	)
	(gr_circle
		(center 430.657 -19.431)
		(end 431.546 -19.431)
		(stroke
			(width 0.2)
			(type default)
		)
		(fill no)
		(layer "In4.Cu")
	)
	(gr_circle
		(center 430.9364 -30.226)
		(end 431.8254 -30.226)
		(stroke
			(width 0.2)
			(type default)
		)
		(fill no)
		(layer "In4.Cu")
	)
	(gr_circle
		(center 431.28565 -45.974)
		(end 432.17465 -45.974)
		(stroke
			(width 0.2)
			(type default)
		)
		(fill no)
		(layer "In4.Cu")
	)
	(gr_circle
		(center 431.285904 -44.577)
		(end 432.174904 -44.577)
		(stroke
			(width 0.2)
			(type default)
		)
		(fill no)
		(layer "In4.Cu")
	)
	(gr_circle
		(center 431.285904 -43.18)
		(end 432.174904 -43.18)
		(stroke
			(width 0.2)
			(type default)
		)
		(fill no)
		(layer "In4.Cu")
	)
	(gr_circle
		(center 431.285904 -41.783)
		(end 432.174904 -41.783)
		(stroke
			(width 0.2)
			(type default)
		)
		(fill no)
		(layer "In4.Cu")
	)
	(gr_circle
		(center 431.285904 -40.386)
		(end 432.174904 -40.386)
		(stroke
			(width 0.2)
			(type default)
		)
		(fill no)
		(layer "In4.Cu")
	)
	(gr_circle
		(center 431.285904 -38.989)
		(end 432.174904 -38.989)
		(stroke
			(width 0.2)
			(type default)
		)
		(fill no)
		(layer "In4.Cu")
	)
	(gr_circle
		(center 431.285904 -37.592)
		(end 432.174904 -37.592)
		(stroke
			(width 0.2)
			(type default)
		)
		(fill no)
		(layer "In4.Cu")
	)
	(gr_circle
		(center 432.054 -41.783)
		(end 432.943 -41.783)
		(stroke
			(width 0.2)
			(type default)
		)
		(fill no)
		(layer "In4.Cu")
	)
	(gr_circle
		(center 432.054 -40.386)
		(end 432.943 -40.386)
		(stroke
			(width 0.2)
			(type default)
		)
		(fill no)
		(layer "In4.Cu")
	)
	(gr_circle
		(center 432.0794 -46.228)
		(end 432.9684 -46.228)
		(stroke
			(width 0.2)
			(type default)
		)
		(fill no)
		(layer "In4.Cu")
	)
	(gr_circle
		(center 432.0794 -45.339)
		(end 432.9684 -45.339)
		(stroke
			(width 0.2)
			(type default)
		)
		(fill no)
		(layer "In4.Cu")
	)
	(gr_circle
		(center 432.1429 -29.0195)
		(end 433.0319 -29.0195)
		(stroke
			(width 0.2)
			(type default)
		)
		(fill no)
		(layer "In4.Cu")
	)
	(gr_circle
		(center 432.32705 -52.197)
		(end 433.21605 -52.197)
		(stroke
			(width 0.2)
			(type default)
		)
		(fill no)
		(layer "In4.Cu")
	)
	(gr_circle
		(center 432.44135 -32.893)
		(end 433.33035 -32.893)
		(stroke
			(width 0.2)
			(type default)
		)
		(fill no)
		(layer "In4.Cu")
	)
	(gr_circle
		(center 432.4604 -43.561)
		(end 433.3494 -43.561)
		(stroke
			(width 0.2)
			(type default)
		)
		(fill no)
		(layer "In4.Cu")
	)
	(gr_circle
		(center 432.9684 -51.181)
		(end 433.8574 -51.181)
		(stroke
			(width 0.2)
			(type default)
		)
		(fill no)
		(layer "In4.Cu")
	)
	(gr_circle
		(center 433.0954 -35.687)
		(end 433.9844 -35.687)
		(stroke
			(width 0.2)
			(type default)
		)
		(fill no)
		(layer "In4.Cu")
	)
	(gr_circle
		(center 433.3494 -23.368)
		(end 434.2384 -23.368)
		(stroke
			(width 0.2)
			(type default)
		)
		(fill no)
		(layer "In4.Cu")
	)
	(gr_circle
		(center 433.4764 -47.371)
		(end 434.3654 -47.371)
		(stroke
			(width 0.2)
			(type default)
		)
		(fill no)
		(layer "In4.Cu")
	)
	(gr_circle
		(center 433.6034 -36.195)
		(end 434.4924 -36.195)
		(stroke
			(width 0.2)
			(type default)
		)
		(fill no)
		(layer "In4.Cu")
	)
	(gr_circle
		(center 434.2384 -40.132)
		(end 435.1274 -40.132)
		(stroke
			(width 0.2)
			(type default)
		)
		(fill no)
		(layer "In4.Cu")
	)
	(gr_circle
		(center 434.60035 -47.498)
		(end 435.48935 -47.498)
		(stroke
			(width 0.2)
			(type default)
		)
		(fill no)
		(layer "In4.Cu")
	)
	(gr_circle
		(center 434.848 -38.862)
		(end 435.737 -38.862)
		(stroke
			(width 0.2)
			(type default)
		)
		(fill no)
		(layer "In4.Cu")
	)
	(gr_line
		(start 434.999892 -158.299912)
		(end 413.999934 -158.299912)
		(stroke
			(width 2.032)
			(type default)
		)
		(layer "In4.Cu")
	)
	(gr_arc
		(start 434.999892 -158.299912)
		(mid 438.535432 -156.835453)
		(end 439.999882 -153.299922)
		(stroke
			(width 2.032)
			(type default)
		)
		(layer "In4.Cu")
	)
	(gr_line
		(start 435.226968 -17.25422)
		(end 452.923148 -34.9504)
		(stroke
			(width 1.016)
			(type default)
		)
		(layer "In4.Cu")
	)
	(gr_circle
		(center 435.235096 -30.353)
		(end 436.124096 -30.353)
		(stroke
			(width 0.2)
			(type default)
		)
		(fill no)
		(layer "In4.Cu")
	)
	(gr_circle
		(center 435.235096 -29.083)
		(end 436.124096 -29.083)
		(stroke
			(width 0.2)
			(type default)
		)
		(fill no)
		(layer "In4.Cu")
	)
	(gr_circle
		(center 435.235096 -27.813)
		(end 436.124096 -27.813)
		(stroke
			(width 0.2)
			(type default)
		)
		(fill no)
		(layer "In4.Cu")
	)
	(gr_circle
		(center 435.23535 -34.163)
		(end 436.12435 -34.163)
		(stroke
			(width 0.2)
			(type default)
		)
		(fill no)
		(layer "In4.Cu")
	)
	(gr_circle
		(center 435.23535 -32.893)
		(end 436.12435 -32.893)
		(stroke
			(width 0.2)
			(type default)
		)
		(fill no)
		(layer "In4.Cu")
	)
	(gr_circle
		(center 435.3814 -36.81095)
		(end 436.2704 -36.81095)
		(stroke
			(width 0.2)
			(type default)
		)
		(fill no)
		(layer "In4.Cu")
	)
	(gr_circle
		(center 435.40045 -47.498)
		(end 436.28945 -47.498)
		(stroke
			(width 0.2)
			(type default)
		)
		(fill no)
		(layer "In4.Cu")
	)
	(gr_circle
		(center 435.74335 -42.799)
		(end 436.63235 -42.799)
		(stroke
			(width 0.2)
			(type default)
		)
		(fill no)
		(layer "In4.Cu")
	)
	(gr_circle
		(center 435.74335 -38.862)
		(end 436.63235 -38.862)
		(stroke
			(width 0.2)
			(type default)
		)
		(fill no)
		(layer "In4.Cu")
	)
	(gr_circle
		(center 436.2704 -40.132)
		(end 437.1594 -40.132)
		(stroke
			(width 0.2)
			(type default)
		)
		(fill no)
		(layer "In4.Cu")
	)
	(gr_circle
		(center 436.54345 -25.146)
		(end 437.43245 -25.146)
		(stroke
			(width 0.2)
			(type default)
		)
		(fill no)
		(layer "In4.Cu")
	)
	(gr_circle
		(center 436.54345 -23.749)
		(end 437.43245 -23.749)
		(stroke
			(width 0.2)
			(type default)
		)
		(fill no)
		(layer "In4.Cu")
	)
	(gr_circle
		(center 436.54345 -22.352)
		(end 437.43245 -22.352)
		(stroke
			(width 0.2)
			(type default)
		)
		(fill no)
		(layer "In4.Cu")
	)
	(gr_circle
		(center 436.64505 -28.448)
		(end 437.53405 -28.448)
		(stroke
			(width 0.2)
			(type default)
		)
		(fill no)
		(layer "In4.Cu")
	)
	(gr_circle
		(center 436.64505 -27.182064)
		(end 437.53405 -27.182064)
		(stroke
			(width 0.2)
			(type default)
		)
		(fill no)
		(layer "In4.Cu")
	)
	(gr_circle
		(center 436.9054 -45.593)
		(end 437.7944 -45.593)
		(stroke
			(width 0.2)
			(type default)
		)
		(fill no)
		(layer "In4.Cu")
	)
	(gr_circle
		(center 437.013096 -44.45)
		(end 437.902096 -44.45)
		(stroke
			(width 0.2)
			(type default)
		)
		(fill no)
		(layer "In4.Cu")
	)
	(gr_circle
		(center 437.134 -36.20135)
		(end 438.023 -36.20135)
		(stroke
			(width 0.2)
			(type default)
		)
		(fill no)
		(layer "In4.Cu")
	)
	(gr_circle
		(center 437.261 -52.07)
		(end 438.15 -52.07)
		(stroke
			(width 0.2)
			(type default)
		)
		(fill no)
		(layer "In4.Cu")
	)
	(gr_circle
		(center 437.2864 -50.419)
		(end 438.1754 -50.419)
		(stroke
			(width 0.2)
			(type default)
		)
		(fill no)
		(layer "In4.Cu")
	)
	(gr_circle
		(center 437.2864 -49.46904)
		(end 438.1754 -49.46904)
		(stroke
			(width 0.2)
			(type default)
		)
		(fill no)
		(layer "In4.Cu")
	)
	(gr_circle
		(center 437.30799 -24.36876)
		(end 438.19699 -24.36876)
		(stroke
			(width 0.2)
			(type default)
		)
		(fill no)
		(layer "In4.Cu")
	)
	(gr_circle
		(center 437.404002 -39.868348)
		(end 438.293002 -39.868348)
		(stroke
			(width 0.2)
			(type default)
		)
		(fill no)
		(layer "In4.Cu")
	)
	(gr_circle
		(center 438.105296 -52.140104)
		(end 438.994296 -52.140104)
		(stroke
			(width 0.2)
			(type default)
		)
		(fill no)
		(layer "In4.Cu")
	)
	(gr_circle
		(center 438.429146 -38.862)
		(end 439.318146 -38.862)
		(stroke
			(width 0.2)
			(type default)
		)
		(fill no)
		(layer "In4.Cu")
	)
	(gr_circle
		(center 438.6834 -41.72712)
		(end 439.5724 -41.72712)
		(stroke
			(width 0.2)
			(type default)
		)
		(fill no)
		(layer "In4.Cu")
	)
	(gr_circle
		(center 438.7088 -26.543)
		(end 439.5978 -26.543)
		(stroke
			(width 0.2)
			(type default)
		)
		(fill no)
		(layer "In4.Cu")
	)
	(gr_circle
		(center 439.03265 -44.45)
		(end 439.92165 -44.45)
		(stroke
			(width 0.2)
			(type default)
		)
		(fill no)
		(layer "In4.Cu")
	)
	(gr_circle
		(center 439.166 -46.609)
		(end 440.055 -46.609)
		(stroke
			(width 0.2)
			(type default)
		)
		(fill no)
		(layer "In4.Cu")
	)
	(gr_circle
		(center 439.270394 -40.426894)
		(end 440.159394 -40.426894)
		(stroke
			(width 0.2)
			(type default)
		)
		(fill no)
		(layer "In4.Cu")
	)
	(gr_circle
		(center 439.270394 -36.489894)
		(end 440.159394 -36.489894)
		(stroke
			(width 0.2)
			(type default)
		)
		(fill no)
		(layer "In4.Cu")
	)
	(gr_circle
		(center 439.90895 -50.546)
		(end 440.79795 -50.546)
		(stroke
			(width 0.2)
			(type default)
		)
		(fill no)
		(layer "In4.Cu")
	)
	(gr_line
		(start 439.999882 -136.77011)
		(end 439.999882 -153.299922)
		(stroke
			(width 2.032)
			(type default)
		)
		(layer "In4.Cu")
	)
	(gr_arc
		(start 439.999882 -11.770106)
		(mid 441.464509 -15.305648)
		(end 445.000126 -16.770096)
		(stroke
			(width 2.032)
			(type default)
		)
		(layer "In4.Cu")
	)
	(gr_arc
		(start 439.999882 -4.99999)
		(mid 438.535415 -1.464472)
		(end 434.999892 0)
		(stroke
			(width 2.032)
			(type default)
		)
		(layer "In4.Cu")
	)
	(gr_line
		(start 439.999882 -4.99999)
		(end 439.999882 -11.770106)
		(stroke
			(width 2.032)
			(type default)
		)
		(layer "In4.Cu")
	)
	(gr_circle
		(center 440.309 -44.13504)
		(end 441.198 -44.13504)
		(stroke
			(width 0.2)
			(type default)
		)
		(fill no)
		(layer "In4.Cu")
	)
	(gr_circle
		(center 441.452 -31.623)
		(end 442.341 -31.623)
		(stroke
			(width 0.2)
			(type default)
		)
		(fill no)
		(layer "In4.Cu")
	)
	(gr_circle
		(center 441.63996 -48.641)
		(end 442.52896 -48.641)
		(stroke
			(width 0.2)
			(type default)
		)
		(fill no)
		(layer "In4.Cu")
	)
	(gr_circle
		(center 442.1124 -65.532)
		(end 443.0014 -65.532)
		(stroke
			(width 0.2)
			(type default)
		)
		(fill no)
		(layer "In4.Cu")
	)
	(gr_circle
		(center 442.1124 -64.897)
		(end 443.0014 -64.897)
		(stroke
			(width 0.2)
			(type default)
		)
		(fill no)
		(layer "In4.Cu")
	)
	(gr_circle
		(center 442.1124 -64.262)
		(end 443.0014 -64.262)
		(stroke
			(width 0.2)
			(type default)
		)
		(fill no)
		(layer "In4.Cu")
	)
	(gr_circle
		(center 442.1124 -63.627)
		(end 443.0014 -63.627)
		(stroke
			(width 0.2)
			(type default)
		)
		(fill no)
		(layer "In4.Cu")
	)
	(gr_circle
		(center 442.1124 -62.992)
		(end 443.0014 -62.992)
		(stroke
			(width 0.2)
			(type default)
		)
		(fill no)
		(layer "In4.Cu")
	)
	(gr_circle
		(center 442.1124 -61.087)
		(end 443.0014 -61.087)
		(stroke
			(width 0.2)
			(type default)
		)
		(fill no)
		(layer "In4.Cu")
	)
	(gr_circle
		(center 442.1124 -60.452)
		(end 443.0014 -60.452)
		(stroke
			(width 0.2)
			(type default)
		)
		(fill no)
		(layer "In4.Cu")
	)
	(gr_circle
		(center 442.1124 -59.817)
		(end 443.0014 -59.817)
		(stroke
			(width 0.2)
			(type default)
		)
		(fill no)
		(layer "In4.Cu")
	)
	(gr_circle
		(center 442.1124 -59.182)
		(end 443.0014 -59.182)
		(stroke
			(width 0.2)
			(type default)
		)
		(fill no)
		(layer "In4.Cu")
	)
	(gr_circle
		(center 443.484 -48.57496)
		(end 444.373 -48.57496)
		(stroke
			(width 0.2)
			(type default)
		)
		(fill no)
		(layer "In4.Cu")
	)
	(gr_circle
		(center 443.97295 -51.816)
		(end 444.86195 -51.816)
		(stroke
			(width 0.2)
			(type default)
		)
		(fill no)
		(layer "In4.Cu")
	)
	(gr_circle
		(center 444.643002 -50.292)
		(end 445.532002 -50.292)
		(stroke
			(width 0.2)
			(type default)
		)
		(fill no)
		(layer "In4.Cu")
	)
	(gr_circle
		(center 444.9064 -65.532)
		(end 445.7954 -65.532)
		(stroke
			(width 0.2)
			(type default)
		)
		(fill no)
		(layer "In4.Cu")
	)
	(gr_circle
		(center 444.9064 -64.897)
		(end 445.7954 -64.897)
		(stroke
			(width 0.2)
			(type default)
		)
		(fill no)
		(layer "In4.Cu")
	)
	(gr_circle
		(center 444.9064 -64.262)
		(end 445.7954 -64.262)
		(stroke
			(width 0.2)
			(type default)
		)
		(fill no)
		(layer "In4.Cu")
	)
	(gr_circle
		(center 444.9064 -63.627)
		(end 445.7954 -63.627)
		(stroke
			(width 0.2)
			(type default)
		)
		(fill no)
		(layer "In4.Cu")
	)
	(gr_circle
		(center 444.9064 -62.992)
		(end 445.7954 -62.992)
		(stroke
			(width 0.2)
			(type default)
		)
		(fill no)
		(layer "In4.Cu")
	)
	(gr_circle
		(center 444.9064 -61.087)
		(end 445.7954 -61.087)
		(stroke
			(width 0.2)
			(type default)
		)
		(fill no)
		(layer "In4.Cu")
	)
	(gr_circle
		(center 444.9064 -60.452)
		(end 445.7954 -60.452)
		(stroke
			(width 0.2)
			(type default)
		)
		(fill no)
		(layer "In4.Cu")
	)
	(gr_circle
		(center 444.9064 -59.817)
		(end 445.7954 -59.817)
		(stroke
			(width 0.2)
			(type default)
		)
		(fill no)
		(layer "In4.Cu")
	)
	(gr_circle
		(center 444.9064 -59.182)
		(end 445.7954 -59.182)
		(stroke
			(width 0.2)
			(type default)
		)
		(fill no)
		(layer "In4.Cu")
	)
	(gr_arc
		(start 445.000126 -131.77012)
		(mid 441.464509 -133.234568)
		(end 439.999882 -136.77011)
		(stroke
			(width 2.032)
			(type default)
		)
		(layer "In4.Cu")
	)
	(gr_line
		(start 445.000126 -16.770096)
		(end 471.000074 -16.770096)
		(stroke
			(width 2.032)
			(type default)
		)
		(layer "In4.Cu")
	)
	(gr_circle
		(center 445.58204 -47.56404)
		(end 446.47104 -47.56404)
		(stroke
			(width 0.2)
			(type default)
		)
		(fill no)
		(layer "In4.Cu")
	)
	(gr_circle
		(center 445.75095 -51.562)
		(end 446.63995 -51.562)
		(stroke
			(width 0.2)
			(type default)
		)
		(fill no)
		(layer "In4.Cu")
	)
	(gr_circle
		(center 446.9384 -29.083)
		(end 447.8274 -29.083)
		(stroke
			(width 0.2)
			(type default)
		)
		(fill no)
		(layer "In4.Cu")
	)
	(gr_circle
		(center 447.02095 -45.4406)
		(end 447.90995 -45.4406)
		(stroke
			(width 0.2)
			(type default)
		)
		(fill no)
		(layer "In4.Cu")
	)
	(gr_circle
		(center 447.4464 -31.629096)
		(end 448.3354 -31.629096)
		(stroke
			(width 0.2)
			(type default)
		)
		(fill no)
		(layer "In4.Cu")
	)
	(gr_circle
		(center 447.82105 -45.4406)
		(end 448.71005 -45.4406)
		(stroke
			(width 0.2)
			(type default)
		)
		(fill no)
		(layer "In4.Cu")
	)
	(gr_circle
		(center 448.03695 -43.429936)
		(end 448.92595 -43.429936)
		(stroke
			(width 0.2)
			(type default)
		)
		(fill no)
		(layer "In4.Cu")
	)
	(gr_circle
		(center 448.03695 -39.492936)
		(end 448.92595 -39.492936)
		(stroke
			(width 0.2)
			(type default)
		)
		(fill no)
		(layer "In4.Cu")
	)
	(gr_circle
		(center 448.056 -40.13835)
		(end 448.945 -40.13835)
		(stroke
			(width 0.2)
			(type default)
		)
		(fill no)
		(layer "In4.Cu")
	)
	(gr_circle
		(center 448.056 -36.20135)
		(end 448.945 -36.20135)
		(stroke
			(width 0.2)
			(type default)
		)
		(fill no)
		(layer "In4.Cu")
	)
	(gr_circle
		(center 448.0814 -30.353)
		(end 448.9704 -30.353)
		(stroke
			(width 0.2)
			(type default)
		)
		(fill no)
		(layer "In4.Cu")
	)
	(gr_circle
		(center 448.673728 -63.576454)
		(end 449.562728 -63.576454)
		(stroke
			(width 0.2)
			(type default)
		)
		(fill no)
		(layer "In4.Cu")
	)
	(gr_circle
		(center 448.673728 -62.814454)
		(end 449.562728 -62.814454)
		(stroke
			(width 0.2)
			(type default)
		)
		(fill no)
		(layer "In4.Cu")
	)
	(gr_circle
		(center 448.677538 -61.670692)
		(end 449.566538 -61.670692)
		(stroke
			(width 0.2)
			(type default)
		)
		(fill no)
		(layer "In4.Cu")
	)
	(gr_circle
		(center 448.677538 -60.908692)
		(end 449.566538 -60.908692)
		(stroke
			(width 0.2)
			(type default)
		)
		(fill no)
		(layer "In4.Cu")
	)
	(gr_circle
		(center 448.79895 -46.101)
		(end 449.68795 -46.101)
		(stroke
			(width 0.2)
			(type default)
		)
		(fill no)
		(layer "In4.Cu")
	)
	(gr_circle
		(center 448.83705 -39.492936)
		(end 449.72605 -39.492936)
		(stroke
			(width 0.2)
			(type default)
		)
		(fill no)
		(layer "In4.Cu")
	)
	(gr_circle
		(center 448.92595 -34.798)
		(end 449.81495 -34.798)
		(stroke
			(width 0.2)
			(type default)
		)
		(fill no)
		(layer "In4.Cu")
	)
	(gr_circle
		(center 449.072 -47.56404)
		(end 449.961 -47.56404)
		(stroke
			(width 0.2)
			(type default)
		)
		(fill no)
		(layer "In4.Cu")
	)
	(gr_circle
		(center 449.199 -40.13835)
		(end 450.088 -40.13835)
		(stroke
			(width 0.2)
			(type default)
		)
		(fill no)
		(layer "In4.Cu")
	)
	(gr_circle
		(center 449.199 -36.20135)
		(end 450.088 -36.20135)
		(stroke
			(width 0.2)
			(type default)
		)
		(fill no)
		(layer "In4.Cu")
	)
	(gr_circle
		(center 449.43395 -51.562)
		(end 450.32295 -51.562)
		(stroke
			(width 0.2)
			(type default)
		)
		(fill no)
		(layer "In4.Cu")
	)
	(gr_circle
		(center 449.446904 -42.799)
		(end 450.335904 -42.799)
		(stroke
			(width 0.2)
			(type default)
		)
		(fill no)
		(layer "In4.Cu")
	)
	(gr_circle
		(center 449.59905 -46.101)
		(end 450.48805 -46.101)
		(stroke
			(width 0.2)
			(type default)
		)
		(fill no)
		(layer "In4.Cu")
	)
	(gr_circle
		(center 449.72605 -34.798)
		(end 450.61505 -34.798)
		(stroke
			(width 0.2)
			(type default)
		)
		(fill no)
		(layer "In4.Cu")
	)
	(gr_circle
		(center 450.215 -44.196)
		(end 451.104 -44.196)
		(stroke
			(width 0.2)
			(type default)
		)
		(fill no)
		(layer "In4.Cu")
	)
	(gr_circle
		(center 450.2404 -45.0342)
		(end 451.1294 -45.0342)
		(stroke
			(width 0.2)
			(type default)
		)
		(fill no)
		(layer "In4.Cu")
	)
	(gr_circle
		(center 450.342 -40.132)
		(end 451.231 -40.132)
		(stroke
			(width 0.2)
			(type default)
		)
		(fill no)
		(layer "In4.Cu")
	)
	(gr_circle
		(center 450.342 -36.20135)
		(end 451.231 -36.20135)
		(stroke
			(width 0.2)
			(type default)
		)
		(fill no)
		(layer "In4.Cu")
	)
	(gr_circle
		(center 450.469 -32.893)
		(end 451.358 -32.893)
		(stroke
			(width 0.2)
			(type default)
		)
		(fill no)
		(layer "In4.Cu")
	)
	(gr_circle
		(center 450.959728 -63.590678)
		(end 451.848728 -63.590678)
		(stroke
			(width 0.2)
			(type default)
		)
		(fill no)
		(layer "In4.Cu")
	)
	(gr_circle
		(center 450.959728 -62.828678)
		(end 451.848728 -62.828678)
		(stroke
			(width 0.2)
			(type default)
		)
		(fill no)
		(layer "In4.Cu")
	)
	(gr_circle
		(center 450.963538 -61.670692)
		(end 451.852538 -61.670692)
		(stroke
			(width 0.2)
			(type default)
		)
		(fill no)
		(layer "In4.Cu")
	)
	(gr_circle
		(center 450.963538 -60.908692)
		(end 451.852538 -60.908692)
		(stroke
			(width 0.2)
			(type default)
		)
		(fill no)
		(layer "In4.Cu")
	)
	(gr_circle
		(center 451.612 -48.133)
		(end 452.501 -48.133)
		(stroke
			(width 0.2)
			(type default)
		)
		(fill no)
		(layer "In4.Cu")
	)
	(gr_line
		(start 452.923148 -34.9504)
		(end 460.502 -34.9504)
		(stroke
			(width 1.016)
			(type default)
		)
		(layer "In4.Cu")
	)
	(gr_circle
		(center 453.118728 -63.590678)
		(end 454.007728 -63.590678)
		(stroke
			(width 0.2)
			(type default)
		)
		(fill no)
		(layer "In4.Cu")
	)
	(gr_circle
		(center 453.118728 -62.828678)
		(end 454.007728 -62.828678)
		(stroke
			(width 0.2)
			(type default)
		)
		(fill no)
		(layer "In4.Cu")
	)
	(gr_circle
		(center 453.122538 -61.670692)
		(end 454.011538 -61.670692)
		(stroke
			(width 0.2)
			(type default)
		)
		(fill no)
		(layer "In4.Cu")
	)
	(gr_circle
		(center 453.122538 -60.908692)
		(end 454.011538 -60.908692)
		(stroke
			(width 0.2)
			(type default)
		)
		(fill no)
		(layer "In4.Cu")
	)
	(gr_circle
		(center 454.5584 -62.738)
		(end 455.4474 -62.738)
		(stroke
			(width 0.2)
			(type default)
		)
		(fill no)
		(layer "In4.Cu")
	)
	(gr_circle
		(center 454.5584 -61.849)
		(end 455.4474 -61.849)
		(stroke
			(width 0.2)
			(type default)
		)
		(fill no)
		(layer "In4.Cu")
	)
	(gr_circle
		(center 457.2254 -47.625)
		(end 458.1144 -47.625)
		(stroke
			(width 0.2)
			(type default)
		)
		(fill no)
		(layer "In4.Cu")
	)
	(gr_circle
		(center 459.6384 -49.53)
		(end 460.5274 -49.53)
		(stroke
			(width 0.2)
			(type default)
		)
		(fill no)
		(layer "In4.Cu")
	)
	(gr_circle
		(center 460.121 -47.244)
		(end 461.01 -47.244)
		(stroke
			(width 0.2)
			(type default)
		)
		(fill no)
		(layer "In4.Cu")
	)
	(gr_line
		(start 460.502 -34.9504)
		(end 466.979 -41.4274)
		(stroke
			(width 1.016)
			(type default)
		)
		(layer "In4.Cu")
	)
	(gr_circle
		(center 461.645 -47.752)
		(end 462.534 -47.752)
		(stroke
			(width 0.2)
			(type default)
		)
		(fill no)
		(layer "In4.Cu")
	)
	(gr_line
		(start 466.979 -66.3702)
		(end 468.0458 -67.437)
		(stroke
			(width 1.016)
			(type default)
		)
		(layer "In4.Cu")
	)
	(gr_line
		(start 466.979 -41.4274)
		(end 466.979 -66.3702)
		(stroke
			(width 1.016)
			(type default)
		)
		(layer "In4.Cu")
	)
	(gr_line
		(start 468.0458 -67.437)
		(end 472.6686 -67.437)
		(stroke
			(width 1.016)
			(type default)
		)
		(layer "In4.Cu")
	)
	(gr_line
		(start 471.000074 -131.77012)
		(end 445.000126 -131.77012)
		(stroke
			(width 2.032)
			(type default)
		)
		(layer "In4.Cu")
	)
	(gr_arc
		(start 471.000074 -131.77012)
		(mid 474.535718 -130.305578)
		(end 476.000064 -126.769876)
		(stroke
			(width 2.032)
			(type default)
		)
		(layer "In4.Cu")
	)
	(gr_line
		(start 472.6686 -77.597)
		(end 405.6634 -77.597)
		(stroke
			(width 1.016)
			(type default)
		)
		(layer "In4.Cu")
	)
	(gr_line
		(start 472.6686 -67.437)
		(end 473.3036 -68.072)
		(stroke
			(width 1.016)
			(type default)
		)
		(layer "In4.Cu")
	)
	(gr_line
		(start 473.3036 -76.962)
		(end 472.6686 -77.597)
		(stroke
			(width 1.016)
			(type default)
		)
		(layer "In4.Cu")
	)
	(gr_line
		(start 473.3036 -68.072)
		(end 473.3036 -76.962)
		(stroke
			(width 1.016)
			(type default)
		)
		(layer "In4.Cu")
	)
	(gr_arc
		(start 476.000064 -21.770086)
		(mid 474.535594 -18.234577)
		(end 471.000074 -16.770096)
		(stroke
			(width 2.032)
			(type default)
		)
		(layer "In4.Cu")
	)
	(gr_line
		(start 476.000064 -21.770086)
		(end 476.000064 -126.769876)
		(stroke
			(width 2.032)
			(type default)
		)
		(layer "In4.Cu")
	)
	(gr_line
		(start 0 -153.299922)
		(end 0 -4.99999)
		(stroke
			(width 2.032)
			(type default)
		)
		(layer "In5.Cu")
	)
	(gr_arc
		(start 0 -153.299922)
		(mid 1.464464 -156.835448)
		(end 4.99999 -158.299912)
		(stroke
			(width 2.032)
			(type default)
		)
		(layer "In5.Cu")
	)
	(gr_poly
		(pts
			(arc
				(start 192.800224 -51.05908)
				(mid 192.819747 -51.055179)
				(end 192.836292 -51.044094)
			)
			(arc
				(start 193.053462 -50.826924)
				(mid 193.064573 -50.81039)
				(end 193.068448 -50.790856)
			)
			(arc
				(start 193.068448 -46.88586)
				(mid 193.064547 -46.866337)
				(end 193.053462 -46.849792)
			)
			(arc
				(start 189.652656 -43.448986)
				(mid 189.636122 -43.437875)
				(end 189.616588 -43.434)
			)
			(arc
				(start 186.057794 -43.434)
				(mid 186.038271 -43.437901)
				(end 186.021726 -43.448986)
			)
			(arc
				(start 182.666386 -46.804326)
				(mid 182.655275 -46.82086)
				(end 182.6514 -46.840394)
			)
			(arc
				(start 182.6514 -50.663602)
				(mid 182.655301 -50.683125)
				(end 182.666386 -50.69967)
			)
			(arc
				(start 183.01081 -51.044094)
				(mid 183.027344 -51.055205)
				(end 183.046878 -51.05908)
			)
		)
		(stroke
			(width 0)
			(type solid)
		)
		(fill yes)
		(layer "In5.Cu")
		(net "P52V_2_FUSE_1")
	)
	(gr_poly
		(pts
			(arc
				(start 257.287522 -51.05908)
				(mid 257.307045 -51.055179)
				(end 257.32359 -51.044094)
			)
			(arc
				(start 257.668014 -50.69967)
				(mid 257.679125 -50.683136)
				(end 257.683 -50.663602)
			)
			(arc
				(start 257.683 -46.840394)
				(mid 257.679099 -46.820871)
				(end 257.668014 -46.804326)
			)
			(arc
				(start 254.312674 -43.448986)
				(mid 254.29614 -43.437875)
				(end 254.276606 -43.434)
			)
			(arc
				(start 250.717812 -43.434)
				(mid 250.698289 -43.437901)
				(end 250.681744 -43.448986)
			)
			(arc
				(start 247.280938 -46.849792)
				(mid 247.269827 -46.866326)
				(end 247.265952 -46.88586)
			)
			(arc
				(start 247.265952 -50.790856)
				(mid 247.269853 -50.810379)
				(end 247.280938 -50.826924)
			)
			(arc
				(start 247.498108 -51.044094)
				(mid 247.514642 -51.055205)
				(end 247.534176 -51.05908)
			)
		)
		(stroke
			(width 0)
			(type solid)
		)
		(fill yes)
		(layer "In5.Cu")
		(net "P52V_1_FUSE_1")
	)
	(gr_poly
		(pts
			(arc
				(start 136.007856 -80.01)
				(mid 136.027379 -80.006099)
				(end 136.043924 -79.995014)
			)
			(arc
				(start 136.343644 -79.695294)
				(mid 136.354755 -79.67876)
				(end 136.35863 -79.659226)
			)
			(arc
				(start 136.35863 -68.303902)
				(mid 136.397314 -68.109513)
				(end 136.507474 -67.944746)
			)
			(arc
				(start 137.49655 -66.95567)
				(mid 137.661318 -66.845512)
				(end 137.855706 -66.806826)
			)
			(arc
				(start 139.442444 -66.806826)
				(mid 139.460379 -66.803555)
				(end 139.475972 -66.794126)
			)
			(arc
				(start 139.475972 -66.794126)
				(mid 139.749442 -66.630021)
				(end 140.06322 -66.572892)
			)
			(arc
				(start 140.06322 -66.572892)
				(mid 140.377013 -66.629983)
				(end 140.650468 -66.794126)
			)
			(arc
				(start 140.650468 -66.794126)
				(mid 140.666078 -66.80351)
				(end 140.683996 -66.806826)
			)
			(arc
				(start 142.0876 -66.806826)
				(mid 142.123521 -66.791947)
				(end 142.1384 -66.756026)
			)
			(xy 142.1384 -64.131698)
			(arc
				(start 142.13713 -64.12611)
				(mid 142.120011 -64.026684)
				(end 142.11427 -63.925958)
			)
			(arc
				(start 142.11427 -63.925958)
				(mid 142.12002 -63.825234)
				(end 142.13713 -63.725806)
			)
			(xy 142.1384 -63.720218) (xy 142.1384 -63.025782)
			(arc
				(start 142.13713 -63.020194)
				(mid 142.120011 -62.920768)
				(end 142.11427 -62.820042)
			)
			(arc
				(start 142.11427 -62.820042)
				(mid 142.12002 -62.719318)
				(end 142.13713 -62.61989)
			)
			(xy 142.1384 -62.614302)
			(arc
				(start 142.1384 -47.729394)
				(mid 142.134499 -47.709871)
				(end 142.123414 -47.693326)
			)
			(arc
				(start 141.308074 -46.877986)
				(mid 141.29154 -46.866875)
				(end 141.272006 -46.863)
			)
			(arc
				(start 123.573794 -46.863)
				(mid 123.554271 -46.866901)
				(end 123.537726 -46.877986)
			)
			(arc
				(start 123.357386 -47.058326)
				(mid 123.346275 -47.07486)
				(end 123.3424 -47.094394)
			)
			(arc
				(start 123.3424 -79.651606)
				(mid 123.346301 -79.671129)
				(end 123.357386 -79.687674)
			)
			(arc
				(start 123.664726 -79.995014)
				(mid 123.68126 -80.006125)
				(end 123.700794 -80.01)
			)
		)
		(stroke
			(width 0)
			(type solid)
		)
		(fill yes)
		(layer "In5.Cu")
		(net "P52V_HS2_DRAIN_1")
	)
	(gr_poly
		(pts
			(arc
				(start 323.745606 -80.01)
				(mid 323.765129 -80.006099)
				(end 323.781674 -79.995014)
			)
			(arc
				(start 324.089014 -79.687674)
				(mid 324.100125 -79.67114)
				(end 324.104 -79.651606)
			)
			(arc
				(start 324.104 -47.094394)
				(mid 324.100099 -47.074871)
				(end 324.089014 -47.058326)
			)
			(arc
				(start 323.908674 -46.877986)
				(mid 323.89214 -46.866875)
				(end 323.872606 -46.863)
			)
			(arc
				(start 305.3588 -46.863)
				(mid 305.322879 -46.877879)
				(end 305.308 -46.9138)
			)
			(arc
				(start 305.308 -62.242954)
				(mid 305.310753 -62.259451)
				(end 305.318668 -62.274196)
			)
			(arc
				(start 305.318668 -62.274196)
				(mid 305.457751 -62.531519)
				(end 305.505866 -62.820042)
			)
			(arc
				(start 305.505866 -62.820042)
				(mid 305.462214 -63.095019)
				(end 305.335686 -63.343028)
			)
			(arc
				(start 305.335686 -63.343028)
				(mid 305.325927 -63.373)
				(end 305.335686 -63.402972)
			)
			(arc
				(start 305.335686 -63.402972)
				(mid 305.462208 -63.650983)
				(end 305.505866 -63.925958)
			)
			(arc
				(start 305.505866 -63.925958)
				(mid 305.45777 -64.214488)
				(end 305.318668 -64.471804)
			)
			(arc
				(start 305.318668 -64.471804)
				(mid 305.310697 -64.48653)
				(end 305.308 -64.503046)
			)
			(arc
				(start 305.308 -66.78549)
				(mid 305.322879 -66.821411)
				(end 305.3588 -66.83629)
			)
			(arc
				(start 306.81422 -66.83629)
				(mid 306.833245 -66.832593)
				(end 306.849526 -66.822066)
			)
			(arc
				(start 306.849526 -66.822066)
				(mid 307.467 -66.57292)
				(end 308.084474 -66.822066)
			)
			(arc
				(start 308.084474 -66.822066)
				(mid 308.100741 -66.832627)
				(end 308.11978 -66.83629)
			)
			(arc
				(start 309.808372 -66.83629)
				(mid 310.002761 -66.874974)
				(end 310.167528 -66.985134)
			)
			(arc
				(start 311.081166 -67.898772)
				(mid 311.191324 -68.06354)
				(end 311.23001 -68.257928)
			)
			(arc
				(start 311.23001 -79.613252)
				(mid 311.233911 -79.632775)
				(end 311.244996 -79.64932)
			)
			(arc
				(start 311.59069 -79.995014)
				(mid 311.607224 -80.006125)
				(end 311.626758 -80.01)
			)
		)
		(stroke
			(width 0)
			(type solid)
		)
		(fill yes)
		(layer "In5.Cu")
		(net "P52V_HS1_DRAIN_1")
	)
	(gr_poly
		(pts
			(arc
				(start 335.427574 -39.920672)
				(mid 335.447097 -39.916771)
				(end 335.463642 -39.905686)
			)
			(arc
				(start 335.533746 -39.835582)
				(mid 335.544857 -39.819048)
				(end 335.548732 -39.799514)
			)
			(arc
				(start 335.548732 -39.398448)
				(mid 335.544831 -39.378925)
				(end 335.533746 -39.36238)
			)
			(arc
				(start 335.3816 -39.210234)
				(mid 335.365066 -39.199123)
				(end 335.345532 -39.195248)
			)
			(arc
				(start 332.266036 -39.195248)
				(mid 332.071647 -39.156564)
				(end 331.90688 -39.046404)
			)
			(arc
				(start 329.260454 -36.399978)
				(mid 329.150296 -36.23521)
				(end 329.11161 -36.040822)
			)
			(arc
				(start 329.11161 -30.31998)
				(mid 329.150294 -30.125591)
				(end 329.260454 -29.960824)
			)
			(arc
				(start 329.740514 -29.480764)
				(mid 329.905282 -29.370606)
				(end 330.09967 -29.33192)
			)
			(arc
				(start 335.94675 -29.33192)
				(mid 335.966273 -29.328019)
				(end 335.982818 -29.316934)
			)
			(arc
				(start 336.134964 -29.164788)
				(mid 336.146075 -29.148254)
				(end 336.14995 -29.12872)
			)
			(arc
				(start 336.14995 -25.176734)
				(mid 336.146049 -25.157211)
				(end 336.134964 -25.140666)
			)
			(arc
				(start 335.854802 -24.860504)
				(mid 335.838268 -24.849393)
				(end 335.818734 -24.845518)
			)
			(arc
				(start 330.355956 -24.845518)
				(mid 330.161567 -24.806834)
				(end 329.9968 -24.696674)
			)
			(arc
				(start 329.260962 -23.960836)
				(mid 329.150804 -23.796068)
				(end 329.112118 -23.60168)
			)
			(arc
				(start 329.112118 -19.02714)
				(mid 329.150802 -18.832751)
				(end 329.260962 -18.667984)
			)
			(arc
				(start 329.83678 -18.092166)
				(mid 330.001548 -17.982008)
				(end 330.195936 -17.943322)
			)
			(arc
				(start 335.978754 -17.943322)
				(mid 335.998277 -17.939421)
				(end 336.014822 -17.928336)
			)
			(arc
				(start 336.198972 -17.744186)
				(mid 336.210083 -17.727652)
				(end 336.213958 -17.708118)
			)
			(arc
				(start 336.213958 -16.1544)
				(mid 336.199079 -16.118479)
				(end 336.163158 -16.1036)
			)
			(arc
				(start 325.1708 -16.1036)
				(mid 325.134879 -16.118479)
				(end 325.12 -16.1544)
			)
			(arc
				(start 325.12 -39.869872)
				(mid 325.134879 -39.905793)
				(end 325.1708 -39.920672)
			)
		)
		(stroke
			(width 0)
			(type solid)
		)
		(fill yes)
		(layer "In5.Cu")
		(net "P52V_HS1_GATE2_R")
	)
	(gr_poly
		(pts
			(arc
				(start 122.2756 -82.042)
				(mid 122.311521 -82.027121)
				(end 122.3264 -81.9912)
			)
			(arc
				(start 122.3264 -55.607204)
				(mid 122.311521 -55.571283)
				(end 122.2756 -55.556404)
			)
			(arc
				(start 112.32896 -55.556404)
				(mid 112.309437 -55.560305)
				(end 112.292892 -55.57139)
			)
			(arc
				(start 111.932212 -55.93207)
				(mid 111.921101 -55.948604)
				(end 111.917226 -55.968138)
			)
			(arc
				(start 111.917226 -56.344566)
				(mid 111.921127 -56.364089)
				(end 111.932212 -56.380634)
			)
			(arc
				(start 112.18037 -56.628792)
				(mid 112.196904 -56.639903)
				(end 112.216438 -56.643778)
			)
			(arc
				(start 118.15953 -56.643778)
				(mid 118.353919 -56.682462)
				(end 118.518686 -56.792622)
			)
			(arc
				(start 119.478298 -57.752234)
				(mid 119.588456 -57.917002)
				(end 119.627142 -58.11139)
			)
			(arc
				(start 119.627142 -62.622176)
				(mid 119.588458 -62.816565)
				(end 119.478298 -62.981332)
			)
			(arc
				(start 118.39067 -64.06896)
				(mid 118.225902 -64.179118)
				(end 118.031514 -64.217804)
			)
			(arc
				(start 112.280192 -64.217804)
				(mid 112.260669 -64.221705)
				(end 112.244124 -64.23279)
			)
			(arc
				(start 111.931958 -64.544956)
				(mid 111.920847 -64.56149)
				(end 111.916972 -64.581024)
			)
			(arc
				(start 111.916972 -67.157346)
				(mid 111.920873 -67.176869)
				(end 111.931958 -67.193414)
			)
			(arc
				(start 112.404144 -67.6656)
				(mid 112.420678 -67.676711)
				(end 112.440212 -67.680586)
			)
			(arc
				(start 117.966998 -67.680586)
				(mid 118.161387 -67.71927)
				(end 118.326154 -67.82943)
			)
			(arc
				(start 119.574056 -69.077332)
				(mid 119.684214 -69.2421)
				(end 119.7229 -69.436488)
			)
			(arc
				(start 119.7229 -73.65873)
				(mid 119.684216 -73.853119)
				(end 119.574056 -74.017886)
			)
			(arc
				(start 118.582186 -75.009756)
				(mid 118.417418 -75.119914)
				(end 118.22303 -75.1586)
			)
			(arc
				(start 111.928402 -75.1586)
				(mid 111.908879 -75.162501)
				(end 111.892334 -75.173586)
			)
			(arc
				(start 111.69142 -75.3745)
				(mid 111.680309 -75.391034)
				(end 111.676434 -75.410568)
			)
			(arc
				(start 111.676434 -79.630524)
				(mid 111.680335 -79.650047)
				(end 111.69142 -79.666592)
			)
			(arc
				(start 114.051842 -82.027014)
				(mid 114.068376 -82.038125)
				(end 114.08791 -82.042)
			)
		)
		(stroke
			(width 0)
			(type solid)
		)
		(fill yes)
		(layer "In5.Cu")
		(net "P52V_HS2_GATE1_R")
	)
	(gr_poly
		(pts
			(arc
				(start 122.2756 -45.339)
				(mid 122.311521 -45.324121)
				(end 122.3264 -45.2882)
			)
			(arc
				(start 122.3264 -19.285204)
				(mid 122.311521 -19.249283)
				(end 122.2756 -19.234404)
			)
			(arc
				(start 112.332008 -19.234404)
				(mid 112.312485 -19.238305)
				(end 112.29594 -19.24939)
			)
			(arc
				(start 112.047528 -19.497802)
				(mid 112.036417 -19.514336)
				(end 112.032542 -19.53387)
			)
			(arc
				(start 112.032542 -23.22957)
				(mid 112.036443 -23.249093)
				(end 112.047528 -23.265638)
			)
			(arc
				(start 112.231932 -23.450042)
				(mid 112.248466 -23.461153)
				(end 112.268 -23.465028)
			)
			(arc
				(start 118.786656 -23.465028)
				(mid 118.981045 -23.503712)
				(end 119.145812 -23.613872)
			)
			(arc
				(start 119.753634 -24.221694)
				(mid 119.863792 -24.386462)
				(end 119.902478 -24.58085)
			)
			(arc
				(start 119.902478 -29.507434)
				(mid 119.863794 -29.701823)
				(end 119.753634 -29.86659)
			)
			(arc
				(start 119.273828 -30.346396)
				(mid 119.10906 -30.456554)
				(end 118.914672 -30.49524)
			)
			(arc
				(start 112.363758 -30.49524)
				(mid 112.344235 -30.499141)
				(end 112.32769 -30.510226)
			)
			(arc
				(start 111.983266 -30.85465)
				(mid 111.972155 -30.871184)
				(end 111.96828 -30.890718)
			)
			(arc
				(start 111.96828 -34.362644)
				(mid 111.972181 -34.382167)
				(end 111.983266 -34.398712)
			)
			(arc
				(start 112.327182 -34.742628)
				(mid 112.343716 -34.753739)
				(end 112.36325 -34.757614)
			)
			(arc
				(start 118.818152 -34.757614)
				(mid 119.012541 -34.796298)
				(end 119.177308 -34.906458)
			)
			(arc
				(start 119.881142 -35.610292)
				(mid 119.9913 -35.77506)
				(end 120.029986 -35.969448)
			)
			(arc
				(start 120.029986 -42.111676)
				(mid 119.991302 -42.306065)
				(end 119.881142 -42.470832)
			)
			(arc
				(start 118.505478 -43.846496)
				(mid 118.34071 -43.956654)
				(end 118.146322 -43.99534)
			)
			(arc
				(start 112.395508 -43.99534)
				(mid 112.375985 -43.999241)
				(end 112.35944 -44.010326)
			)
			(arc
				(start 112.01527 -44.354496)
				(mid 112.004159 -44.37103)
				(end 112.000284 -44.390564)
			)
			(arc
				(start 112.000284 -45.079412)
				(mid 112.004185 -45.098935)
				(end 112.01527 -45.11548)
			)
			(arc
				(start 112.223804 -45.324014)
				(mid 112.240338 -45.335125)
				(end 112.259872 -45.339)
			)
		)
		(stroke
			(width 0)
			(type solid)
		)
		(fill yes)
		(layer "In5.Cu")
		(net "P52V_HS2_GATE2_R")
	)
	(gr_poly
		(pts
			(arc
				(start 141.221206 -45.847)
				(mid 141.240729 -45.843099)
				(end 141.257274 -45.832014)
			)
			(arc
				(start 142.123414 -44.965874)
				(mid 142.134525 -44.94934)
				(end 142.1384 -44.929806)
			)
			(arc
				(start 142.1384 -41.667176)
				(mid 142.131291 -41.641003)
				(end 142.11173 -41.622218)
			)
			(arc
				(start 142.11173 -41.622218)
				(mid 141.769734 -41.29524)
				(end 141.643862 -40.839136)
			)
			(arc
				(start 141.643862 -40.839136)
				(mid 141.647416 -40.759442)
				(end 141.658086 -40.680386)
			)
			(xy 141.660372 -40.66794) (xy 141.653006 -40.644318)
			(arc
				(start 141.511274 -40.502586)
				(mid 141.49474 -40.491475)
				(end 141.475206 -40.4876)
			)
			(arc
				(start 139.1666 -40.4876)
				(mid 138.972211 -40.448916)
				(end 138.807444 -40.338756)
			)
			(arc
				(start 137.689844 -39.221156)
				(mid 137.579686 -39.056388)
				(end 137.541 -38.862)
			)
			(arc
				(start 137.541 -33.8328)
				(mid 137.579684 -33.638411)
				(end 137.689844 -33.473644)
			)
			(arc
				(start 137.989564 -33.173924)
				(mid 138.154332 -33.063766)
				(end 138.34872 -33.02508)
			)
			(arc
				(start 139.38885 -33.02508)
				(mid 139.408704 -33.02104)
				(end 139.425426 -33.009586)
			)
			(arc
				(start 139.425426 -33.009586)
				(mid 140.06322 -32.740107)
				(end 140.701014 -33.009586)
			)
			(arc
				(start 140.701014 -33.009586)
				(mid 140.717722 -33.021073)
				(end 140.73759 -33.02508)
			)
			(arc
				(start 141.520926 -33.02508)
				(mid 141.540449 -33.021179)
				(end 141.556994 -33.010094)
			)
			(arc
				(start 142.123414 -32.443674)
				(mid 142.134525 -32.42714)
				(end 142.1384 -32.407606)
			)
			(xy 142.1384 -30.298898)
			(arc
				(start 142.13713 -30.29331)
				(mid 142.120011 -30.193884)
				(end 142.11427 -30.093158)
			)
			(arc
				(start 142.11427 -30.093158)
				(mid 142.12002 -29.992434)
				(end 142.13713 -29.893006)
			)
			(xy 142.1384 -29.887418) (xy 142.1384 -29.192982)
			(arc
				(start 142.13713 -29.187394)
				(mid 142.120011 -29.087968)
				(end 142.11427 -28.987242)
			)
			(arc
				(start 142.11427 -28.987242)
				(mid 142.12002 -28.886518)
				(end 142.13713 -28.78709)
			)
			(xy 142.1384 -28.781502)
			(arc
				(start 142.1384 -13.439394)
				(mid 142.134499 -13.419871)
				(end 142.123414 -13.403326)
			)
			(arc
				(start 141.689074 -12.968986)
				(mid 141.67254 -12.957875)
				(end 141.653006 -12.954)
			)
			(arc
				(start 123.700794 -12.954)
				(mid 123.681271 -12.957901)
				(end 123.664726 -12.968986)
			)
			(arc
				(start 123.357386 -13.276326)
				(mid 123.346275 -13.29286)
				(end 123.3424 -13.312394)
			)
			(arc
				(start 123.3424 -45.615606)
				(mid 123.346301 -45.635129)
				(end 123.357386 -45.651674)
			)
			(arc
				(start 123.537726 -45.832014)
				(mid 123.55426 -45.843125)
				(end 123.573794 -45.847)
			)
		)
		(stroke
			(width 0)
			(type solid)
		)
		(fill yes)
		(layer "In5.Cu")
		(net "P52V_HS2_DRAIN_2")
	)
	(gr_poly
		(pts
			(arc
				(start 328.507852 -80.01)
				(mid 328.527375 -80.006099)
				(end 328.54392 -79.995014)
			)
			(arc
				(start 329.080114 -79.45882)
				(mid 329.091225 -79.442286)
				(end 329.0951 -79.422752)
			)
			(arc
				(start 329.0951 -75.586336)
				(mid 329.133784 -75.391947)
				(end 329.243944 -75.22718)
			)
			(arc
				(start 329.627992 -74.843132)
				(mid 329.79276 -74.732974)
				(end 329.987148 -74.694288)
			)
			(arc
				(start 336.025998 -74.694288)
				(mid 336.045521 -74.690387)
				(end 336.062066 -74.679302)
			)
			(arc
				(start 336.262218 -74.47915)
				(mid 336.273329 -74.462616)
				(end 336.277204 -74.443082)
			)
			(arc
				(start 336.277204 -70.603364)
				(mid 336.273303 -70.583841)
				(end 336.262218 -70.567296)
			)
			(arc
				(start 335.982056 -70.287134)
				(mid 335.965522 -70.276023)
				(end 335.945988 -70.272148)
			)
			(arc
				(start 330.16317 -70.272148)
				(mid 329.968781 -70.233464)
				(end 329.804014 -70.123304)
			)
			(arc
				(start 329.164188 -69.483478)
				(mid 329.05403 -69.31871)
				(end 329.015344 -69.124322)
			)
			(arc
				(start 329.015344 -64.29375)
				(mid 329.054028 -64.099361)
				(end 329.164188 -63.934594)
			)
			(arc
				(start 330.347828 -62.750954)
				(mid 330.512596 -62.640796)
				(end 330.706984 -62.60211)
			)
			(arc
				(start 335.594198 -62.60211)
				(mid 335.613721 -62.598209)
				(end 335.630266 -62.587124)
			)
			(arc
				(start 336.102198 -62.115192)
				(mid 336.113309 -62.098658)
				(end 336.117184 -62.079124)
			)
			(arc
				(start 336.117184 -59.502802)
				(mid 336.113283 -59.483279)
				(end 336.102198 -59.466734)
			)
			(arc
				(start 335.88579 -59.250326)
				(mid 335.869256 -59.239215)
				(end 335.849722 -59.23534)
			)
			(arc
				(start 330.226924 -59.23534)
				(mid 330.032535 -59.196656)
				(end 329.867768 -59.086496)
			)
			(arc
				(start 329.387962 -58.60669)
				(mid 329.277804 -58.441922)
				(end 329.239118 -58.247534)
			)
			(arc
				(start 329.239118 -52.553108)
				(mid 329.277802 -52.358719)
				(end 329.387962 -52.193952)
			)
			(arc
				(start 329.707748 -51.874166)
				(mid 329.872516 -51.764008)
				(end 330.066904 -51.725322)
			)
			(arc
				(start 335.089246 -51.725322)
				(mid 335.108769 -51.721421)
				(end 335.125314 -51.710336)
			)
			(arc
				(start 335.612486 -51.223164)
				(mid 335.623597 -51.20663)
				(end 335.627472 -51.187096)
			)
			(arc
				(start 335.627472 -50.338228)
				(mid 335.623571 -50.318705)
				(end 335.612486 -50.30216)
			)
			(arc
				(start 335.060544 -49.750218)
				(mid 335.04401 -49.739107)
				(end 335.024476 -49.735232)
			)
			(arc
				(start 325.1708 -49.735232)
				(mid 325.134879 -49.750111)
				(end 325.12 -49.786032)
			)
			(xy 325.12 -79.883) (xy 325.119492 -79.904082) (xy 325.118984 -79.914496) (xy 325.12635 -79.9338)
			(arc
				(start 325.184262 -79.994252)
				(mid 325.201056 -80.005929)
				(end 325.221092 -80.01)
			)
		)
		(stroke
			(width 0)
			(type solid)
		)
		(fill yes)
		(layer "In5.Cu")
		(net "P52V_HS1_GATE1_R")
	)
	(gr_poly
		(pts
			(arc
				(start 324.0532 -45.847)
				(mid 324.089121 -45.832121)
				(end 324.104 -45.7962)
			)
			(arc
				(start 324.104 -13.312394)
				(mid 324.100099 -13.292871)
				(end 324.089014 -13.276326)
			)
			(arc
				(start 323.781674 -12.968986)
				(mid 323.76514 -12.957875)
				(end 323.745606 -12.954)
			)
			(arc
				(start 305.793394 -12.954)
				(mid 305.773871 -12.957901)
				(end 305.757326 -12.968986)
			)
			(arc
				(start 305.322986 -13.403326)
				(mid 305.311875 -13.41986)
				(end 305.308 -13.439394)
			)
			(arc
				(start 305.308 -28.410154)
				(mid 305.310753 -28.426651)
				(end 305.318668 -28.441396)
			)
			(arc
				(start 305.318668 -28.441396)
				(mid 305.457751 -28.698719)
				(end 305.505866 -28.987242)
			)
			(arc
				(start 305.505866 -28.987242)
				(mid 305.462214 -29.262219)
				(end 305.335686 -29.510228)
			)
			(arc
				(start 305.335686 -29.510228)
				(mid 305.325927 -29.5402)
				(end 305.335686 -29.570172)
			)
			(arc
				(start 305.335686 -29.570172)
				(mid 305.462208 -29.818183)
				(end 305.505866 -30.093158)
			)
			(arc
				(start 305.505866 -30.093158)
				(mid 305.45777 -30.381688)
				(end 305.318668 -30.639004)
			)
			(arc
				(start 305.318668 -30.639004)
				(mid 305.310697 -30.65373)
				(end 305.308 -30.670246)
			)
			(arc
				(start 305.308 -32.712406)
				(mid 305.311901 -32.731929)
				(end 305.322986 -32.748474)
			)
			(arc
				(start 305.53152 -32.957008)
				(mid 305.548054 -32.968119)
				(end 305.567588 -32.971994)
			)
			(arc
				(start 306.848764 -32.971994)
				(mid 306.866531 -32.968786)
				(end 306.882038 -32.959548)
			)
			(arc
				(start 306.882038 -32.959548)
				(mid 307.467 -32.740071)
				(end 308.051962 -32.959548)
			)
			(arc
				(start 308.051962 -32.959548)
				(mid 308.067477 -32.968763)
				(end 308.085236 -32.971994)
			)
			(arc
				(start 309.723028 -32.971994)
				(mid 309.917417 -33.010678)
				(end 310.082184 -33.120838)
			)
			(arc
				(start 311.103518 -34.142172)
				(mid 311.213676 -34.30694)
				(end 311.252362 -34.501328)
			)
			(arc
				(start 311.252362 -39.039038)
				(mid 311.213678 -39.233427)
				(end 311.103518 -39.398194)
			)
			(arc
				(start 309.629556 -40.872156)
				(mid 309.464788 -40.982314)
				(end 309.2704 -41.021)
			)
			(arc
				(start 305.844194 -41.021)
				(mid 305.824671 -41.024901)
				(end 305.808126 -41.035986)
			)
			(xy 305.748944 -41.095168)
			(arc
				(start 305.745134 -41.102788)
				(mid 305.574995 -41.341081)
				(end 305.336702 -41.51122)
			)
			(xy 305.329082 -41.51503)
			(arc
				(start 305.322986 -41.521126)
				(mid 305.311875 -41.53766)
				(end 305.308 -41.557194)
			)
			(arc
				(start 305.308 -45.158406)
				(mid 305.311901 -45.177929)
				(end 305.322986 -45.194474)
			)
			(arc
				(start 305.960526 -45.832014)
				(mid 305.97706 -45.843125)
				(end 305.996594 -45.847)
			)
		)
		(stroke
			(width 0)
			(type solid)
		)
		(fill yes)
		(layer "In5.Cu")
		(net "P52V_HS1_DRAIN_2")
	)
	(gr_poly
		(pts
			(xy 151.275796 -80.228948) (xy 151.285865 -80.228524) (xy 151.304466 -80.220805) (xy 151.311864 -80.213962)
			(xy 152.065736 -79.46009) (xy 152.072588 -79.452694) (xy 152.080328 -79.434095) (xy 152.080722 -79.424022)
			(xy 152.080722 -63.40221) (xy 152.081243 -63.368949) (xy 152.089928 -63.302997) (xy 152.10715 -63.238744)
			(xy 152.132615 -63.17729) (xy 152.165887 -63.119687) (xy 152.206395 -63.066921) (xy 152.229566 -63.043054)
			(xy 160.261808 -55.010812) (xy 160.285686 -54.987651) (xy 160.338447 -54.947136) (xy 160.396047 -54.913857)
			(xy 160.457499 -54.888385) (xy 160.521751 -54.871156) (xy 160.587703 -54.862464) (xy 160.620964 -54.861968)
			(xy 175.379888 -54.861968) (xy 175.389959 -54.861546) (xy 175.408563 -54.853831) (xy 175.415956 -54.846982)
			(xy 175.779176 -54.483762) (xy 175.786019 -54.476363) (xy 175.793744 -54.457764) (xy 175.794162 -54.447694)
			(xy 175.794162 -53.658516) (xy 175.793723 -53.648453) (xy 175.785983 -53.629875) (xy 175.779176 -53.622448)
			(xy 173.785022 -51.628294) (xy 173.777619 -51.62146) (xy 173.759021 -51.613755) (xy 173.748954 -51.613308)
			(xy 172.583348 -51.613308) (xy 172.550087 -51.61279) (xy 172.484133 -51.604108) (xy 172.419878 -51.586888)
			(xy 172.358423 -51.561423) (xy 172.300819 -51.528151) (xy 172.248054 -51.48764) (xy 172.224192 -51.464464)
			(xy 171.815506 -51.055778) (xy 171.792346 -51.0319) (xy 171.751833 -50.979138) (xy 171.718556 -50.921538)
			(xy 171.693086 -50.860086) (xy 171.675859 -50.795834) (xy 171.667169 -50.729883) (xy 171.666662 -50.696622)
			(xy 171.666662 -43.570398) (xy 171.667183 -43.537138) (xy 171.67587 -43.471187) (xy 171.693095 -43.406936)
			(xy 171.718563 -43.345483) (xy 171.751837 -43.287883) (xy 171.792348 -43.235122) (xy 171.815506 -43.211242)
			(xy 173.556676 -41.470072) (xy 173.580556 -41.446916) (xy 173.63332 -41.406411) (xy 173.690921 -41.373143)
			(xy 173.752373 -41.347681) (xy 173.816624 -41.330462) (xy 173.882573 -41.32178) (xy 173.915832 -41.321228)
			(xy 191.747394 -41.321228) (xy 191.780655 -41.321749) (xy 191.846606 -41.330434) (xy 191.910859 -41.347657)
			(xy 191.972313 -41.373123) (xy 192.029915 -41.406395) (xy 192.08268 -41.446904) (xy 192.10655 -41.470072)
			(xy 197.992492 -47.356014) (xy 197.999886 -47.362871) (xy 198.018485 -47.370622) (xy 198.02856 -47.371)
			(xy 209.852006 -47.371) (xy 209.862076 -47.370576) (xy 209.880679 -47.36286) (xy 209.888074 -47.356014)
			(xy 210.449414 -46.794674) (xy 210.456266 -46.787278) (xy 210.464004 -46.768679) (xy 210.4644 -46.758606)
			(xy 210.4644 -30.457394) (xy 210.463976 -30.447324) (xy 210.45626 -30.428721) (xy 210.449414 -30.421326)
			(xy 208.999074 -28.970986) (xy 208.991678 -28.964134) (xy 208.973079 -28.956396) (xy 208.963006 -28.956)
			(xy 161.946082 -28.956) (xy 161.912822 -28.955477) (xy 161.846873 -28.946788) (xy 161.782624 -28.929561)
			(xy 161.721174 -28.90409) (xy 161.663577 -28.870813) (xy 161.610819 -28.830299) (xy 161.586926 -28.807156)
			(xy 160.321244 -27.541474) (xy 160.298087 -27.517595) (xy 160.257578 -27.464831) (xy 160.224306 -27.407231)
			(xy 160.19884 -27.345779) (xy 160.181615 -27.281528) (xy 160.172927 -27.215578) (xy 160.1724 -27.182318)
			(xy 160.1724 -16.377412) (xy 160.171979 -16.367341) (xy 160.164268 -16.348733) (xy 160.157414 -16.341344)
			(xy 156.785056 -12.968986) (xy 156.777659 -12.962137) (xy 156.75906 -12.954405) (xy 156.748988 -12.954)
			(xy 143.639794 -12.954) (xy 143.629724 -12.954424) (xy 143.611121 -12.96214) (xy 143.603726 -12.968986)
			(xy 143.169386 -13.403326) (xy 143.162534 -13.410722) (xy 143.154796 -13.429321) (xy 143.1544 -13.439394)
			(xy 143.1544 -28.086812) (xy 143.176752 -28.114498) (xy 143.194278 -28.118308) (xy 143.236229 -28.128019)
			(xy 143.318173 -28.154495) (xy 143.397174 -28.188768) (xy 143.472493 -28.230517) (xy 143.543424 -28.279349)
			(xy 143.609303 -28.334808) (xy 143.669514 -28.396375) (xy 143.723492 -28.463473) (xy 143.770733 -28.535474)
			(xy 143.810793 -28.611704) (xy 143.843298 -28.691449) (xy 143.867943 -28.773962) (xy 143.884498 -28.858471)
			(xy 143.892807 -28.944184) (xy 143.893286 -28.987242) (xy 143.89284 -29.027188) (xy 143.885653 -29.106756)
			(xy 143.87136 -29.185359) (xy 143.850075 -29.262363) (xy 143.82197 -29.337149) (xy 143.787272 -29.409112)
			(xy 143.746259 -29.477674) (xy 143.723106 -29.510228) (xy 143.717172 -29.519192) (xy 143.712701 -29.5402)
			(xy 143.717172 -29.561208) (xy 143.723106 -29.570172) (xy 143.746249 -29.602733) (xy 143.787257 -29.671295)
			(xy 143.821951 -29.743258) (xy 143.850052 -29.818043) (xy 143.871334 -29.895046) (xy 143.885626 -29.973647)
			(xy 143.892811 -30.053213) (xy 143.893286 -30.093158) (xy 143.892778 -30.136213) (xy 143.884453 -30.22192)
			(xy 143.867886 -30.306421) (xy 143.843233 -30.388926) (xy 143.810723 -30.468664) (xy 143.770662 -30.544888)
			(xy 143.723424 -30.616884) (xy 143.669451 -30.68398) (xy 143.609247 -30.745547) (xy 143.543378 -30.80101)
			(xy 143.472457 -30.849849) (xy 143.39715 -30.891608) (xy 143.318161 -30.925895) (xy 143.236229 -30.95239)
			(xy 143.194278 -30.962092) (xy 143.176752 -30.965902) (xy 143.1544 -30.993588) (xy 143.1544 -32.458406)
			(xy 143.154824 -32.468476) (xy 143.16254 -32.487079) (xy 143.169386 -32.494474) (xy 143.685006 -33.010094)
			(xy 143.692405 -33.01694) (xy 143.711003 -33.024673) (xy 143.721074 -33.02508) (xy 145.18005 -33.02508)
			(xy 145.190294 -33.024611) (xy 145.209156 -33.016612) (xy 145.216626 -33.009586) (xy 145.246136 -32.979918)
			(xy 145.309846 -32.925658) (xy 145.37837 -32.877621) (xy 145.451103 -32.836233) (xy 145.527403 -32.801859)
			(xy 145.606593 -32.774803) (xy 145.687975 -32.755305) (xy 145.770828 -32.743537) (xy 145.85442 -32.739602)
			(xy 145.938012 -32.743537) (xy 146.020865 -32.755305) (xy 146.102247 -32.774803) (xy 146.181437 -32.801859)
			(xy 146.257737 -32.836233) (xy 146.33047 -32.877621) (xy 146.398994 -32.925658) (xy 146.462704 -32.979918)
			(xy 146.492214 -33.009586) (xy 146.499661 -33.016649) (xy 146.518536 -33.024665) (xy 146.52879 -33.02508)
			(xy 147.35048 -33.02508) (xy 147.383741 -33.0256) (xy 147.449692 -33.034285) (xy 147.513945 -33.051508)
			(xy 147.575399 -33.076974) (xy 147.633 -33.110248) (xy 147.685763 -33.150759) (xy 147.709636 -33.173924)
			(xy 148.212556 -33.676844) (xy 148.235712 -33.700724) (xy 148.276218 -33.753488) (xy 148.309489 -33.811089)
			(xy 148.334953 -33.87254) (xy 148.352175 -33.936791) (xy 148.360861 -34.002741) (xy 148.3614 -34.036)
			(xy 148.3614 -38.3794) (xy 148.360879 -38.41266) (xy 148.352191 -38.47861) (xy 148.334966 -38.542861)
			(xy 148.309497 -38.604312) (xy 148.276221 -38.661911) (xy 148.235708 -38.714671) (xy 148.212556 -38.738556)
			(xy 146.612356 -40.338756) (xy 146.588476 -40.361912) (xy 146.535712 -40.402418) (xy 146.478111 -40.435689)
			(xy 146.41666 -40.461153) (xy 146.352409 -40.478375) (xy 146.286459 -40.487061) (xy 146.2532 -40.4876)
			(xy 144.292574 -40.4876) (xy 144.280913 -40.48818) (xy 144.260011 -40.49852) (xy 144.252442 -40.507412)
			(xy 144.1958 -40.58031) (xy 144.191228 -40.60317) (xy 144.194276 -40.614854) (xy 144.203403 -40.65153)
			(xy 144.216167 -40.72603) (xy 144.222575 -40.801343) (xy 144.222978 -40.839136) (xy 144.222502 -40.880237)
			(xy 144.214914 -40.962088) (xy 144.199806 -41.042889) (xy 144.177307 -41.121952) (xy 144.14761 -41.198602)
			(xy 144.110966 -41.272185) (xy 144.06769 -41.342073) (xy 144.01815 -41.407669) (xy 143.962768 -41.468415)
			(xy 143.902019 -41.523792) (xy 143.836418 -41.573327) (xy 143.766527 -41.616598) (xy 143.692942 -41.653236)
			(xy 143.61629 -41.682928) (xy 143.537225 -41.705421) (xy 143.456422 -41.720523) (xy 143.374571 -41.728105)
			(xy 143.33347 -41.728644) (xy 143.316052 -41.728547) (xy 143.281244 -41.727151) (xy 143.263874 -41.72585)
			(xy 143.253206 -41.725088) (xy 143.233394 -41.731946) (xy 143.170656 -41.789858) (xy 143.16328 -41.797381)
			(xy 143.154871 -41.816672) (xy 143.1544 -41.827196) (xy 143.1544 -60.8863) (xy 149.598912 -60.8863)
			(xy 149.602942 -60.801701) (xy 149.614995 -60.717868) (xy 149.634963 -60.635561) (xy 149.662664 -60.555524)
			(xy 149.697848 -60.478483) (xy 149.740195 -60.405135) (xy 149.789323 -60.336145) (xy 149.844787 -60.272137)
			(xy 149.906083 -60.213691) (xy 149.972658 -60.161336) (xy 150.043908 -60.115546) (xy 150.119188 -60.076737)
			(xy 150.197816 -60.04526) (xy 150.279081 -60.021399) (xy 150.362245 -60.00537) (xy 150.446557 -59.99732)
			(xy 150.488904 -59.996832) (xy 150.528495 -59.997261) (xy 150.607366 -60.004283) (xy 150.685298 -60.018299)
			(xy 150.7236 -60.028328) (xy 150.727765 -60.029405) (xy 150.73632 -60.030297) (xy 150.740618 -60.030106)
			(xy 150.755901 -60.02907) (xy 150.786515 -60.027929) (xy 150.801832 -60.02782) (xy 150.832093 -60.028115)
			(xy 150.892471 -60.032308) (xy 150.922482 -60.036202) (xy 150.927916 -60.036809) (xy 150.938811 -60.035912)
			(xy 150.944072 -60.034424) (xy 150.985684 -60.022469) (xy 151.070635 -60.005731) (xy 151.156812 -59.997337)
			(xy 151.200104 -59.996832) (xy 151.241719 -59.997325) (xy 151.324585 -60.005093) (xy 151.406363 -60.02057)
			(xy 151.446484 -60.03163) (xy 151.451259 -60.032927) (xy 151.461111 -60.033821) (xy 151.466042 -60.033408)
			(xy 151.490408 -60.030832) (xy 151.539331 -60.028037) (xy 151.563832 -60.02782) (xy 151.606191 -60.028361)
			(xy 151.690524 -60.036417) (xy 151.77371 -60.052453) (xy 151.854996 -60.076323) (xy 151.933644 -60.107811)
			(xy 152.008943 -60.146633) (xy 152.080211 -60.192436) (xy 152.146802 -60.244807) (xy 152.208114 -60.303269)
			(xy 152.263591 -60.367296) (xy 152.312731 -60.436305) (xy 152.355089 -60.509673) (xy 152.390281 -60.586735)
			(xy 152.417989 -60.666794) (xy 152.437961 -60.749123) (xy 152.450018 -60.832978) (xy 152.454049 -60.9176)
			(xy 152.450018 -61.002222) (xy 152.437961 -61.086077) (xy 152.417989 -61.168406) (xy 152.390281 -61.248465)
			(xy 152.355089 -61.325527) (xy 152.312731 -61.398895) (xy 152.263591 -61.467904) (xy 152.208114 -61.531931)
			(xy 152.146802 -61.590393) (xy 152.080211 -61.642764) (xy 152.008943 -61.688567) (xy 151.933644 -61.727389)
			(xy 151.854996 -61.758877) (xy 151.77371 -61.782747) (xy 151.690524 -61.798783) (xy 151.606191 -61.806839)
			(xy 151.563832 -61.807344) (xy 151.522083 -61.806861) (xy 151.438953 -61.799037) (xy 151.356924 -61.783444)
			(xy 151.31669 -61.772292) (xy 151.311917 -61.770986) (xy 151.302063 -61.770098) (xy 151.297132 -61.770514)
			(xy 151.272952 -61.773004) (xy 151.224411 -61.775674) (xy 151.200104 -61.775848) (xy 151.169974 -61.775594)
			(xy 151.109852 -61.771527) (xy 151.079962 -61.76772) (xy 151.074527 -61.767126) (xy 151.063633 -61.768014)
			(xy 151.058372 -61.769498) (xy 151.016682 -61.781509) (xy 150.931565 -61.798338) (xy 150.845214 -61.806808)
			(xy 150.801832 -61.807344) (xy 150.762109 -61.806904) (xy 150.68298 -61.7998) (xy 150.604797 -61.785683)
			(xy 150.566374 -61.775594) (xy 150.562211 -61.774509) (xy 150.553654 -61.773623) (xy 150.549356 -61.773816)
			(xy 150.534261 -61.774769) (xy 150.504029 -61.775786) (xy 150.488904 -61.775848) (xy 150.446557 -61.77528)
			(xy 150.362245 -61.76723) (xy 150.279081 -61.751201) (xy 150.197816 -61.72734) (xy 150.119188 -61.695863)
			(xy 150.043908 -61.657054) (xy 149.972658 -61.611264) (xy 149.906083 -61.558909) (xy 149.844787 -61.500463)
			(xy 149.789323 -61.436455) (xy 149.740195 -61.367465) (xy 149.697848 -61.294117) (xy 149.662664 -61.217076)
			(xy 149.634963 -61.137039) (xy 149.614995 -61.054732) (xy 149.602942 -60.970899) (xy 149.598912 -60.8863)
			(xy 143.1544 -60.8863) (xy 143.1544 -61.919612) (xy 143.176752 -61.947298) (xy 143.194278 -61.951108)
			(xy 143.236229 -61.960819) (xy 143.318173 -61.987295) (xy 143.397174 -62.021568) (xy 143.472493 -62.063317)
			(xy 143.543424 -62.112149) (xy 143.609303 -62.167608) (xy 143.669514 -62.229175) (xy 143.723492 -62.296273)
			(xy 143.770733 -62.368274) (xy 143.810793 -62.444504) (xy 143.843298 -62.524249) (xy 143.867943 -62.606762)
			(xy 143.884498 -62.691271) (xy 143.892807 -62.776984) (xy 143.893286 -62.820042) (xy 143.89284 -62.859988)
			(xy 143.885653 -62.939556) (xy 143.87136 -63.018159) (xy 143.850075 -63.095163) (xy 143.82197 -63.169949)
			(xy 143.787272 -63.241912) (xy 143.746259 -63.310474) (xy 143.723106 -63.343028) (xy 143.717172 -63.351992)
			(xy 143.712701 -63.373) (xy 143.717172 -63.394008) (xy 143.723106 -63.402972) (xy 143.746249 -63.435533)
			(xy 143.787257 -63.504095) (xy 143.821951 -63.576058) (xy 143.850052 -63.650843) (xy 143.871334 -63.727846)
			(xy 143.885626 -63.806447) (xy 143.892811 -63.886013) (xy 143.893286 -63.925958) (xy 143.892778 -63.969013)
			(xy 143.884453 -64.05472) (xy 143.867886 -64.139221) (xy 143.843233 -64.221726) (xy 143.810723 -64.301464)
			(xy 143.770662 -64.377688) (xy 143.723424 -64.449684) (xy 143.669451 -64.51678) (xy 143.609247 -64.578347)
			(xy 143.543378 -64.63381) (xy 143.472457 -64.682649) (xy 143.39715 -64.724408) (xy 143.318161 -64.758695)
			(xy 143.236229 -64.78519) (xy 143.194278 -64.794892) (xy 143.176752 -64.798702) (xy 143.1544 -64.826388)
			(xy 143.1544 -66.756026) (xy 143.154893 -66.76603) (xy 143.162557 -66.784513) (xy 143.176709 -66.798658)
			(xy 143.195196 -66.806312) (xy 143.2052 -66.806826) (xy 145.801842 -66.806826) (xy 145.811034 -66.806436)
			(xy 145.828224 -66.799921) (xy 145.83537 -66.794126) (xy 145.865785 -66.768004) (xy 145.930547 -66.720732)
			(xy 145.999299 -66.679479) (xy 146.071485 -66.644579) (xy 146.146518 -66.616315) (xy 146.223789 -66.594916)
			(xy 146.302673 -66.580557) (xy 146.382528 -66.573354) (xy 146.422618 -66.572892) (xy 146.462709 -66.573322)
			(xy 146.542568 -66.580516) (xy 146.621455 -66.594871) (xy 146.69873 -66.61627) (xy 146.773763 -66.644539)
			(xy 146.845947 -66.679449) (xy 146.914695 -66.720717) (xy 146.979448 -66.768006) (xy 147.009866 -66.794126)
			(xy 147.017023 -66.799901) (xy 147.034207 -66.806413) (xy 147.043394 -66.806826) (xy 149.521926 -66.806826)
			(xy 149.555186 -66.807349) (xy 149.621135 -66.816038) (xy 149.685386 -66.833264) (xy 149.746837 -66.858733)
			(xy 149.804436 -66.892007) (xy 149.857198 -66.932518) (xy 149.881082 -66.95567) (xy 151.077168 -68.151756)
			(xy 151.100327 -68.175634) (xy 151.140839 -68.228396) (xy 151.174114 -68.285996) (xy 151.199581 -68.347449)
			(xy 151.216805 -68.411701) (xy 151.225491 -68.477652) (xy 151.226012 -68.510912) (xy 151.226012 -74.081386)
			(xy 151.225492 -74.114646) (xy 151.216806 -74.180598) (xy 151.199582 -74.24485) (xy 151.174115 -74.306303)
			(xy 151.14084 -74.363903) (xy 151.100329 -74.416665) (xy 151.077168 -74.440542) (xy 149.646894 -75.870816)
			(xy 149.640051 -75.878216) (xy 149.632323 -75.896814) (xy 149.631908 -75.906884) (xy 149.631908 -79.977742)
			(xy 149.632339 -79.987809) (xy 149.640065 -80.006401) (xy 149.646894 -80.01381) (xy 149.847046 -80.213962)
			(xy 149.854445 -80.220805) (xy 149.873044 -80.228529) (xy 149.883114 -80.228948)
		)
		(stroke
			(width 0)
			(type solid)
		)
		(fill yes)
		(layer "In5.Cu")
		(net "P52V_2")
	)
	(gr_poly
		(pts
			(xy 474.000068 -199.098154) (xy 474.055876 -199.097646) (xy 474.167179 -199.089307) (xy 474.277548 -199.072673)
			(xy 474.386365 -199.047838) (xy 474.493022 -199.01494) (xy 474.596923 -198.974164) (xy 474.697485 -198.925736)
			(xy 474.794147 -198.869929) (xy 474.886368 -198.807054) (xy 474.973633 -198.737463) (xy 475.055452 -198.661545)
			(xy 475.13137 -198.579725) (xy 475.20096 -198.49246) (xy 475.263834 -198.400239) (xy 475.319641 -198.303576)
			(xy 475.368068 -198.203014) (xy 475.408844 -198.099113) (xy 475.441741 -197.992456) (xy 475.466575 -197.883638)
			(xy 475.483208 -197.773269) (xy 475.491546 -197.661966) (xy 475.492064 -197.606158) (xy 475.492064 -135.770112)
			(xy 475.491555 -135.714305) (xy 475.483215 -135.603002) (xy 475.46658 -135.492634) (xy 475.441744 -135.383817)
			(xy 475.408845 -135.277161) (xy 475.368068 -135.173262) (xy 475.31964 -135.072701) (xy 475.263833 -134.97604)
			(xy 475.200958 -134.88382) (xy 475.131367 -134.796556) (xy 475.055449 -134.714737) (xy 474.973629 -134.63882)
			(xy 474.886364 -134.569231) (xy 474.794143 -134.506357) (xy 474.697481 -134.450551) (xy 474.596919 -134.402124)
			(xy 474.49302 -134.361348) (xy 474.386363 -134.328451) (xy 474.277546 -134.303616) (xy 474.167178 -134.286983)
			(xy 474.055875 -134.278644) (xy 474.000068 -134.278116) (xy 444.999872 -134.278116) (xy 444.929968 -134.278612)
			(xy 444.790381 -134.286463) (xy 444.651454 -134.302127) (xy 444.513624 -134.325555) (xy 444.377323 -134.356674)
			(xy 444.242982 -134.395385) (xy 444.111022 -134.441566) (xy 443.981859 -134.495074) (xy 443.855899 -134.555738)
			(xy 443.733538 -134.623368) (xy 443.615161 -134.697752) (xy 443.50114 -134.778656) (xy 443.391834 -134.865825)
			(xy 443.287587 -134.958985) (xy 443.188727 -135.057842) (xy 443.095565 -135.162087) (xy 443.008393 -135.27139)
			(xy 442.927487 -135.385409) (xy 442.8531 -135.503784) (xy 442.785466 -135.626144) (xy 442.724799 -135.752102)
			(xy 442.671289 -135.881264) (xy 442.625104 -136.013223) (xy 442.586389 -136.147563) (xy 442.555267 -136.283863)
			(xy 442.531836 -136.421693) (xy 442.516168 -136.56062) (xy 442.508314 -136.700206) (xy 442.507878 -136.77011)
			(xy 442.507878 -153.299922) (xy 442.507375 -153.422774) (xy 442.499335 -153.668345) (xy 442.483265 -153.913522)
			(xy 442.459181 -154.158042) (xy 442.42711 -154.401643) (xy 442.387085 -154.644065) (xy 442.33915 -154.885047)
			(xy 442.283356 -155.124331) (xy 442.219763 -155.361662) (xy 442.148438 -155.596785) (xy 442.069459 -155.829449)
			(xy 441.982909 -156.059404) (xy 441.888882 -156.286404) (xy 441.787478 -156.510205) (xy 441.678806 -156.73057)
			(xy 441.562982 -156.94726) (xy 441.44013 -157.160045) (xy 441.310381 -157.368697) (xy 441.173875 -157.572991)
			(xy 441.030758 -157.77271) (xy 440.881183 -157.967639) (xy 440.72531 -158.15757) (xy 440.563307 -158.342299)
			(xy 440.395346 -158.521628) (xy 440.221607 -158.695366) (xy 440.042277 -158.863327) (xy 439.857547 -159.02533)
			(xy 439.667615 -159.181202) (xy 439.472686 -159.330776) (xy 439.272966 -159.473893) (xy 439.068671 -159.610398)
			(xy 438.860019 -159.740145) (xy 438.647234 -159.862996) (xy 438.430543 -159.97882) (xy 438.210178 -160.087491)
			(xy 437.986376 -160.188894) (xy 437.759376 -160.28292) (xy 437.52942 -160.369469) (xy 437.296757 -160.448447)
			(xy 437.061633 -160.519771) (xy 436.824302 -160.583363) (xy 436.585017 -160.639156) (xy 436.344035 -160.68709)
			(xy 436.101614 -160.727114) (xy 435.858012 -160.759184) (xy 435.613492 -160.783267) (xy 435.368315 -160.799337)
			(xy 435.122744 -160.807376) (xy 434.999892 -160.807908) (xy 416.576256 -160.807908) (xy 416.506352 -160.808399)
			(xy 416.366764 -160.816241) (xy 416.227835 -160.831897) (xy 416.090003 -160.855317) (xy 415.9537 -160.88643)
			(xy 415.819357 -160.925136) (xy 415.687395 -160.971313) (xy 415.55823 -161.024817) (xy 415.432268 -161.085479)
			(xy 415.309905 -161.153108) (xy 415.191527 -161.227492) (xy 415.077506 -161.308396) (xy 414.968201 -161.395567)
			(xy 414.863955 -161.488728) (xy 414.765097 -161.587588) (xy 414.671937 -161.691836) (xy 414.584769 -161.801143)
			(xy 414.503867 -161.915166) (xy 414.429485 -162.033545) (xy 414.361858 -162.155909) (xy 414.301198 -162.281872)
			(xy 414.247697 -162.411038) (xy 414.201522 -162.543001) (xy 414.162818 -162.677345) (xy 414.131708 -162.813648)
			(xy 414.10829 -162.951481) (xy 414.092637 -163.09041) (xy 414.084798 -163.229998) (xy 414.084262 -163.299902)
			(xy 414.084262 -187.606178) (xy 414.083778 -187.676532) (xy 414.07589 -187.817019) (xy 414.060137 -187.956842)
			(xy 414.036568 -188.095562) (xy 414.005258 -188.232743) (xy 413.966306 -188.367952) (xy 413.919834 -188.500764)
			(xy 413.865987 -188.630762) (xy 413.804937 -188.757535) (xy 413.736874 -188.880686) (xy 413.662013 -188.999827)
			(xy 413.580589 -189.114583) (xy 413.492859 -189.224593) (xy 413.399098 -189.329511) (xy 413.299602 -189.429006)
			(xy 413.194684 -189.522766) (xy 413.084674 -189.610496) (xy 412.969917 -189.691919) (xy 412.850776 -189.76678)
			(xy 412.727625 -189.834842) (xy 412.600851 -189.895892) (xy 412.470853 -189.949738) (xy 412.33804 -189.99621)
			(xy 412.202831 -190.035161) (xy 412.065651 -190.06647) (xy 411.92693 -190.090038) (xy 411.787107 -190.105791)
			(xy 411.64662 -190.113679) (xy 411.576266 -190.114174) (xy 351.499932 -190.114174) (xy 351.429578 -190.113691)
			(xy 351.28909 -190.105803) (xy 351.149266 -190.09005) (xy 351.010545 -190.066482) (xy 350.873364 -190.035172)
			(xy 350.738154 -189.996221) (xy 350.605341 -189.949748) (xy 350.475343 -189.895903) (xy 350.348569 -189.834852)
			(xy 350.225417 -189.766789) (xy 350.106275 -189.691929) (xy 349.991518 -189.610505) (xy 349.881507 -189.522775)
			(xy 349.776589 -189.429014) (xy 349.677092 -189.329519) (xy 349.583332 -189.2246) (xy 349.495601 -189.11459)
			(xy 349.414177 -188.999833) (xy 349.339316 -188.880692) (xy 349.271252 -188.75754) (xy 349.210202 -188.630766)
			(xy 349.156355 -188.500768) (xy 349.109883 -188.367955) (xy 349.07093 -188.232746) (xy 349.03962 -188.095565)
			(xy 349.016052 -187.956844) (xy 349.000298 -187.81702) (xy 348.99241 -187.676532) (xy 348.991936 -187.606178)
			(xy 348.991936 -110.499906) (xy 348.991437 -110.399374) (xy 348.983341 -110.198474) (xy 348.967162 -109.998063)
			(xy 348.942927 -109.798466) (xy 348.910674 -109.600006) (xy 348.870457 -109.403006) (xy 348.822339 -109.207786)
			(xy 348.7664 -109.014661) (xy 348.702729 -108.823945) (xy 348.631431 -108.635948) (xy 348.552621 -108.450974)
			(xy 348.466427 -108.269323) (xy 348.372988 -108.09129) (xy 348.272456 -107.917165) (xy 348.164995 -107.747228)
			(xy 348.050777 -107.581757) (xy 347.92999 -107.421018) (xy 347.802828 -107.265274) (xy 347.669498 -107.114776)
			(xy 347.530217 -106.969769) (xy 347.385209 -106.830488) (xy 347.234711 -106.697159) (xy 347.078966 -106.569998)
			(xy 346.918227 -106.449211) (xy 346.752755 -106.334994) (xy 346.582818 -106.227533) (xy 346.408692 -106.127002)
			(xy 346.230659 -106.033564) (xy 346.049008 -105.947371) (xy 345.864034 -105.868561) (xy 345.676036 -105.797264)
			(xy 345.48532 -105.733594) (xy 345.292195 -105.677656) (xy 345.096974 -105.629539) (xy 344.899974 -105.589322)
			(xy 344.701514 -105.55707) (xy 344.501917 -105.532836) (xy 344.301506 -105.516658) (xy 344.100606 -105.508563)
			(xy 344.000074 -105.508044) (xy 293.310056 -105.508044) (xy 293.254251 -105.508567) (xy 293.142952 -105.516911)
			(xy 293.032588 -105.533549) (xy 292.923776 -105.558388) (xy 292.817125 -105.591289) (xy 292.713231 -105.632068)
			(xy 292.612674 -105.680497) (xy 292.516018 -105.736305) (xy 292.423802 -105.799181) (xy 292.336543 -105.868771)
			(xy 292.254729 -105.944688) (xy 292.178817 -106.026507) (xy 292.109231 -106.11377) (xy 292.046361 -106.205989)
			(xy 291.990558 -106.302648) (xy 291.942135 -106.403208) (xy 291.901361 -106.507104) (xy 291.868466 -106.613758)
			(xy 291.843634 -106.722571) (xy 291.827002 -106.832936) (xy 291.818664 -106.944235) (xy 291.81806 -107.00004)
			(xy 291.81806 -121.780046) (xy 291.817562 -121.863539) (xy 291.809615 -122.030336) (xy 291.793739 -122.196566)
			(xy 291.769973 -122.361852) (xy 291.738368 -122.52582) (xy 291.698998 -122.688098) (xy 291.65195 -122.848319)
			(xy 291.597333 -123.006121) (xy 291.535268 -123.161144) (xy 291.465898 -123.313039) (xy 291.389379 -123.461461)
			(xy 291.305884 -123.606075) (xy 291.215603 -123.746551) (xy 291.11874 -123.882573) (xy 291.015514 -124.013832)
			(xy 290.90616 -124.14003) (xy 290.790925 -124.260882) (xy 290.670071 -124.376114) (xy 290.54387 -124.485465)
			(xy 290.412609 -124.588688) (xy 290.276585 -124.685548) (xy 290.136106 -124.775826) (xy 289.991491 -124.859317)
			(xy 289.843067 -124.935833) (xy 289.691171 -125.0052) (xy 289.536146 -125.067261) (xy 289.378343 -125.121875)
			(xy 289.218121 -125.168919) (xy 289.055841 -125.208285) (xy 288.891873 -125.239886) (xy 288.726586 -125.263649)
			(xy 288.560356 -125.27952) (xy 288.393559 -125.287464) (xy 288.310066 -125.28804) (xy 139.910058 -125.28804)
			(xy 139.826564 -125.287542) (xy 139.659766 -125.279595) (xy 139.493535 -125.26372) (xy 139.328247 -125.239954)
			(xy 139.164277 -125.20835) (xy 139.001997 -125.168979) (xy 138.841774 -125.121932) (xy 138.683971 -125.067315)
			(xy 138.528946 -125.005251) (xy 138.377049 -124.935881) (xy 138.228625 -124.859362) (xy 138.08401 -124.775868)
			(xy 137.943531 -124.685588) (xy 137.807507 -124.588725) (xy 137.676246 -124.4855) (xy 137.550046 -124.376146)
			(xy 137.429191 -124.260912) (xy 137.313956 -124.140057) (xy 137.204603 -124.013857) (xy 137.101377 -123.882596)
			(xy 137.004515 -123.746572) (xy 136.914234 -123.606094) (xy 136.830739 -123.461479) (xy 136.75422 -123.313055)
			(xy 136.68485 -123.161158) (xy 136.622786 -123.006132) (xy 136.568169 -122.848329) (xy 136.521122 -122.688106)
			(xy 136.481751 -122.525826) (xy 136.450147 -122.361857) (xy 136.42638 -122.196569) (xy 136.410505 -122.030338)
			(xy 136.402558 -121.86354) (xy 136.402064 -121.780046) (xy 136.402064 -107.00004) (xy 136.401556 -106.944232)
			(xy 136.393218 -106.832928) (xy 136.376585 -106.722558) (xy 136.35175 -106.61374) (xy 136.318853 -106.507082)
			(xy 136.278076 -106.403181) (xy 136.229649 -106.302618) (xy 136.173842 -106.205955) (xy 136.110967 -106.113733)
			(xy 136.041377 -106.026468) (xy 135.965459 -105.944647) (xy 135.883638 -105.868729) (xy 135.796373 -105.799137)
			(xy 135.704152 -105.736262) (xy 135.607489 -105.680455) (xy 135.506926 -105.632027) (xy 135.403025 -105.59125)
			(xy 135.296368 -105.558352) (xy 135.18755 -105.533517) (xy 135.07718 -105.516883) (xy 134.965876 -105.508544)
			(xy 134.910068 -105.508044) (xy 95.999808 -105.508044) (xy 95.899276 -105.508543) (xy 95.698376 -105.516639)
			(xy 95.497964 -105.532817) (xy 95.298366 -105.557053) (xy 95.099907 -105.589305) (xy 94.902906 -105.629523)
			(xy 94.707685 -105.67764) (xy 94.51456 -105.73358) (xy 94.323844 -105.79725) (xy 94.135846 -105.868548)
			(xy 93.950872 -105.947358) (xy 93.769221 -106.033552) (xy 93.591188 -106.126991) (xy 93.417061 -106.227522)
			(xy 93.247124 -106.334984) (xy 93.081652 -106.449201) (xy 92.920913 -106.569988) (xy 92.765169 -106.69715)
			(xy 92.61467 -106.83048) (xy 92.469663 -106.969761) (xy 92.330381 -107.114769) (xy 92.197051 -107.265267)
			(xy 92.06989 -107.421012) (xy 91.949102 -107.581751) (xy 91.834885 -107.747223) (xy 91.727424 -107.91716)
			(xy 91.626892 -108.091286) (xy 91.533453 -108.269319) (xy 91.447259 -108.45097) (xy 91.368448 -108.635944)
			(xy 91.29715 -108.823942) (xy 91.23348 -109.014658) (xy 91.177541 -109.207783) (xy 91.129423 -109.403004)
			(xy 91.089206 -109.600005) (xy 91.056953 -109.798465) (xy 91.032718 -109.998062) (xy 91.016539 -110.198474)
			(xy 91.008443 -110.399374) (xy 91.007946 -110.499906) (xy 91.007946 -187.606178) (xy 91.007462 -187.676532)
			(xy 90.999574 -187.817018) (xy 90.983821 -187.956841) (xy 90.960252 -188.095561) (xy 90.928942 -188.232741)
			(xy 90.88999 -188.36795) (xy 90.843517 -188.500762) (xy 90.789671 -188.630759) (xy 90.72862 -188.757532)
			(xy 90.660557 -188.880683) (xy 90.585696 -188.999823) (xy 90.504272 -189.114579) (xy 90.416542 -189.224588)
			(xy 90.322781 -189.329506) (xy 90.223285 -189.429) (xy 90.118367 -189.52276) (xy 90.008357 -189.610489)
			(xy 89.8936 -189.691911) (xy 89.774459 -189.766771) (xy 89.651307 -189.834833) (xy 89.524533 -189.895882)
			(xy 89.394536 -189.949727) (xy 89.261723 -189.996198) (xy 89.126514 -190.035149) (xy 88.989334 -190.066457)
			(xy 88.850614 -190.090024) (xy 88.71079 -190.105776) (xy 88.570304 -190.113663) (xy 88.49995 -190.114174)
			(xy 28.42387 -190.114174) (xy 28.353517 -190.11368) (xy 28.213033 -190.105789) (xy 28.073211 -190.090033)
			(xy 27.934494 -190.066462) (xy 27.797316 -190.035151) (xy 27.66211 -189.996197) (xy 27.5293 -189.949723)
			(xy 27.399305 -189.895876) (xy 27.272534 -189.834824) (xy 27.149386 -189.766761) (xy 27.030248 -189.691899)
			(xy 26.915494 -189.610476) (xy 26.805487 -189.522746) (xy 26.700572 -189.428986) (xy 26.601078 -189.329491)
			(xy 26.507321 -189.224573) (xy 26.419593 -189.114564) (xy 26.338172 -188.999809) (xy 26.263313 -188.880669)
			(xy 26.195252 -188.757519) (xy 26.134203 -188.630747) (xy 26.080358 -188.500751) (xy 26.033887 -188.367941)
			(xy 25.994936 -188.232734) (xy 25.963628 -188.095555) (xy 25.94006 -187.956837) (xy 25.924307 -187.817016)
			(xy 25.916419 -187.676531) (xy 25.915874 -187.606178) (xy 25.915874 -163.299902) (xy 25.915393 -163.229997)
			(xy 25.907553 -163.090407) (xy 25.8919 -162.951476) (xy 25.868481 -162.813642) (xy 25.83737 -162.677337)
			(xy 25.798666 -162.542992) (xy 25.752489 -162.411028) (xy 25.698986 -162.28186) (xy 25.638325 -162.155896)
			(xy 25.570696 -162.033531) (xy 25.496312 -161.915151) (xy 25.415408 -161.801128) (xy 25.328237 -161.69182)
			(xy 25.235075 -161.587572) (xy 25.136214 -161.488712) (xy 25.031966 -161.395551) (xy 24.922658 -161.308381)
			(xy 24.808634 -161.227478) (xy 24.690253 -161.153095) (xy 24.567888 -161.085467) (xy 24.441923 -161.024807)
			(xy 24.312756 -160.971304) (xy 24.180791 -160.925129) (xy 24.046445 -160.886426) (xy 23.91014 -160.855316)
			(xy 23.772306 -160.831898) (xy 23.633375 -160.816245) (xy 23.493785 -160.808407) (xy 23.42388 -160.807908)
			(xy 1.999996 -160.807908) (xy 1.944189 -160.80843) (xy 1.832887 -160.816771) (xy 1.72252 -160.833407)
			(xy 1.613705 -160.858243) (xy 1.50705 -160.891142) (xy 1.403152 -160.93192) (xy 1.302591 -160.980347)
			(xy 1.205931 -161.036154) (xy 1.113712 -161.099029) (xy 1.026449 -161.168619) (xy 0.94463 -161.244536)
			(xy 0.868714 -161.326355) (xy 0.799124 -161.413618) (xy 0.73625 -161.505838) (xy 0.680444 -161.602499)
			(xy 0.632016 -161.703059) (xy 0.59124 -161.806958) (xy 0.558341 -161.913613) (xy 0.533505 -162.022428)
			(xy 0.51687 -162.132795) (xy 0.50853 -162.244097) (xy 0.508 -162.299904) (xy 0.508 -194.670734) (xy 2.904225 -194.670734)
			(xy 2.904225 -194.541594) (xy 2.912175 -194.412699) (xy 2.928045 -194.284539) (xy 2.951774 -194.157598)
			(xy 2.983273 -194.032359) (xy 3.022422 -193.909296) (xy 3.069073 -193.788877) (xy 3.123048 -193.671558)
			(xy 3.184143 -193.557784) (xy 3.252126 -193.447987) (xy 3.32674 -193.342584) (xy 3.407701 -193.241974)
			(xy 3.494701 -193.146539) (xy 3.587412 -193.05664) (xy 3.685482 -192.972619) (xy 3.788537 -192.894795)
			(xy 3.896188 -192.823463) (xy 4.008027 -192.758893) (xy 4.123628 -192.701331) (xy 4.242553 -192.650994)
			(xy 4.364352 -192.608074) (xy 4.488562 -192.572733) (xy 4.614711 -192.545106) (xy 4.742323 -192.525297)
			(xy 4.870912 -192.513381) (xy 4.99999 -192.509405) (xy 5.129068 -192.513381) (xy 5.257657 -192.525297)
			(xy 5.385269 -192.545106) (xy 5.511418 -192.572733) (xy 5.635628 -192.608074) (xy 5.757427 -192.650994)
			(xy 5.876352 -192.701331) (xy 5.991953 -192.758893) (xy 6.103792 -192.823463) (xy 6.211443 -192.894795)
			(xy 6.314498 -192.972619) (xy 6.412568 -193.05664) (xy 6.505279 -193.146539) (xy 6.592279 -193.241974)
			(xy 6.67324 -193.342584) (xy 6.747854 -193.447987) (xy 6.815837 -193.557784) (xy 6.876932 -193.671558)
			(xy 6.930907 -193.788877) (xy 6.977558 -193.909296) (xy 7.016707 -194.032359) (xy 7.048206 -194.157598)
			(xy 7.071935 -194.284539) (xy 7.087805 -194.412699) (xy 7.095755 -194.541594) (xy 7.096252 -194.606164)
			(xy 7.095755 -194.670734) (xy 468.904309 -194.670734) (xy 468.904309 -194.541594) (xy 468.912259 -194.412699)
			(xy 468.928129 -194.284539) (xy 468.951858 -194.157598) (xy 468.983357 -194.032359) (xy 469.022506 -193.909296)
			(xy 469.069157 -193.788877) (xy 469.123132 -193.671558) (xy 469.184227 -193.557784) (xy 469.25221 -193.447987)
			(xy 469.326824 -193.342584) (xy 469.407785 -193.241974) (xy 469.494785 -193.146539) (xy 469.587496 -193.05664)
			(xy 469.685566 -192.972619) (xy 469.788621 -192.894795) (xy 469.896272 -192.823463) (xy 470.008111 -192.758893)
			(xy 470.123712 -192.701331) (xy 470.242637 -192.650994) (xy 470.364436 -192.608074) (xy 470.488646 -192.572733)
			(xy 470.614795 -192.545106) (xy 470.742407 -192.525297) (xy 470.870996 -192.513381) (xy 471.000074 -192.509405)
			(xy 471.129152 -192.513381) (xy 471.257741 -192.525297) (xy 471.385353 -192.545106) (xy 471.511502 -192.572733)
			(xy 471.635712 -192.608074) (xy 471.757511 -192.650994) (xy 471.876436 -192.701331) (xy 471.992037 -192.758893)
			(xy 472.103876 -192.823463) (xy 472.211527 -192.894795) (xy 472.314582 -192.972619) (xy 472.412652 -193.05664)
			(xy 472.505363 -193.146539) (xy 472.592363 -193.241974) (xy 472.673324 -193.342584) (xy 472.747938 -193.447987)
			(xy 472.815921 -193.557784) (xy 472.877016 -193.671558) (xy 472.930991 -193.788877) (xy 472.977642 -193.909296)
			(xy 473.016791 -194.032359) (xy 473.04829 -194.157598) (xy 473.072019 -194.284539) (xy 473.087889 -194.412699)
			(xy 473.095839 -194.541594) (xy 473.096336 -194.606164) (xy 473.095839 -194.670734) (xy 473.087889 -194.799629)
			(xy 473.072019 -194.927789) (xy 473.04829 -195.05473) (xy 473.016791 -195.179969) (xy 472.977642 -195.303032)
			(xy 472.930991 -195.423451) (xy 472.877016 -195.54077) (xy 472.815921 -195.654544) (xy 472.747938 -195.764341)
			(xy 472.673324 -195.869744) (xy 472.592363 -195.970354) (xy 472.505363 -196.065789) (xy 472.412652 -196.155688)
			(xy 472.314582 -196.239709) (xy 472.211527 -196.317533) (xy 472.103876 -196.388865) (xy 471.992037 -196.453435)
			(xy 471.876436 -196.510997) (xy 471.757511 -196.561334) (xy 471.635712 -196.604254) (xy 471.511502 -196.639595)
			(xy 471.385353 -196.667222) (xy 471.257741 -196.687031) (xy 471.129152 -196.698947) (xy 471.000074 -196.702924)
			(xy 470.870996 -196.698947) (xy 470.742407 -196.687031) (xy 470.614795 -196.667222) (xy 470.488646 -196.639595)
			(xy 470.364436 -196.604254) (xy 470.242637 -196.561334) (xy 470.123712 -196.510997) (xy 470.008111 -196.453435)
			(xy 469.896272 -196.388865) (xy 469.788621 -196.317533) (xy 469.685566 -196.239709) (xy 469.587496 -196.155688)
			(xy 469.494785 -196.065789) (xy 469.407785 -195.970354) (xy 469.326824 -195.869744) (xy 469.25221 -195.764341)
			(xy 469.184227 -195.654544) (xy 469.123132 -195.54077) (xy 469.069157 -195.423451) (xy 469.022506 -195.303032)
			(xy 468.983357 -195.179969) (xy 468.951858 -195.05473) (xy 468.928129 -194.927789) (xy 468.912259 -194.799629)
			(xy 468.904309 -194.670734) (xy 7.095755 -194.670734) (xy 7.087805 -194.799629) (xy 7.071935 -194.927789)
			(xy 7.048206 -195.05473) (xy 7.016707 -195.179969) (xy 6.977558 -195.303032) (xy 6.930907 -195.423451)
			(xy 6.876932 -195.54077) (xy 6.815837 -195.654544) (xy 6.747854 -195.764341) (xy 6.67324 -195.869744)
			(xy 6.592279 -195.970354) (xy 6.505279 -196.065789) (xy 6.412568 -196.155688) (xy 6.314498 -196.239709)
			(xy 6.211443 -196.317533) (xy 6.103792 -196.388865) (xy 5.991953 -196.453435) (xy 5.876352 -196.510997)
			(xy 5.757427 -196.561334) (xy 5.635628 -196.604254) (xy 5.511418 -196.639595) (xy 5.385269 -196.667222)
			(xy 5.257657 -196.687031) (xy 5.129068 -196.698947) (xy 4.99999 -196.702924) (xy 4.870912 -196.698947)
			(xy 4.742323 -196.687031) (xy 4.614711 -196.667222) (xy 4.488562 -196.639595) (xy 4.364352 -196.604254)
			(xy 4.242553 -196.561334) (xy 4.123628 -196.510997) (xy 4.008027 -196.453435) (xy 3.896188 -196.388865)
			(xy 3.788537 -196.317533) (xy 3.685482 -196.239709) (xy 3.587412 -196.155688) (xy 3.494701 -196.065789)
			(xy 3.407701 -195.970354) (xy 3.32674 -195.869744) (xy 3.252126 -195.764341) (xy 3.184143 -195.654544)
			(xy 3.123048 -195.54077) (xy 3.069073 -195.423451) (xy 3.022422 -195.303032) (xy 2.983273 -195.179969)
			(xy 2.951774 -195.05473) (xy 2.928045 -194.927789) (xy 2.912175 -194.799629) (xy 2.904225 -194.670734)
			(xy 0.508 -194.670734) (xy 0.508 -197.606158) (xy 0.508522 -197.661965) (xy 0.516863 -197.773267)
			(xy 0.533498 -197.883634) (xy 0.558335 -197.99245) (xy 0.591234 -198.099105) (xy 0.632011 -198.203004)
			(xy 0.680438 -198.303564) (xy 0.736246 -198.400225) (xy 0.79912 -198.492445) (xy 0.86871 -198.579708)
			(xy 0.944627 -198.661527) (xy 1.026446 -198.737444) (xy 1.113709 -198.807034) (xy 1.205929 -198.869908)
			(xy 1.30259 -198.925716) (xy 1.40315 -198.974143) (xy 1.507049 -199.01492) (xy 1.613704 -199.047819)
			(xy 1.72252 -199.072656) (xy 1.832887 -199.089291) (xy 1.944189 -199.097632) (xy 1.999996 -199.098154)
		)
		(stroke
			(width 0)
			(type solid)
		)
		(fill yes)
		(layer "In5.Cu")
		(net "GND3")
	)
	(gr_poly
		(pts
			(xy 278.621998 -88.135206) (xy 278.632069 -88.134784) (xy 278.650674 -88.12707) (xy 278.658066 -88.12022)
			(xy 279.130252 -87.648034) (xy 279.137093 -87.640634) (xy 279.144811 -87.622035) (xy 279.145238 -87.611966)
			(xy 279.145238 -84.544154) (xy 279.144805 -84.534089) (xy 279.137072 -84.515502) (xy 279.130252 -84.508086)
			(xy 279.03424 -84.412074) (xy 279.027128 -84.404708) (xy 279.008332 -84.397088) (xy 265.824716 -84.397088)
			(xy 265.791456 -84.396568) (xy 265.725505 -84.387882) (xy 265.661253 -84.370658) (xy 265.5998 -84.34519)
			(xy 265.542201 -84.311914) (xy 265.48944 -84.271401) (xy 265.46556 -84.248244) (xy 264.337546 -83.12023)
			(xy 264.314391 -83.09635) (xy 264.273887 -83.043585) (xy 264.24062 -82.985984) (xy 264.215159 -82.924532)
			(xy 264.19794 -82.860282) (xy 264.189257 -82.794333) (xy 264.188702 -82.761074) (xy 264.188702 -69.935598)
			(xy 264.188361 -69.926997) (xy 264.18264 -69.910773) (xy 264.177526 -69.903848) (xy 264.15102 -69.870009)
			(xy 264.103919 -69.7981) (xy 264.063977 -69.721981) (xy 264.031566 -69.642362) (xy 264.006991 -69.559988)
			(xy 263.990479 -69.475627) (xy 263.982185 -69.390065) (xy 263.982186 -69.304103) (xy 263.990483 -69.218543)
			(xy 264.006998 -69.134182) (xy 264.031577 -69.051808) (xy 264.06399 -68.972191) (xy 264.103935 -68.896073)
			(xy 264.151038 -68.824166) (xy 264.177526 -68.790312) (xy 264.182633 -68.783387) (xy 264.188329 -68.76716)
			(xy 264.188702 -68.758562) (xy 264.188702 -52.959) (xy 264.189223 -52.92574) (xy 264.197911 -52.85979)
			(xy 264.215136 -52.795539) (xy 264.240605 -52.734088) (xy 264.273881 -52.676489) (xy 264.314395 -52.62373)
			(xy 264.337546 -52.599844) (xy 265.767058 -51.170332) (xy 265.772967 -51.163875) (xy 265.780403 -51.148044)
			(xy 265.78208 -51.130634) (xy 265.780266 -51.122072) (xy 265.75893 -51.03749) (xy 265.75647 -51.029185)
			(xy 265.746876 -51.014778) (xy 265.733035 -51.004384) (xy 265.724894 -51.001422) (xy 265.724386 -51.001168)
			(xy 265.682565 -50.988113) (xy 265.601498 -50.954879) (xy 265.524089 -50.913837) (xy 265.451091 -50.865384)
			(xy 265.383208 -50.80999) (xy 265.3211 -50.748191) (xy 265.265367 -50.680587) (xy 265.21655 -50.607831)
			(xy 265.175121 -50.53063) (xy 265.141482 -50.449729) (xy 265.115958 -50.365914) (xy 265.098797 -50.279995)
			(xy 265.090165 -50.192806) (xy 265.08964 -50.148998) (xy 265.090144 -50.106637) (xy 265.098197 -50.0223)
			(xy 265.114231 -49.93911) (xy 265.138099 -49.85782) (xy 265.169587 -49.779168) (xy 265.208409 -49.703865)
			(xy 265.254212 -49.632593) (xy 265.306583 -49.565997) (xy 265.365048 -49.504682) (xy 265.429076 -49.449201)
			(xy 265.498088 -49.400058) (xy 265.571458 -49.357698) (xy 265.648523 -49.322503) (xy 265.728585 -49.294794)
			(xy 265.810918 -49.27482) (xy 265.894777 -49.262763) (xy 265.979402 -49.258732) (xy 266.064027 -49.262763)
			(xy 266.147886 -49.27482) (xy 266.230219 -49.294794) (xy 266.310281 -49.322503) (xy 266.387346 -49.357698)
			(xy 266.460716 -49.400058) (xy 266.529728 -49.449201) (xy 266.593756 -49.504682) (xy 266.652221 -49.565997)
			(xy 266.704592 -49.632593) (xy 266.750395 -49.703865) (xy 266.789217 -49.779168) (xy 266.820705 -49.85782)
			(xy 266.844573 -49.93911) (xy 266.860607 -50.0223) (xy 266.86866 -50.106637) (xy 266.869164 -50.148998)
			(xy 266.868583 -50.194008) (xy 266.859465 -50.283565) (xy 266.841352 -50.371745) (xy 266.814429 -50.457645)
			(xy 266.778972 -50.540388) (xy 266.757658 -50.580036) (xy 266.757658 -50.58029) (xy 266.753719 -50.588157)
			(xy 266.750885 -50.605509) (xy 266.754062 -50.6228) (xy 266.758166 -50.630582) (xy 266.802616 -50.705766)
			(xy 266.805664 -50.710592) (xy 266.813318 -50.719736) (xy 266.834647 -50.73033) (xy 266.846558 -50.730912)
			(xy 274.733512 -50.730912) (xy 274.766772 -50.731434) (xy 274.832721 -50.740123) (xy 274.896971 -50.75735)
			(xy 274.95842 -50.78282) (xy 275.016017 -50.816098) (xy 275.068775 -50.856612) (xy 275.092668 -50.879756)
			(xy 282.490926 -58.278014) (xy 282.498322 -58.284866) (xy 282.516921 -58.292604) (xy 282.526994 -58.293)
			(xy 293.3954 -58.293) (xy 293.42866 -58.293521) (xy 293.49461 -58.302209) (xy 293.558861 -58.319434)
			(xy 293.620312 -58.344903) (xy 293.677911 -58.378179) (xy 293.730671 -58.418692) (xy 293.754556 -58.441844)
			(xy 296.904156 -61.591444) (xy 296.927312 -61.615324) (xy 296.967818 -61.668088) (xy 297.001089 -61.725689)
			(xy 297.026553 -61.78714) (xy 297.043775 -61.851391) (xy 297.052461 -61.917341) (xy 297.053 -61.9506)
			(xy 297.053 -65.300606) (xy 297.053424 -65.310676) (xy 297.06114 -65.329279) (xy 297.067986 -65.336674)
			(xy 298.552616 -66.821304) (xy 298.560016 -66.828147) (xy 298.578614 -66.835875) (xy 298.588684 -66.83629)
			(xy 301.013368 -66.83629) (xy 301.018258 -66.836152) (xy 301.02785 -66.83423) (xy 301.032418 -66.83248)
			(xy 301.058072 -66.822066) (xy 301.065184 -66.815462) (xy 301.096119 -66.786949) (xy 301.162495 -66.735244)
			(xy 301.233454 -66.690036) (xy 301.308365 -66.651729) (xy 301.386557 -66.620664) (xy 301.467333 -66.59712)
			(xy 301.54997 -66.581305) (xy 301.633731 -66.573363) (xy 301.717869 -66.573363) (xy 301.80163 -66.581305)
			(xy 301.884267 -66.59712) (xy 301.965043 -66.620664) (xy 302.043235 -66.651729) (xy 302.118146 -66.690036)
			(xy 302.189105 -66.735244) (xy 302.255481 -66.786949) (xy 302.286416 -66.815462) (xy 302.293528 -66.822066)
			(xy 302.319182 -66.83248) (xy 302.323749 -66.834236) (xy 302.333341 -66.836158) (xy 302.338232 -66.83629)
			(xy 304.2412 -66.83629) (xy 304.251221 -66.83587) (xy 304.269736 -66.8282) (xy 304.283906 -66.814027)
			(xy 304.291572 -66.795511) (xy 304.292 -66.78549) (xy 304.292 -64.788288) (xy 304.291644 -64.779012)
			(xy 304.285127 -64.761646) (xy 304.272844 -64.747748) (xy 304.264822 -64.743076) (xy 304.26152 -64.741552)
			(xy 304.222278 -64.723927) (xy 304.147076 -64.682145) (xy 304.076257 -64.633299) (xy 304.010485 -64.577845)
			(xy 303.950372 -64.516301) (xy 303.896482 -64.449241) (xy 303.849316 -64.377293) (xy 303.809316 -64.301127)
			(xy 303.776855 -64.221456) (xy 303.752236 -64.139024) (xy 303.735689 -64.0546) (xy 303.727369 -63.968973)
			(xy 303.72685 -63.925958) (xy 303.727296 -63.886012) (xy 303.734483 -63.806444) (xy 303.748777 -63.727842)
			(xy 303.770062 -63.650838) (xy 303.798168 -63.576053) (xy 303.832868 -63.50409) (xy 303.873881 -63.43553)
			(xy 303.89703 -63.402972) (xy 303.90297 -63.39401) (xy 303.907447 -63.373) (xy 303.90297 -63.35199)
			(xy 303.89703 -63.343028) (xy 303.873886 -63.310468) (xy 303.832877 -63.241906) (xy 303.798181 -63.169943)
			(xy 303.770079 -63.095158) (xy 303.748796 -63.018155) (xy 303.734504 -62.939554) (xy 303.727318 -62.859987)
			(xy 303.72685 -62.820042) (xy 303.727352 -62.777025) (xy 303.735656 -62.691391) (xy 303.752191 -62.60696)
			(xy 303.776801 -62.524521) (xy 303.809258 -62.444843) (xy 303.849258 -62.368672) (xy 303.896426 -62.296719)
			(xy 303.950322 -62.229658) (xy 304.010442 -62.168114) (xy 304.076224 -62.112664) (xy 304.147053 -62.063826)
			(xy 304.222268 -62.022055) (xy 304.26152 -62.004448) (xy 304.264822 -62.002924) (xy 304.272848 -61.998255)
			(xy 304.285136 -61.984354) (xy 304.291673 -61.96699) (xy 304.292 -61.957712) (xy 304.292 -42.065194)
			(xy 304.291576 -42.055124) (xy 304.28386 -42.036521) (xy 304.277014 -42.029126) (xy 303.762918 -41.51503)
			(xy 303.755298 -41.51122) (xy 303.717764 -41.492337) (xy 303.646082 -41.448492) (xy 303.578856 -41.39808)
			(xy 303.516685 -41.341552) (xy 303.460124 -41.279412) (xy 303.409676 -41.212213) (xy 303.365793 -41.140555)
			(xy 303.346866 -41.103042) (xy 303.34331 -41.095422) (xy 303.283874 -41.035986) (xy 303.276762 -41.02862)
			(xy 303.257966 -41.021) (xy 300.6852 -41.021) (xy 300.65194 -41.020479) (xy 300.58599 -41.011791)
			(xy 300.521739 -40.994566) (xy 300.460288 -40.969097) (xy 300.402689 -40.935821) (xy 300.349929 -40.895308)
			(xy 300.326044 -40.872156) (xy 298.809156 -39.355268) (xy 298.785999 -39.331388) (xy 298.74549 -39.278625)
			(xy 298.712218 -39.221025) (xy 298.686752 -39.159573) (xy 298.669527 -39.095322) (xy 298.66084 -39.029372)
			(xy 298.660312 -38.996112) (xy 298.660312 -33.576768) (xy 298.660835 -33.543509) (xy 298.669527 -33.477561)
			(xy 298.686756 -33.413313) (xy 298.712228 -33.351865) (xy 298.745507 -33.29427) (xy 298.786022 -33.241514)
			(xy 298.809156 -33.217612) (xy 298.90593 -33.120838) (xy 298.929808 -33.097677) (xy 298.982568 -33.057162)
			(xy 299.040168 -33.023884) (xy 299.101621 -32.998414) (xy 299.165873 -32.981186) (xy 299.231825 -32.972497)
			(xy 299.265086 -32.971994) (xy 301.057564 -32.971994) (xy 301.066668 -32.97162) (xy 301.083722 -32.96524)
			(xy 301.090838 -32.959548) (xy 301.123229 -32.931922) (xy 301.192413 -32.882304) (xy 301.266022 -32.839525)
			(xy 301.343383 -32.803977) (xy 301.423787 -32.775985) (xy 301.506499 -32.755806) (xy 301.59076 -32.743624)
			(xy 301.6758 -32.739551) (xy 301.76084 -32.743624) (xy 301.845101 -32.755806) (xy 301.927813 -32.775985)
			(xy 302.008217 -32.803977) (xy 302.085578 -32.839525) (xy 302.159187 -32.882304) (xy 302.228371 -32.931922)
			(xy 302.260762 -32.959548) (xy 302.267887 -32.96522) (xy 302.284937 -32.971583) (xy 302.294036 -32.971994)
			(xy 304.007012 -32.971994) (xy 304.017081 -32.971568) (xy 304.035682 -32.96385) (xy 304.04308 -32.957008)
			(xy 304.277014 -32.723074) (xy 304.283866 -32.715678) (xy 304.291604 -32.697079) (xy 304.292 -32.687006)
			(xy 304.292 -30.955488) (xy 304.291644 -30.946212) (xy 304.285127 -30.928846) (xy 304.272844 -30.914948)
			(xy 304.264822 -30.910276) (xy 304.26152 -30.908752) (xy 304.222278 -30.891127) (xy 304.147076 -30.849345)
			(xy 304.076257 -30.800499) (xy 304.010485 -30.745045) (xy 303.950372 -30.683501) (xy 303.896482 -30.616441)
			(xy 303.849316 -30.544493) (xy 303.809316 -30.468327) (xy 303.776855 -30.388656) (xy 303.752236 -30.306224)
			(xy 303.735689 -30.2218) (xy 303.727369 -30.136173) (xy 303.72685 -30.093158) (xy 303.727296 -30.053212)
			(xy 303.734483 -29.973644) (xy 303.748777 -29.895042) (xy 303.770062 -29.818038) (xy 303.798168 -29.743253)
			(xy 303.832868 -29.67129) (xy 303.873881 -29.60273) (xy 303.89703 -29.570172) (xy 303.90297 -29.56121)
			(xy 303.907447 -29.5402) (xy 303.90297 -29.51919) (xy 303.89703 -29.510228) (xy 303.873886 -29.477668)
			(xy 303.832877 -29.409106) (xy 303.798181 -29.337143) (xy 303.770079 -29.262358) (xy 303.748796 -29.185355)
			(xy 303.734504 -29.106754) (xy 303.727318 -29.027187) (xy 303.72685 -28.987242) (xy 303.727352 -28.944225)
			(xy 303.735656 -28.858591) (xy 303.752191 -28.77416) (xy 303.776801 -28.691721) (xy 303.809258 -28.612043)
			(xy 303.849258 -28.535872) (xy 303.896426 -28.463919) (xy 303.950322 -28.396858) (xy 304.010442 -28.335314)
			(xy 304.076224 -28.279864) (xy 304.147053 -28.231026) (xy 304.222268 -28.189255) (xy 304.26152 -28.171648)
			(xy 304.264822 -28.170124) (xy 304.272848 -28.165455) (xy 304.285136 -28.151554) (xy 304.291673 -28.13419)
			(xy 304.292 -28.124912) (xy 304.292 -13.439394) (xy 304.291576 -13.429324) (xy 304.28386 -13.410721)
			(xy 304.277014 -13.403326) (xy 303.842674 -12.968986) (xy 303.835562 -12.96162) (xy 303.816766 -12.954)
			(xy 283.585412 -12.954) (xy 283.575341 -12.954421) (xy 283.556733 -12.962132) (xy 283.549344 -12.968986)
			(xy 280.176986 -16.341344) (xy 280.16962 -16.348456) (xy 280.162 -16.367252) (xy 280.162 -27.182318)
			(xy 280.161477 -27.215578) (xy 280.152788 -27.281527) (xy 280.135561 -27.345776) (xy 280.11009 -27.407226)
			(xy 280.076813 -27.464823) (xy 280.036299 -27.517581) (xy 280.013156 -27.541474) (xy 278.747474 -28.807156)
			(xy 278.723595 -28.830313) (xy 278.670831 -28.870822) (xy 278.613231 -28.904094) (xy 278.551779 -28.92956)
			(xy 278.487528 -28.946785) (xy 278.421578 -28.955473) (xy 278.388318 -28.956) (xy 231.371394 -28.956)
			(xy 231.361324 -28.956424) (xy 231.342721 -28.96414) (xy 231.335326 -28.970986) (xy 229.884986 -30.421326)
			(xy 229.87762 -30.428438) (xy 229.87 -30.447234) (xy 229.87 -46.758606) (xy 229.870424 -46.768676)
			(xy 229.87814 -46.787279) (xy 229.884986 -46.794674) (xy 230.446326 -47.356014) (xy 230.453722 -47.362866)
			(xy 230.472321 -47.370604) (xy 230.482394 -47.371) (xy 242.73256 -47.371) (xy 242.742625 -47.370566)
			(xy 242.761214 -47.362836) (xy 242.768628 -47.356014) (xy 248.359676 -41.764966) (xy 248.383556 -41.741811)
			(xy 248.43632 -41.701306) (xy 248.493921 -41.668038) (xy 248.555373 -41.642576) (xy 248.619624 -41.625357)
			(xy 248.685573 -41.616675) (xy 248.718832 -41.616122) (xy 255.690116 -41.616122) (xy 255.723376 -41.616644)
			(xy 255.789326 -41.625332) (xy 255.853578 -41.642557) (xy 255.91503 -41.668025) (xy 255.97263 -41.701298)
			(xy 256.025393 -41.741808) (xy 256.049272 -41.764966) (xy 258.550156 -44.26585) (xy 258.573312 -44.28973)
			(xy 258.613818 -44.342494) (xy 258.647087 -44.400095) (xy 258.672551 -44.461547) (xy 258.689772 -44.525797)
			(xy 258.698457 -44.591747) (xy 258.699 -44.625006) (xy 258.699 -46.377606) (xy 258.699424 -46.387676)
			(xy 258.70714 -46.406279) (xy 258.713986 -46.413674) (xy 259.198872 -46.89856) (xy 259.205743 -46.904809)
			(xy 259.222693 -46.912366) (xy 259.241219 -46.913442) (xy 259.25018 -46.911006) (xy 259.350002 -46.879002)
			(xy 259.368544 -46.857666) (xy 259.37083 -46.843442) (xy 259.378189 -46.802416) (xy 259.399576 -46.721849)
			(xy 259.428405 -46.643637) (xy 259.464422 -46.568463) (xy 259.507313 -46.496987) (xy 259.5567 -46.429837)
			(xy 259.612152 -46.3676) (xy 259.673181 -46.310822) (xy 259.739253 -46.26) (xy 259.809789 -46.215582)
			(xy 259.88417 -46.177955) (xy 259.961745 -46.14745) (xy 260.041832 -46.124334) (xy 260.12373 -46.10881)
			(xy 260.206722 -46.101013) (xy 260.2484 -46.100492) (xy 260.289502 -46.100967) (xy 260.371357 -46.108552)
			(xy 260.452162 -46.123657) (xy 260.531229 -46.146153) (xy 260.607883 -46.175849) (xy 260.68147 -46.212491)
			(xy 260.751362 -46.255766) (xy 260.816963 -46.305306) (xy 260.877713 -46.360687) (xy 260.933094 -46.421437)
			(xy 260.982634 -46.487038) (xy 261.025909 -46.55693) (xy 261.062551 -46.630517) (xy 261.092247 -46.707171)
			(xy 261.114743 -46.786238) (xy 261.129848 -46.867043) (xy 261.137433 -46.948898) (xy 261.137908 -46.99)
			(xy 261.137421 -47.03168) (xy 261.129625 -47.114674) (xy 261.1141 -47.196576) (xy 261.090983 -47.276666)
			(xy 261.060477 -47.354244) (xy 261.022849 -47.428628) (xy 260.978428 -47.499167) (xy 260.927605 -47.565241)
			(xy 260.870825 -47.626273) (xy 260.808585 -47.681727) (xy 260.741432 -47.731116) (xy 260.669954 -47.774008)
			(xy 260.594777 -47.810027) (xy 260.516561 -47.838857) (xy 260.435992 -47.860245) (xy 260.394958 -47.86757)
			(xy 260.380734 -47.869856) (xy 260.359398 -47.888398) (xy 260.327394 -47.98822) (xy 260.324948 -47.997187)
			(xy 260.325968 -48.015731) (xy 260.333552 -48.032683) (xy 260.33984 -48.039528) (xy 260.872986 -48.572674)
			(xy 260.896143 -48.596553) (xy 260.936652 -48.649316) (xy 260.969923 -48.706916) (xy 260.995388 -48.768369)
			(xy 261.012609 -48.83262) (xy 261.021292 -48.89857) (xy 261.02183 -48.93183) (xy 261.02183 -51.207359)
			(xy 261.88314 -51.207359) (xy 261.88314 -51.122637) (xy 261.891193 -51.0383) (xy 261.907227 -50.95511)
			(xy 261.931095 -50.87382) (xy 261.962583 -50.795168) (xy 262.001405 -50.719865) (xy 262.047208 -50.648593)
			(xy 262.099579 -50.581997) (xy 262.158044 -50.520682) (xy 262.222072 -50.465201) (xy 262.291084 -50.416058)
			(xy 262.364454 -50.373698) (xy 262.441519 -50.338503) (xy 262.521581 -50.310794) (xy 262.603914 -50.29082)
			(xy 262.687773 -50.278763) (xy 262.772398 -50.274732) (xy 262.857023 -50.278763) (xy 262.940882 -50.29082)
			(xy 263.023215 -50.310794) (xy 263.103277 -50.338503) (xy 263.180342 -50.373698) (xy 263.253712 -50.416058)
			(xy 263.322724 -50.465201) (xy 263.386752 -50.520682) (xy 263.445217 -50.581997) (xy 263.497588 -50.648593)
			(xy 263.543391 -50.719865) (xy 263.582213 -50.795168) (xy 263.613701 -50.87382) (xy 263.637569 -50.95511)
			(xy 263.653603 -51.0383) (xy 263.661656 -51.122637) (xy 263.66216 -51.164998) (xy 263.661656 -51.207359)
			(xy 263.653603 -51.291696) (xy 263.637569 -51.374886) (xy 263.613701 -51.456176) (xy 263.582213 -51.534828)
			(xy 263.543391 -51.610131) (xy 263.497588 -51.681403) (xy 263.445217 -51.747999) (xy 263.386752 -51.809314)
			(xy 263.322724 -51.864795) (xy 263.253712 -51.913938) (xy 263.180342 -51.956298) (xy 263.103277 -51.991493)
			(xy 263.023215 -52.019202) (xy 262.940882 -52.039176) (xy 262.857023 -52.051233) (xy 262.772398 -52.055265)
			(xy 262.687773 -52.051233) (xy 262.603914 -52.039176) (xy 262.521581 -52.019202) (xy 262.441519 -51.991493)
			(xy 262.364454 -51.956298) (xy 262.291084 -51.913938) (xy 262.222072 -51.864795) (xy 262.158044 -51.809314)
			(xy 262.099579 -51.747999) (xy 262.047208 -51.681403) (xy 262.001405 -51.610131) (xy 261.962583 -51.534828)
			(xy 261.931095 -51.456176) (xy 261.907227 -51.374886) (xy 261.891193 -51.291696) (xy 261.88314 -51.207359)
			(xy 261.02183 -51.207359) (xy 261.02183 -51.862228) (xy 261.022198 -51.871272) (xy 261.028485 -51.888234)
			(xy 261.040267 -51.90196) (xy 261.047992 -51.906678) (xy 261.125462 -51.949858) (xy 261.133485 -51.953964)
			(xy 261.15127 -51.956806) (xy 261.168934 -51.95329) (xy 261.17677 -51.948842) (xy 261.177024 -51.948588)
			(xy 261.212192 -51.927377) (xy 261.285719 -51.890777) (xy 261.362309 -51.861115) (xy 261.441308 -51.838644)
			(xy 261.522043 -51.823556) (xy 261.603826 -51.81598) (xy 261.644892 -51.815492) (xy 261.6454 -51.815492)
			(xy 261.687748 -51.815996) (xy 261.772062 -51.824047) (xy 261.855228 -51.840076) (xy 261.936495 -51.863937)
			(xy 262.015125 -51.895416) (xy 262.090406 -51.934227) (xy 262.161658 -51.980017) (xy 262.228234 -52.032373)
			(xy 262.289532 -52.090821) (xy 262.344997 -52.154831) (xy 262.394126 -52.223823) (xy 262.436475 -52.297173)
			(xy 262.471659 -52.374216) (xy 262.499361 -52.454255) (xy 262.519329 -52.536564) (xy 262.531382 -52.620399)
			(xy 262.535413 -52.705) (xy 262.531382 -52.789601) (xy 262.519329 -52.873436) (xy 262.499361 -52.955745)
			(xy 262.471659 -53.035784) (xy 262.436475 -53.112827) (xy 262.394126 -53.186177) (xy 262.344997 -53.255169)
			(xy 262.289532 -53.319179) (xy 262.228234 -53.377627) (xy 262.161658 -53.429983) (xy 262.090406 -53.475773)
			(xy 262.015125 -53.514584) (xy 261.936495 -53.546063) (xy 261.855228 -53.569924) (xy 261.772062 -53.585953)
			(xy 261.687748 -53.594004) (xy 261.6454 -53.594508) (xy 261.644892 -53.594508) (xy 261.603826 -53.594022)
			(xy 261.522047 -53.586426) (xy 261.441315 -53.571329) (xy 261.362318 -53.548857) (xy 261.285727 -53.519202)
			(xy 261.212194 -53.482617) (xy 261.177024 -53.461412) (xy 261.17677 -53.461158) (xy 261.168901 -53.456791)
			(xy 261.151257 -53.453302) (xy 261.133485 -53.456067) (xy 261.125462 -53.460142) (xy 261.047992 -53.503322)
			(xy 261.040259 -53.508029) (xy 261.028478 -53.521757) (xy 261.022209 -53.538726) (xy 261.02183 -53.547772)
			(xy 261.02183 -53.650134) (xy 261.022274 -53.659922) (xy 261.029582 -53.678084) (xy 261.036054 -53.68544)
			(xy 261.062978 -53.713634) (xy 261.08025 -53.721762) (xy 261.089648 -53.72227) (xy 261.131324 -53.725572)
			(xy 261.213841 -53.739024) (xy 261.294733 -53.760158) (xy 261.373286 -53.788787) (xy 261.448807 -53.824658)
			(xy 261.520629 -53.867456) (xy 261.588121 -53.916802) (xy 261.650685 -53.972262) (xy 261.707771 -54.033347)
			(xy 261.758875 -54.099517) (xy 261.803546 -54.17019) (xy 261.841391 -54.244741) (xy 261.872075 -54.322514)
			(xy 261.895328 -54.402823) (xy 261.910945 -54.484958) (xy 261.918788 -54.568196) (xy 261.918788 -54.651804)
			(xy 261.910945 -54.735042) (xy 261.895328 -54.817177) (xy 261.872075 -54.897486) (xy 261.841391 -54.975259)
			(xy 261.803546 -55.04981) (xy 261.758875 -55.120483) (xy 261.707771 -55.186653) (xy 261.650685 -55.247738)
			(xy 261.588121 -55.303198) (xy 261.520629 -55.352544) (xy 261.448807 -55.395342) (xy 261.373286 -55.431213)
			(xy 261.294733 -55.459842) (xy 261.213841 -55.480976) (xy 261.131324 -55.494428) (xy 261.089648 -55.49773)
			(xy 261.08025 -55.498238) (xy 261.062978 -55.506366) (xy 261.036054 -55.53456) (xy 261.029575 -55.541912)
			(xy 261.022265 -55.560075) (xy 261.02183 -55.569866) (xy 261.02183 -64.558361) (xy 261.838182 -64.558361)
			(xy 261.838182 -64.473639) (xy 261.846235 -64.389302) (xy 261.862269 -64.306112) (xy 261.886137 -64.224822)
			(xy 261.917625 -64.14617) (xy 261.956447 -64.070867) (xy 262.00225 -63.999595) (xy 262.054621 -63.932999)
			(xy 262.113086 -63.871684) (xy 262.177114 -63.816203) (xy 262.246126 -63.76706) (xy 262.319496 -63.7247)
			(xy 262.396561 -63.689505) (xy 262.476623 -63.661796) (xy 262.558956 -63.641822) (xy 262.642815 -63.629765)
			(xy 262.72744 -63.625734) (xy 262.812065 -63.629765) (xy 262.895924 -63.641822) (xy 262.978257 -63.661796)
			(xy 263.058319 -63.689505) (xy 263.135384 -63.7247) (xy 263.208754 -63.76706) (xy 263.277766 -63.816203)
			(xy 263.341794 -63.871684) (xy 263.400259 -63.932999) (xy 263.45263 -63.999595) (xy 263.498433 -64.070867)
			(xy 263.537255 -64.14617) (xy 263.568743 -64.224822) (xy 263.592611 -64.306112) (xy 263.608645 -64.389302)
			(xy 263.616698 -64.473639) (xy 263.617202 -64.516) (xy 263.616698 -64.558361) (xy 263.608645 -64.642698)
			(xy 263.592611 -64.725888) (xy 263.568743 -64.807178) (xy 263.537255 -64.88583) (xy 263.498433 -64.961133)
			(xy 263.45263 -65.032405) (xy 263.400259 -65.099001) (xy 263.341794 -65.160316) (xy 263.277766 -65.215797)
			(xy 263.208754 -65.26494) (xy 263.135384 -65.3073) (xy 263.058319 -65.342495) (xy 262.978257 -65.370204)
			(xy 262.895924 -65.390178) (xy 262.812065 -65.402235) (xy 262.72744 -65.406267) (xy 262.642815 -65.402235)
			(xy 262.558956 -65.390178) (xy 262.476623 -65.370204) (xy 262.396561 -65.342495) (xy 262.319496 -65.3073)
			(xy 262.246126 -65.26494) (xy 262.177114 -65.215797) (xy 262.113086 -65.160316) (xy 262.054621 -65.099001)
			(xy 262.00225 -65.032405) (xy 261.956447 -64.961133) (xy 261.917625 -64.88583) (xy 261.886137 -64.807178)
			(xy 261.862269 -64.725888) (xy 261.846235 -64.642698) (xy 261.838182 -64.558361) (xy 261.02183 -64.558361)
			(xy 261.02183 -70.657466) (xy 261.02183 -70.66026) (xy 261.022945 -70.671137) (xy 261.033083 -70.690485)
			(xy 261.041388 -70.697598) (xy 261.044182 -70.69963) (xy 261.124446 -70.753732) (xy 261.149592 -70.756526)
			(xy 261.161276 -70.7517) (xy 261.200842 -70.73636) (xy 261.282257 -70.712405) (xy 261.365581 -70.696303)
			(xy 261.450059 -70.688201) (xy 261.492492 -70.687692) (xy 261.493254 -70.687692) (xy 261.539618 -70.688288)
			(xy 261.631843 -70.697935) (xy 261.722564 -70.717128) (xy 261.810793 -70.745659) (xy 261.853426 -70.763892)
			(xy 261.863368 -70.767698) (xy 261.884632 -70.767698) (xy 261.894574 -70.763892) (xy 261.937179 -70.745677)
			(xy 262.025348 -70.717165) (xy 262.116002 -70.697969) (xy 262.20816 -70.688298) (xy 262.254492 -70.687692)
			(xy 262.255 -70.687692) (xy 262.297348 -70.688196) (xy 262.381662 -70.696247) (xy 262.464828 -70.712276)
			(xy 262.546095 -70.736137) (xy 262.624725 -70.767616) (xy 262.700006 -70.806427) (xy 262.771258 -70.852217)
			(xy 262.837834 -70.904573) (xy 262.899132 -70.963021) (xy 262.954597 -71.027031) (xy 263.003726 -71.096023)
			(xy 263.046075 -71.169373) (xy 263.081259 -71.246416) (xy 263.108961 -71.326455) (xy 263.128929 -71.408764)
			(xy 263.140982 -71.492599) (xy 263.145013 -71.5772) (xy 263.140982 -71.661801) (xy 263.128929 -71.745636)
			(xy 263.108961 -71.827945) (xy 263.081259 -71.907984) (xy 263.046075 -71.985027) (xy 263.003726 -72.058377)
			(xy 262.954597 -72.127369) (xy 262.899132 -72.191379) (xy 262.837834 -72.249827) (xy 262.771258 -72.302183)
			(xy 262.700006 -72.347973) (xy 262.624725 -72.386784) (xy 262.546095 -72.418263) (xy 262.464828 -72.442124)
			(xy 262.381662 -72.458153) (xy 262.297348 -72.466204) (xy 262.255 -72.466708) (xy 262.254492 -72.466708)
			(xy 262.20816 -72.4661) (xy 262.116 -72.45644) (xy 262.025344 -72.437248) (xy 261.937177 -72.40873)
			(xy 261.894574 -72.390508) (xy 261.884632 -72.386702) (xy 261.863368 -72.386702) (xy 261.853426 -72.390508)
			(xy 261.810791 -72.408734) (xy 261.72256 -72.43726) (xy 261.631841 -72.456455) (xy 261.539618 -72.466114)
			(xy 261.493254 -72.466708) (xy 261.492492 -72.466708) (xy 261.450058 -72.466218) (xy 261.365576 -72.458134)
			(xy 261.282249 -72.44203) (xy 261.200839 -72.418052) (xy 261.161276 -72.4027) (xy 261.149592 -72.397874)
			(xy 261.124446 -72.400668) (xy 261.044182 -72.45477) (xy 261.041388 -72.456802) (xy 261.033088 -72.463918)
			(xy 261.022952 -72.483265) (xy 261.02183 -72.49414) (xy 261.02183 -76.296012) (xy 261.022245 -76.305628)
			(xy 261.029336 -76.323506) (xy 261.042516 -76.337513) (xy 261.05104 -76.341986) (xy 261.088791 -76.360278)
			(xy 261.161008 -76.402972) (xy 261.228886 -76.452273) (xy 261.291822 -76.507744) (xy 261.349258 -76.568893)
			(xy 261.400684 -76.635176) (xy 261.445643 -76.706005) (xy 261.483735 -76.780752) (xy 261.514624 -76.858751)
			(xy 261.538033 -76.939312) (xy 261.553757 -77.021718) (xy 261.561654 -77.105239) (xy 261.561656 -77.189132)
			(xy 261.553761 -77.272653) (xy 261.53804 -77.35506) (xy 261.514633 -77.435621) (xy 261.483747 -77.513622)
			(xy 261.445657 -77.58837) (xy 261.400701 -77.6592) (xy 261.349277 -77.725485) (xy 261.291843 -77.786636)
			(xy 261.228909 -77.842109) (xy 261.161032 -77.891413) (xy 261.088817 -77.934109) (xy 261.05104 -77.952346)
			(xy 261.042509 -77.956805) (xy 261.029332 -77.970819) (xy 261.022249 -77.988702) (xy 261.02183 -77.99832)
			(xy 261.02183 -85.262212) (xy 261.022256 -85.272281) (xy 261.029977 -85.290879) (xy 261.036816 -85.29828)
			(xy 263.858756 -88.12022) (xy 263.866154 -88.127067) (xy 263.884753 -88.134793) (xy 263.894824 -88.135206)
		)
		(stroke
			(width 0)
			(type solid)
		)
		(fill yes)
		(layer "In5.Cu")
		(net "P52V_1")
	)
	(gr_poly
		(pts
			(xy 8.69061 -157.283912) (xy 8.701029 -157.283399) (xy 8.720158 -157.275126) (xy 8.727694 -157.26791)
			(xy 8.747468 -157.24764) (xy 8.791935 -157.212581) (xy 8.841096 -157.184481) (xy 8.893871 -157.163956)
			(xy 8.9491 -157.151458) (xy 9.00557 -157.147261) (xy 9.06204 -157.151458) (xy 9.117269 -157.163956)
			(xy 9.170044 -157.184481) (xy 9.219205 -157.212581) (xy 9.263672 -157.24764) (xy 9.283446 -157.26791)
			(xy 9.290947 -157.275171) (xy 9.3101 -157.283424) (xy 9.32053 -157.283912) (xy 13.77061 -157.283912)
			(xy 13.781029 -157.283399) (xy 13.800158 -157.275126) (xy 13.807694 -157.26791) (xy 13.827468 -157.24764)
			(xy 13.871935 -157.212581) (xy 13.921096 -157.184481) (xy 13.973871 -157.163956) (xy 14.0291 -157.151458)
			(xy 14.08557 -157.147261) (xy 14.14204 -157.151458) (xy 14.197269 -157.163956) (xy 14.250044 -157.184481)
			(xy 14.299205 -157.212581) (xy 14.343672 -157.24764) (xy 14.363446 -157.26791) (xy 14.370947 -157.275171)
			(xy 14.3901 -157.283424) (xy 14.40053 -157.283912) (xy 18.85061 -157.283912) (xy 18.861029 -157.283399)
			(xy 18.880158 -157.275126) (xy 18.887694 -157.26791) (xy 18.907468 -157.24764) (xy 18.951935 -157.212581)
			(xy 19.001096 -157.184481) (xy 19.053871 -157.163956) (xy 19.1091 -157.151458) (xy 19.16557 -157.147261)
			(xy 19.22204 -157.151458) (xy 19.277269 -157.163956) (xy 19.330044 -157.184481) (xy 19.379205 -157.212581)
			(xy 19.423672 -157.24764) (xy 19.443446 -157.26791) (xy 19.450947 -157.275171) (xy 19.4701 -157.283424)
			(xy 19.48053 -157.283912) (xy 21.99767 -157.283912) (xy 22.007735 -157.283477) (xy 22.026322 -157.275746)
			(xy 22.033738 -157.268926) (xy 22.689566 -156.613098) (xy 22.696416 -156.605701) (xy 22.704155 -156.587103)
			(xy 22.704552 -156.57703) (xy 22.704552 -44.961048) (xy 22.70507 -44.927786) (xy 22.713751 -44.861832)
			(xy 22.730971 -44.797577) (xy 22.756434 -44.73612) (xy 22.789704 -44.678515) (xy 22.830212 -44.625747)
			(xy 22.853396 -44.601892) (xy 33.29686 -34.158428) (xy 33.30448 -34.137092) (xy 33.30321 -34.125662)
			(xy 33.301137 -34.103305) (xy 33.298976 -34.058453) (xy 33.298892 -34.036) (xy 33.299367 -33.994898)
			(xy 33.306952 -33.913043) (xy 33.322057 -33.832238) (xy 33.344553 -33.753171) (xy 33.374249 -33.676517)
			(xy 33.410891 -33.60293) (xy 33.454166 -33.533038) (xy 33.503706 -33.467437) (xy 33.559087 -33.406687)
			(xy 33.619837 -33.351306) (xy 33.685438 -33.301766) (xy 33.75533 -33.258491) (xy 33.828917 -33.221849)
			(xy 33.905571 -33.192153) (xy 33.984638 -33.169657) (xy 34.065443 -33.154552) (xy 34.147298 -33.146967)
			(xy 34.1884 -33.146492) (xy 34.211427 -33.146595) (xy 34.257424 -33.148881) (xy 34.280348 -33.151064)
			(xy 34.290624 -33.151678) (xy 34.310288 -33.145654) (xy 34.318448 -33.13938) (xy 34.341386 -33.12062)
			(xy 34.390857 -33.087996) (xy 34.443787 -33.061348) (xy 34.499458 -33.041039) (xy 34.557113 -33.027344)
			(xy 34.61597 -33.02045) (xy 34.6456 -33.02) (xy 57.66181 -33.02) (xy 57.671879 -33.019575) (xy 57.690481 -33.011858)
			(xy 57.697878 -33.005014) (xy 57.793636 -32.909256) (xy 57.801256 -32.890206) (xy 57.800748 -32.879538)
			(xy 57.800494 -32.85871) (xy 57.800494 -22.431502) (xy 57.800153 -22.422615) (xy 57.794057 -22.405919)
			(xy 57.782606 -22.392326) (xy 57.775094 -22.38756) (xy 57.719579 -22.354802) (xy 57.612238 -22.283409)
			(xy 57.509488 -22.205552) (xy 57.411717 -22.121528) (xy 57.319296 -22.031654) (xy 57.232573 -21.936269)
			(xy 57.151877 -21.835734) (xy 57.077513 -21.730429) (xy 57.009761 -21.620753) (xy 56.948878 -21.50712)
			(xy 56.895095 -21.389961) (xy 56.848614 -21.269716) (xy 56.809611 -21.146843) (xy 56.778235 -21.021804)
			(xy 56.754602 -20.895074) (xy 56.738804 -20.76713) (xy 56.730899 -20.638458) (xy 56.730392 -20.574)
			(xy 56.730879 -20.509543) (xy 56.73879 -20.380871) (xy 56.754594 -20.252929) (xy 56.77823 -20.126199)
			(xy 56.809611 -20.001162) (xy 56.848617 -19.87829) (xy 56.895101 -19.758048) (xy 56.948886 -19.640889)
			(xy 57.009771 -19.527258) (xy 57.077524 -19.417583) (xy 57.151889 -19.31228) (xy 57.232585 -19.211746)
			(xy 57.319308 -19.116361) (xy 57.411729 -19.026487) (xy 57.509498 -18.942463) (xy 57.612247 -18.864606)
			(xy 57.719587 -18.793211) (xy 57.775094 -18.76044) (xy 57.782587 -18.755661) (xy 57.793999 -18.742057)
			(xy 57.800088 -18.725376) (xy 57.800494 -18.716498) (xy 57.800494 -1.761744) (xy 57.80006 -1.751678)
			(xy 57.792331 -1.733089) (xy 57.785508 -1.725676) (xy 57.090818 -1.030986) (xy 57.083419 -1.024143)
			(xy 57.06482 -1.016425) (xy 57.05475 -1.016) (xy 56.553862 -1.016) (xy 56.543415 -1.016563) (xy 56.524271 -1.024954)
			(xy 56.516778 -1.032256) (xy 56.496959 -1.052804) (xy 56.452307 -1.088372) (xy 56.402856 -1.116893)
			(xy 56.349709 -1.137732) (xy 56.294051 -1.150425) (xy 56.237124 -1.154687) (xy 56.180197 -1.150425)
			(xy 56.124539 -1.137732) (xy 56.071392 -1.116893) (xy 56.021941 -1.088372) (xy 55.977289 -1.052804)
			(xy 55.95747 -1.032256) (xy 55.949995 -1.024929) (xy 55.93084 -1.01655) (xy 55.920386 -1.016) (xy 51.473862 -1.016)
			(xy 51.463415 -1.016563) (xy 51.444271 -1.024954) (xy 51.436778 -1.032256) (xy 51.416959 -1.052804)
			(xy 51.372307 -1.088372) (xy 51.322856 -1.116893) (xy 51.269709 -1.137732) (xy 51.214051 -1.150425)
			(xy 51.157124 -1.154687) (xy 51.100197 -1.150425) (xy 51.044539 -1.137732) (xy 50.991392 -1.116893)
			(xy 50.941941 -1.088372) (xy 50.897289 -1.052804) (xy 50.87747 -1.032256) (xy 50.869995 -1.024929)
			(xy 50.85084 -1.01655) (xy 50.840386 -1.016) (xy 46.393862 -1.016) (xy 46.383415 -1.016563) (xy 46.364271 -1.024954)
			(xy 46.356778 -1.032256) (xy 46.336959 -1.052804) (xy 46.292307 -1.088372) (xy 46.242856 -1.116893)
			(xy 46.189709 -1.137732) (xy 46.134051 -1.150425) (xy 46.077124 -1.154687) (xy 46.020197 -1.150425)
			(xy 45.964539 -1.137732) (xy 45.911392 -1.116893) (xy 45.861941 -1.088372) (xy 45.817289 -1.052804)
			(xy 45.79747 -1.032256) (xy 45.789995 -1.024929) (xy 45.77084 -1.01655) (xy 45.760386 -1.016) (xy 41.313862 -1.016)
			(xy 41.303415 -1.016563) (xy 41.284271 -1.024954) (xy 41.276778 -1.032256) (xy 41.256959 -1.052804)
			(xy 41.212307 -1.088372) (xy 41.162856 -1.116893) (xy 41.109709 -1.137732) (xy 41.054051 -1.150425)
			(xy 40.997124 -1.154687) (xy 40.940197 -1.150425) (xy 40.884539 -1.137732) (xy 40.831392 -1.116893)
			(xy 40.781941 -1.088372) (xy 40.737289 -1.052804) (xy 40.71747 -1.032256) (xy 40.709995 -1.024929)
			(xy 40.69084 -1.01655) (xy 40.680386 -1.016) (xy 36.233862 -1.016) (xy 36.223415 -1.016563) (xy 36.204271 -1.024954)
			(xy 36.196778 -1.032256) (xy 36.176959 -1.052804) (xy 36.132307 -1.088372) (xy 36.082856 -1.116893)
			(xy 36.029709 -1.137732) (xy 35.974051 -1.150425) (xy 35.917124 -1.154687) (xy 35.860197 -1.150425)
			(xy 35.804539 -1.137732) (xy 35.751392 -1.116893) (xy 35.701941 -1.088372) (xy 35.657289 -1.052804)
			(xy 35.63747 -1.032256) (xy 35.629995 -1.024929) (xy 35.61084 -1.01655) (xy 35.600386 -1.016) (xy 31.153862 -1.016)
			(xy 31.143415 -1.016563) (xy 31.124271 -1.024954) (xy 31.116778 -1.032256) (xy 31.096959 -1.052804)
			(xy 31.052307 -1.088372) (xy 31.002856 -1.116893) (xy 30.949709 -1.137732) (xy 30.894051 -1.150425)
			(xy 30.837124 -1.154687) (xy 30.780197 -1.150425) (xy 30.724539 -1.137732) (xy 30.671392 -1.116893)
			(xy 30.621941 -1.088372) (xy 30.577289 -1.052804) (xy 30.55747 -1.032256) (xy 30.549995 -1.024929)
			(xy 30.53084 -1.01655) (xy 30.520386 -1.016) (xy 26.073862 -1.016) (xy 26.063415 -1.016563) (xy 26.044271 -1.024954)
			(xy 26.036778 -1.032256) (xy 26.016959 -1.052804) (xy 25.972307 -1.088372) (xy 25.922856 -1.116893)
			(xy 25.869709 -1.137732) (xy 25.814051 -1.150425) (xy 25.757124 -1.154687) (xy 25.700197 -1.150425)
			(xy 25.644539 -1.137732) (xy 25.591392 -1.116893) (xy 25.541941 -1.088372) (xy 25.497289 -1.052804)
			(xy 25.47747 -1.032256) (xy 25.469995 -1.024929) (xy 25.45084 -1.01655) (xy 25.440386 -1.016) (xy 20.993862 -1.016)
			(xy 20.983415 -1.016563) (xy 20.964271 -1.024954) (xy 20.956778 -1.032256) (xy 20.936959 -1.052804)
			(xy 20.892307 -1.088372) (xy 20.842856 -1.116893) (xy 20.789709 -1.137732) (xy 20.734051 -1.150425)
			(xy 20.677124 -1.154687) (xy 20.620197 -1.150425) (xy 20.564539 -1.137732) (xy 20.511392 -1.116893)
			(xy 20.461941 -1.088372) (xy 20.417289 -1.052804) (xy 20.39747 -1.032256) (xy 20.389995 -1.024929)
			(xy 20.37084 -1.01655) (xy 20.360386 -1.016) (xy 8.11022 -1.016) (xy 8.099978 -1.016474) (xy 8.081122 -1.024478)
			(xy 8.073644 -1.031494) (xy 8.053949 -1.051039) (xy 8.009917 -1.084801) (xy 7.961459 -1.111829) (xy 7.909597 -1.131553)
			(xy 7.855425 -1.143556) (xy 7.800086 -1.147586) (xy 7.744747 -1.143556) (xy 7.690575 -1.131553) (xy 7.638713 -1.111829)
			(xy 7.590255 -1.084801) (xy 7.546223 -1.051039) (xy 7.526528 -1.031494) (xy 7.519077 -1.024442) (xy 7.500202 -1.016451)
			(xy 7.489952 -1.016) (xy 4.99999 -1.016) (xy 4.908159 -1.016535) (xy 4.724692 -1.025013) (xy 4.541811 -1.041936)
			(xy 4.359903 -1.067266) (xy 4.179356 -1.10095) (xy 4.000552 -1.142916) (xy 3.823872 -1.193076) (xy 3.64969 -1.251323)
			(xy 3.478377 -1.317533) (xy 3.310297 -1.391566) (xy 3.145805 -1.473264) (xy 3.065272 -1.517396) (xy 3.055752 -1.523279)
			(xy 3.042572 -1.541333) (xy 3.039872 -1.552194) (xy 3.034517 -1.578033) (xy 3.017628 -1.628025) (xy 2.994005 -1.675209)
			(xy 2.964098 -1.718684) (xy 2.928481 -1.757618) (xy 2.887834 -1.791266) (xy 2.842933 -1.818986) (xy 2.794639 -1.840248)
			(xy 2.743873 -1.854644) (xy 2.691606 -1.8619) (xy 2.665222 -1.862328) (xy 2.645131 -1.862086) (xy 2.605168 -1.857888)
			(xy 2.585466 -1.853946) (xy 2.574372 -1.852091) (xy 2.552469 -1.857083) (xy 2.543302 -1.863598) (xy 2.472546 -1.919663)
			(xy 2.335599 -2.037321) (xy 2.204122 -2.161062) (xy 2.078386 -2.290632) (xy 1.958649 -2.425765) (xy 1.845157 -2.566184)
			(xy 1.738142 -2.7116) (xy 1.637825 -2.861714) (xy 1.544411 -3.016219) (xy 1.458092 -3.174798) (xy 1.379046 -3.337123)
			(xy 1.307435 -3.502863) (xy 1.243405 -3.671677) (xy 1.187089 -3.843219) (xy 1.138601 -4.017135) (xy 1.098042 -4.193069)
			(xy 1.065495 -4.37066) (xy 1.041027 -4.549544) (xy 1.024687 -4.729352) (xy 1.01651 -4.909716) (xy 1.016 -4.99999)
			(xy 1.016 -5.76707) (xy 1.016472 -5.777312) (xy 1.024474 -5.796171) (xy 1.031494 -5.803646) (xy 1.051201 -5.823366)
			(xy 1.085261 -5.867503) (xy 1.112534 -5.916126) (xy 1.132441 -5.968201) (xy 1.144557 -6.022619) (xy 1.148624 -6.07822)
			(xy 1.144557 -6.133821) (xy 1.132441 -6.188239) (xy 1.112534 -6.240314) (xy 1.085261 -6.288937) (xy 1.051201 -6.333074)
			(xy 1.031494 -6.352794) (xy 1.024446 -6.360247) (xy 1.016463 -6.379122) (xy 1.016 -6.38937) (xy 1.016 -10.84707)
			(xy 1.016472 -10.857312) (xy 1.024474 -10.876171) (xy 1.031494 -10.883646) (xy 1.051201 -10.903366)
			(xy 1.085261 -10.947503) (xy 1.112534 -10.996126) (xy 1.132441 -11.048201) (xy 1.144557 -11.102619)
			(xy 1.148624 -11.15822) (xy 1.144557 -11.213821) (xy 1.132441 -11.268239) (xy 1.112534 -11.320314)
			(xy 1.085261 -11.368937) (xy 1.051201 -11.413074) (xy 1.031494 -11.432794) (xy 1.024446 -11.440247)
			(xy 1.016463 -11.459122) (xy 1.016 -11.46937) (xy 1.016 -15.92707) (xy 1.016472 -15.937312) (xy 1.024474 -15.956171)
			(xy 1.031494 -15.963646) (xy 1.051201 -15.983366) (xy 1.085261 -16.027503) (xy 1.112534 -16.076126)
			(xy 1.132441 -16.128201) (xy 1.144557 -16.182619) (xy 1.148624 -16.23822) (xy 1.144557 -16.293821)
			(xy 1.132441 -16.348239) (xy 1.112534 -16.400314) (xy 1.085261 -16.448937) (xy 1.051201 -16.493074)
			(xy 1.031494 -16.512794) (xy 1.024446 -16.520247) (xy 1.016463 -16.539122) (xy 1.016 -16.54937) (xy 1.016 -21.00707)
			(xy 1.016472 -21.017312) (xy 1.024474 -21.036171) (xy 1.031494 -21.043646) (xy 1.051201 -21.063366)
			(xy 1.085261 -21.107503) (xy 1.112534 -21.156126) (xy 1.132441 -21.208201) (xy 1.144557 -21.262619)
			(xy 1.148624 -21.31822) (xy 1.144557 -21.373821) (xy 1.132441 -21.428239) (xy 1.112534 -21.480314)
			(xy 1.085261 -21.528937) (xy 1.051201 -21.573074) (xy 1.031494 -21.592794) (xy 1.024446 -21.600247)
			(xy 1.016463 -21.619122) (xy 1.016 -21.62937) (xy 1.016 -26.08707) (xy 1.016472 -26.097312) (xy 1.024474 -26.116171)
			(xy 1.031494 -26.123646) (xy 1.051201 -26.143366) (xy 1.085261 -26.187503) (xy 1.112534 -26.236126)
			(xy 1.132441 -26.288201) (xy 1.144557 -26.342619) (xy 1.148624 -26.39822) (xy 1.144557 -26.453821)
			(xy 1.132441 -26.508239) (xy 1.112534 -26.560314) (xy 1.085261 -26.608937) (xy 1.051201 -26.653074)
			(xy 1.031494 -26.672794) (xy 1.024446 -26.680247) (xy 1.016463 -26.699122) (xy 1.016 -26.70937) (xy 1.016 -31.16707)
			(xy 1.016472 -31.177312) (xy 1.024474 -31.196171) (xy 1.031494 -31.203646) (xy 1.051201 -31.223366)
			(xy 1.085261 -31.267503) (xy 1.112534 -31.316126) (xy 1.132441 -31.368201) (xy 1.144557 -31.422619)
			(xy 1.148624 -31.47822) (xy 1.144557 -31.533821) (xy 1.132441 -31.588239) (xy 1.112534 -31.640314)
			(xy 1.085261 -31.688937) (xy 1.051201 -31.733074) (xy 1.031494 -31.752794) (xy 1.024446 -31.760247)
			(xy 1.016463 -31.779122) (xy 1.016 -31.78937) (xy 1.016 -36.24707) (xy 1.016472 -36.257312) (xy 1.024474 -36.276171)
			(xy 1.031494 -36.283646) (xy 1.051201 -36.303366) (xy 1.085261 -36.347503) (xy 1.112534 -36.396126)
			(xy 1.132441 -36.448201) (xy 1.144557 -36.502619) (xy 1.148624 -36.55822) (xy 1.144557 -36.613821)
			(xy 1.132441 -36.668239) (xy 1.112534 -36.720314) (xy 1.085261 -36.768937) (xy 1.051201 -36.813074)
			(xy 1.031494 -36.832794) (xy 1.024446 -36.840247) (xy 1.016463 -36.859122) (xy 1.016 -36.86937) (xy 1.016 -41.32707)
			(xy 1.016472 -41.337312) (xy 1.024474 -41.356171) (xy 1.031494 -41.363646) (xy 1.051201 -41.383366)
			(xy 1.085261 -41.427503) (xy 1.112534 -41.476126) (xy 1.132441 -41.528201) (xy 1.144557 -41.582619)
			(xy 1.148624 -41.63822) (xy 1.144557 -41.693821) (xy 1.132441 -41.748239) (xy 1.112534 -41.800314)
			(xy 1.085261 -41.848937) (xy 1.051201 -41.893074) (xy 1.031494 -41.912794) (xy 1.024446 -41.920247)
			(xy 1.016463 -41.939122) (xy 1.016 -41.94937) (xy 1.016 -46.40707) (xy 1.016472 -46.417312) (xy 1.024474 -46.436171)
			(xy 1.031494 -46.443646) (xy 1.051201 -46.463366) (xy 1.085261 -46.507503) (xy 1.112534 -46.556126)
			(xy 1.132441 -46.608201) (xy 1.144557 -46.662619) (xy 1.148624 -46.71822) (xy 1.144557 -46.773821)
			(xy 1.132441 -46.828239) (xy 1.112534 -46.880314) (xy 1.085261 -46.928937) (xy 1.051201 -46.973074)
			(xy 1.031494 -46.992794) (xy 1.024446 -47.000247) (xy 1.016463 -47.019122) (xy 1.016 -47.02937) (xy 1.016 -51.48707)
			(xy 1.016472 -51.497312) (xy 1.024474 -51.516171) (xy 1.031494 -51.523646) (xy 1.051201 -51.543366)
			(xy 1.085261 -51.587503) (xy 1.112534 -51.636126) (xy 1.132441 -51.688201) (xy 1.144557 -51.742619)
			(xy 1.148624 -51.79822) (xy 1.144557 -51.853821) (xy 1.132441 -51.908239) (xy 1.112534 -51.960314)
			(xy 1.085261 -52.008937) (xy 1.051201 -52.053074) (xy 1.031494 -52.072794) (xy 1.024446 -52.080247)
			(xy 1.016463 -52.099122) (xy 1.016 -52.10937) (xy 1.016 -56.56707) (xy 1.016472 -56.577312) (xy 1.024474 -56.596171)
			(xy 1.031494 -56.603646) (xy 1.051201 -56.623366) (xy 1.085261 -56.667503) (xy 1.112534 -56.716126)
			(xy 1.132441 -56.768201) (xy 1.144557 -56.822619) (xy 1.148624 -56.87822) (xy 1.144557 -56.933821)
			(xy 1.132441 -56.988239) (xy 1.112534 -57.040314) (xy 1.085261 -57.088937) (xy 1.051201 -57.133074)
			(xy 1.031494 -57.152794) (xy 1.024446 -57.160247) (xy 1.016463 -57.179122) (xy 1.016 -57.18937) (xy 1.016 -60.099956)
			(xy 12.484104 -60.099956) (xy 12.488134 -59.957621) (xy 12.500209 -59.815741) (xy 12.520292 -59.674773)
			(xy 12.548319 -59.535166) (xy 12.584199 -59.397368) (xy 12.627817 -59.261821) (xy 12.679034 -59.128959)
			(xy 12.737685 -58.999207) (xy 12.803583 -58.872981) (xy 12.876517 -58.750685) (xy 12.956254 -58.632712)
			(xy 13.042536 -58.519439) (xy 13.135089 -58.411228) (xy 13.233616 -58.308427) (xy 13.337801 -58.211365)
			(xy 13.44731 -58.120353) (xy 13.561793 -58.035681) (xy 13.680883 -57.957623) (xy 13.804198 -57.886427)
			(xy 13.931344 -57.822321) (xy 14.061913 -57.765512) (xy 14.195487 -57.71618) (xy 14.331638 -57.674484)
			(xy 14.469929 -57.640558) (xy 14.609919 -57.61451) (xy 14.751158 -57.596424) (xy 14.893194 -57.586357)
			(xy 15.035572 -57.584342) (xy 15.177836 -57.590385) (xy 15.31953 -57.604467) (xy 15.4602 -57.626543)
			(xy 15.599397 -57.656543) (xy 15.736673 -57.694369) (xy 15.871589 -57.739901) (xy 16.003713 -57.792992)
			(xy 16.132622 -57.853474) (xy 16.257903 -57.921152) (xy 16.379154 -57.995809) (xy 16.495987 -58.077207)
			(xy 16.608028 -58.165084) (xy 16.714918 -58.259159) (xy 16.816315 -58.359131) (xy 16.911893 -58.464679)
			(xy 17.001347 -58.575465) (xy 17.084389 -58.691134) (xy 17.160755 -58.811317) (xy 17.230199 -58.935627)
			(xy 17.292499 -59.063668) (xy 17.347455 -59.195027) (xy 17.394892 -59.329286) (xy 17.434656 -59.466013)
			(xy 17.466622 -59.604771) (xy 17.490687 -59.745115) (xy 17.506773 -59.886596) (xy 17.514828 -60.02876)
			(xy 17.515332 -60.099956) (xy 17.514828 -60.171152) (xy 17.506773 -60.313316) (xy 17.490687 -60.454797)
			(xy 17.466622 -60.595141) (xy 17.434656 -60.733899) (xy 17.394892 -60.870626) (xy 17.347455 -61.004885)
			(xy 17.292499 -61.136244) (xy 17.230199 -61.264285) (xy 17.160755 -61.388595) (xy 17.084389 -61.508778)
			(xy 17.001347 -61.624447) (xy 16.911893 -61.735233) (xy 16.816315 -61.840781) (xy 16.714918 -61.940753)
			(xy 16.608028 -62.034828) (xy 16.495987 -62.122705) (xy 16.379154 -62.204103) (xy 16.257903 -62.27876)
			(xy 16.132622 -62.346438) (xy 16.003713 -62.40692) (xy 15.871589 -62.460011) (xy 15.736673 -62.505543)
			(xy 15.599397 -62.543369) (xy 15.4602 -62.573369) (xy 15.31953 -62.595445) (xy 15.177836 -62.609527)
			(xy 15.035572 -62.61557) (xy 14.893194 -62.613555) (xy 14.751158 -62.603488) (xy 14.609919 -62.585402)
			(xy 14.469929 -62.559354) (xy 14.331638 -62.525428) (xy 14.195487 -62.483732) (xy 14.061913 -62.4344)
			(xy 13.931344 -62.377591) (xy 13.804198 -62.313485) (xy 13.680883 -62.242289) (xy 13.561793 -62.164231)
			(xy 13.44731 -62.079559) (xy 13.337801 -61.988547) (xy 13.233616 -61.891485) (xy 13.135089 -61.788684)
			(xy 13.042536 -61.680473) (xy 12.956254 -61.5672) (xy 12.876517 -61.449227) (xy 12.803583 -61.326931)
			(xy 12.737685 -61.200705) (xy 12.679034 -61.070953) (xy 12.627817 -60.938091) (xy 12.584199 -60.802544)
			(xy 12.548319 -60.664746) (xy 12.520292 -60.525139) (xy 12.500209 -60.384171) (xy 12.488134 -60.242291)
			(xy 12.484104 -60.099956) (xy 1.016 -60.099956) (xy 1.016 -61.64707) (xy 1.016472 -61.657312) (xy 1.024474 -61.676171)
			(xy 1.031494 -61.683646) (xy 1.051201 -61.703366) (xy 1.085261 -61.747503) (xy 1.112534 -61.796126)
			(xy 1.132441 -61.848201) (xy 1.144557 -61.902619) (xy 1.148624 -61.95822) (xy 1.144557 -62.013821)
			(xy 1.132441 -62.068239) (xy 1.112534 -62.120314) (xy 1.085261 -62.168937) (xy 1.051201 -62.213074)
			(xy 1.031494 -62.232794) (xy 1.024446 -62.240247) (xy 1.016463 -62.259122) (xy 1.016 -62.26937) (xy 1.016 -66.72707)
			(xy 1.016472 -66.737312) (xy 1.024474 -66.756171) (xy 1.031494 -66.763646) (xy 1.051201 -66.783366)
			(xy 1.085261 -66.827503) (xy 1.112534 -66.876126) (xy 1.132441 -66.928201) (xy 1.144557 -66.982619)
			(xy 1.148624 -67.03822) (xy 1.144557 -67.093821) (xy 1.132441 -67.148239) (xy 1.112534 -67.200314)
			(xy 1.085261 -67.248937) (xy 1.051201 -67.293074) (xy 1.031494 -67.312794) (xy 1.024446 -67.320247)
			(xy 1.016463 -67.339122) (xy 1.016 -67.34937) (xy 1.016 -71.80707) (xy 1.016472 -71.817312) (xy 1.024474 -71.836171)
			(xy 1.031494 -71.843646) (xy 1.051201 -71.863366) (xy 1.085261 -71.907503) (xy 1.112534 -71.956126)
			(xy 1.132441 -72.008201) (xy 1.144557 -72.062619) (xy 1.148624 -72.11822) (xy 1.144557 -72.173821)
			(xy 1.132441 -72.228239) (xy 1.112534 -72.280314) (xy 1.085261 -72.328937) (xy 1.051201 -72.373074)
			(xy 1.031494 -72.392794) (xy 1.024446 -72.400247) (xy 1.016463 -72.419122) (xy 1.016 -72.42937) (xy 1.016 -76.88707)
			(xy 1.016472 -76.897312) (xy 1.024474 -76.916171) (xy 1.031494 -76.923646) (xy 1.051201 -76.943366)
			(xy 1.085261 -76.987503) (xy 1.112534 -77.036126) (xy 1.132441 -77.088201) (xy 1.144557 -77.142619)
			(xy 1.148624 -77.19822) (xy 1.144557 -77.253821) (xy 1.132441 -77.308239) (xy 1.112534 -77.360314)
			(xy 1.085261 -77.408937) (xy 1.051201 -77.453074) (xy 1.031494 -77.472794) (xy 1.024446 -77.480247)
			(xy 1.016463 -77.499122) (xy 1.016 -77.50937) (xy 1.016 -81.96707) (xy 1.016472 -81.977312) (xy 1.024474 -81.996171)
			(xy 1.031494 -82.003646) (xy 1.051201 -82.023366) (xy 1.085261 -82.067503) (xy 1.112534 -82.116126)
			(xy 1.132441 -82.168201) (xy 1.144557 -82.222619) (xy 1.148624 -82.27822) (xy 1.144557 -82.333821)
			(xy 1.132441 -82.388239) (xy 1.112534 -82.440314) (xy 1.085261 -82.488937) (xy 1.051201 -82.533074)
			(xy 1.031494 -82.552794) (xy 1.024446 -82.560247) (xy 1.016463 -82.579122) (xy 1.016 -82.58937) (xy 1.016 -87.04707)
			(xy 1.016472 -87.057312) (xy 1.024474 -87.076171) (xy 1.031494 -87.083646) (xy 1.051201 -87.103366)
			(xy 1.085261 -87.147503) (xy 1.112534 -87.196126) (xy 1.132441 -87.248201) (xy 1.144557 -87.302619)
			(xy 1.148624 -87.35822) (xy 1.144557 -87.413821) (xy 1.132441 -87.468239) (xy 1.112534 -87.520314)
			(xy 1.085261 -87.568937) (xy 1.051201 -87.613074) (xy 1.031494 -87.632794) (xy 1.024446 -87.640247)
			(xy 1.016463 -87.659122) (xy 1.016 -87.66937) (xy 1.016 -92.12707) (xy 1.016472 -92.137312) (xy 1.024474 -92.156171)
			(xy 1.031494 -92.163646) (xy 1.051201 -92.183366) (xy 1.085261 -92.227503) (xy 1.112534 -92.276126)
			(xy 1.132441 -92.328201) (xy 1.144557 -92.382619) (xy 1.148624 -92.43822) (xy 1.144557 -92.493821)
			(xy 1.132441 -92.548239) (xy 1.112534 -92.600314) (xy 1.085261 -92.648937) (xy 1.051201 -92.693074)
			(xy 1.031494 -92.712794) (xy 1.024446 -92.720247) (xy 1.016463 -92.739122) (xy 1.016 -92.74937) (xy 1.016 -97.20707)
			(xy 1.016472 -97.217312) (xy 1.024474 -97.236171) (xy 1.031494 -97.243646) (xy 1.051201 -97.263366)
			(xy 1.085261 -97.307503) (xy 1.112534 -97.356126) (xy 1.132441 -97.408201) (xy 1.144557 -97.462619)
			(xy 1.148624 -97.51822) (xy 1.144557 -97.573821) (xy 1.132441 -97.628239) (xy 1.112534 -97.680314)
			(xy 1.085261 -97.728937) (xy 1.051201 -97.773074) (xy 1.031494 -97.792794) (xy 1.024446 -97.800247)
			(xy 1.016463 -97.819122) (xy 1.016 -97.82937) (xy 1.016 -102.28707) (xy 1.016472 -102.297312) (xy 1.024474 -102.316171)
			(xy 1.031494 -102.323646) (xy 1.051201 -102.343366) (xy 1.085261 -102.387503) (xy 1.112534 -102.436126)
			(xy 1.132441 -102.488201) (xy 1.144557 -102.542619) (xy 1.148624 -102.59822) (xy 1.144557 -102.653821)
			(xy 1.132441 -102.708239) (xy 1.112534 -102.760314) (xy 1.085261 -102.808937) (xy 1.051201 -102.853074)
			(xy 1.031494 -102.872794) (xy 1.024446 -102.880247) (xy 1.016463 -102.899122) (xy 1.016 -102.90937)
			(xy 1.016 -104.544876) (xy 12.484104 -104.544876) (xy 12.488134 -104.402541) (xy 12.500209 -104.260661)
			(xy 12.520292 -104.119693) (xy 12.548319 -103.980086) (xy 12.584199 -103.842288) (xy 12.627817 -103.706741)
			(xy 12.679034 -103.573879) (xy 12.737685 -103.444127) (xy 12.803583 -103.317901) (xy 12.876517 -103.195605)
			(xy 12.956254 -103.077632) (xy 13.042536 -102.964359) (xy 13.135089 -102.856148) (xy 13.233616 -102.753347)
			(xy 13.337801 -102.656285) (xy 13.44731 -102.565273) (xy 13.561793 -102.480601) (xy 13.680883 -102.402543)
			(xy 13.804198 -102.331347) (xy 13.931344 -102.267241) (xy 14.061913 -102.210432) (xy 14.195487 -102.1611)
			(xy 14.331638 -102.119404) (xy 14.469929 -102.085478) (xy 14.609919 -102.05943) (xy 14.751158 -102.041344)
			(xy 14.893194 -102.031277) (xy 15.035572 -102.029262) (xy 15.177836 -102.035305) (xy 15.31953 -102.049387)
			(xy 15.4602 -102.071463) (xy 15.599397 -102.101463) (xy 15.736673 -102.139289) (xy 15.871589 -102.184821)
			(xy 16.003713 -102.237912) (xy 16.132622 -102.298394) (xy 16.257903 -102.366072) (xy 16.379154 -102.440729)
			(xy 16.495987 -102.522127) (xy 16.608028 -102.610004) (xy 16.714918 -102.704079) (xy 16.816315 -102.804051)
			(xy 16.911893 -102.909599) (xy 17.001347 -103.020385) (xy 17.084389 -103.136054) (xy 17.160755 -103.256237)
			(xy 17.230199 -103.380547) (xy 17.292499 -103.508588) (xy 17.347455 -103.639947) (xy 17.394892 -103.774206)
			(xy 17.434656 -103.910933) (xy 17.466622 -104.049691) (xy 17.490687 -104.190035) (xy 17.506773 -104.331516)
			(xy 17.514828 -104.47368) (xy 17.515332 -104.544876) (xy 17.514828 -104.616072) (xy 17.506773 -104.758236)
			(xy 17.490687 -104.899717) (xy 17.466622 -105.040061) (xy 17.434656 -105.178819) (xy 17.394892 -105.315546)
			(xy 17.347455 -105.449805) (xy 17.292499 -105.581164) (xy 17.230199 -105.709205) (xy 17.160755 -105.833515)
			(xy 17.084389 -105.953698) (xy 17.001347 -106.069367) (xy 16.911893 -106.180153) (xy 16.816315 -106.285701)
			(xy 16.714918 -106.385673) (xy 16.608028 -106.479748) (xy 16.495987 -106.567625) (xy 16.379154 -106.649023)
			(xy 16.257903 -106.72368) (xy 16.132622 -106.791358) (xy 16.003713 -106.85184) (xy 15.871589 -106.904931)
			(xy 15.736673 -106.950463) (xy 15.599397 -106.988289) (xy 15.4602 -107.018289) (xy 15.31953 -107.040365)
			(xy 15.177836 -107.054447) (xy 15.035572 -107.06049) (xy 14.893194 -107.058475) (xy 14.751158 -107.048408)
			(xy 14.609919 -107.030322) (xy 14.469929 -107.004274) (xy 14.331638 -106.970348) (xy 14.195487 -106.928652)
			(xy 14.061913 -106.87932) (xy 13.931344 -106.822511) (xy 13.804198 -106.758405) (xy 13.680883 -106.687209)
			(xy 13.561793 -106.609151) (xy 13.44731 -106.524479) (xy 13.337801 -106.433467) (xy 13.233616 -106.336405)
			(xy 13.135089 -106.233604) (xy 13.042536 -106.125393) (xy 12.956254 -106.01212) (xy 12.876517 -105.894147)
			(xy 12.803583 -105.771851) (xy 12.737685 -105.645625) (xy 12.679034 -105.515873) (xy 12.627817 -105.383011)
			(xy 12.584199 -105.247464) (xy 12.548319 -105.109666) (xy 12.520292 -104.970059) (xy 12.500209 -104.829091)
			(xy 12.488134 -104.687211) (xy 12.484104 -104.544876) (xy 1.016 -104.544876) (xy 1.016 -107.36707)
			(xy 1.016472 -107.377312) (xy 1.024474 -107.396171) (xy 1.031494 -107.403646) (xy 1.051201 -107.423366)
			(xy 1.085261 -107.467503) (xy 1.112534 -107.516126) (xy 1.132441 -107.568201) (xy 1.144557 -107.622619)
			(xy 1.148624 -107.67822) (xy 1.144557 -107.733821) (xy 1.132441 -107.788239) (xy 1.112534 -107.840314)
			(xy 1.085261 -107.888937) (xy 1.051201 -107.933074) (xy 1.031494 -107.952794) (xy 1.024446 -107.960247)
			(xy 1.016463 -107.979122) (xy 1.016 -107.98937) (xy 1.016 -112.44707) (xy 1.016472 -112.457312) (xy 1.024474 -112.476171)
			(xy 1.031494 -112.483646) (xy 1.051201 -112.503366) (xy 1.085261 -112.547503) (xy 1.112534 -112.596126)
			(xy 1.132441 -112.648201) (xy 1.144557 -112.702619) (xy 1.148624 -112.75822) (xy 1.144557 -112.813821)
			(xy 1.132441 -112.868239) (xy 1.112534 -112.920314) (xy 1.085261 -112.968937) (xy 1.051201 -113.013074)
			(xy 1.031494 -113.032794) (xy 1.024446 -113.040247) (xy 1.016463 -113.059122) (xy 1.016 -113.06937)
			(xy 1.016 -117.52707) (xy 1.016472 -117.537312) (xy 1.024474 -117.556171) (xy 1.031494 -117.563646)
			(xy 1.051201 -117.583366) (xy 1.085261 -117.627503) (xy 1.112534 -117.676126) (xy 1.132441 -117.728201)
			(xy 1.144557 -117.782619) (xy 1.148624 -117.83822) (xy 1.144557 -117.893821) (xy 1.132441 -117.948239)
			(xy 1.112534 -118.000314) (xy 1.085261 -118.048937) (xy 1.051201 -118.093074) (xy 1.031494 -118.112794)
			(xy 1.024446 -118.120247) (xy 1.016463 -118.139122) (xy 1.016 -118.14937) (xy 1.016 -122.60707) (xy 1.016472 -122.617312)
			(xy 1.024474 -122.636171) (xy 1.031494 -122.643646) (xy 1.051201 -122.663366) (xy 1.085261 -122.707503)
			(xy 1.112534 -122.756126) (xy 1.132441 -122.808201) (xy 1.144557 -122.862619) (xy 1.148624 -122.91822)
			(xy 1.144557 -122.973821) (xy 1.132441 -123.028239) (xy 1.112534 -123.080314) (xy 1.085261 -123.128937)
			(xy 1.051201 -123.173074) (xy 1.031494 -123.192794) (xy 1.024446 -123.200247) (xy 1.016463 -123.219122)
			(xy 1.016 -123.22937) (xy 1.016 -127.68707) (xy 1.016472 -127.697312) (xy 1.024474 -127.716171) (xy 1.031494 -127.723646)
			(xy 1.051201 -127.743366) (xy 1.085261 -127.787503) (xy 1.112534 -127.836126) (xy 1.132441 -127.888201)
			(xy 1.144557 -127.942619) (xy 1.148624 -127.99822) (xy 1.144557 -128.053821) (xy 1.132441 -128.108239)
			(xy 1.112534 -128.160314) (xy 1.085261 -128.208937) (xy 1.051201 -128.253074) (xy 1.031494 -128.272794)
			(xy 1.024446 -128.280247) (xy 1.016463 -128.299122) (xy 1.016 -128.30937) (xy 1.016 -132.76707) (xy 1.016472 -132.777312)
			(xy 1.024474 -132.796171) (xy 1.031494 -132.803646) (xy 1.051201 -132.823366) (xy 1.085261 -132.867503)
			(xy 1.112534 -132.916126) (xy 1.132441 -132.968201) (xy 1.144557 -133.022619) (xy 1.148624 -133.07822)
			(xy 1.144557 -133.133821) (xy 1.132441 -133.188239) (xy 1.112534 -133.240314) (xy 1.085261 -133.288937)
			(xy 1.051201 -133.333074) (xy 1.031494 -133.352794) (xy 1.024446 -133.360247) (xy 1.016463 -133.379122)
			(xy 1.016 -133.38937) (xy 1.016 -137.84707) (xy 1.016472 -137.857312) (xy 1.024474 -137.876171) (xy 1.031494 -137.883646)
			(xy 1.051201 -137.903366) (xy 1.085261 -137.947503) (xy 1.112534 -137.996126) (xy 1.132441 -138.048201)
			(xy 1.144557 -138.102619) (xy 1.148624 -138.15822) (xy 1.144557 -138.213821) (xy 1.132441 -138.268239)
			(xy 1.112534 -138.320314) (xy 1.085261 -138.368937) (xy 1.051201 -138.413074) (xy 1.031494 -138.432794)
			(xy 1.024446 -138.440247) (xy 1.016463 -138.459122) (xy 1.016 -138.46937) (xy 1.016 -142.92707) (xy 1.016472 -142.937312)
			(xy 1.024474 -142.956171) (xy 1.031494 -142.963646) (xy 1.051201 -142.983366) (xy 1.085261 -143.027503)
			(xy 1.112534 -143.076126) (xy 1.132441 -143.128201) (xy 1.144557 -143.182619) (xy 1.148624 -143.23822)
			(xy 1.144557 -143.293821) (xy 1.132441 -143.348239) (xy 1.112534 -143.400314) (xy 1.085261 -143.448937)
			(xy 1.051201 -143.493074) (xy 1.031494 -143.512794) (xy 1.024446 -143.520247) (xy 1.016463 -143.539122)
			(xy 1.016 -143.54937) (xy 1.016 -148.00707) (xy 1.016472 -148.017312) (xy 1.024474 -148.036171) (xy 1.031494 -148.043646)
			(xy 1.051201 -148.063366) (xy 1.085261 -148.107503) (xy 1.112534 -148.156126) (xy 1.132441 -148.208201)
			(xy 1.144557 -148.262619) (xy 1.148624 -148.31822) (xy 1.144557 -148.373821) (xy 1.132441 -148.428239)
			(xy 1.112534 -148.480314) (xy 1.085261 -148.528937) (xy 1.051201 -148.573074) (xy 1.031494 -148.592794)
			(xy 1.024446 -148.600247) (xy 1.016463 -148.619122) (xy 1.016 -148.62937) (xy 1.016 -153.08707) (xy 1.016472 -153.097312)
			(xy 1.024474 -153.116171) (xy 1.031494 -153.123646) (xy 1.049599 -153.141681) (xy 1.08131 -153.181753)
			(xy 1.107386 -153.225701) (xy 1.127359 -153.272739) (xy 1.140871 -153.322022) (xy 1.14768 -153.372669)
			(xy 1.14808 -153.39822) (xy 1.14757 -153.426437) (xy 1.139255 -153.482255) (xy 1.122812 -153.53624)
			(xy 1.098598 -153.587216) (xy 1.067142 -153.63407) (xy 1.048512 -153.655268) (xy 1.04178 -153.66353)
			(xy 1.035082 -153.683738) (xy 1.035558 -153.694384) (xy 1.044767 -153.782058) (xy 1.069972 -153.956556)
			(xy 1.102871 -154.129769) (xy 1.143399 -154.301357) (xy 1.191478 -154.470985) (xy 1.247013 -154.63832)
			(xy 1.309896 -154.803034) (xy 1.380003 -154.964806) (xy 1.457197 -155.123318) (xy 1.541328 -155.27826)
			(xy 1.632229 -155.429329) (xy 1.729725 -155.57623) (xy 1.833622 -155.718674) (xy 1.943719 -155.856383)
			(xy 2.0598 -155.989087) (xy 2.181637 -156.116526) (xy 2.308991 -156.238452) (xy 2.441615 -156.354624)
			(xy 2.579247 -156.464817) (xy 2.721619 -156.568813) (xy 2.868452 -156.666411) (xy 3.019458 -156.757417)
			(xy 3.174342 -156.841655) (xy 3.3328 -156.91896) (xy 3.494523 -156.989179) (xy 3.659194 -157.052176)
			(xy 3.74269 -157.080458) (xy 3.753078 -157.083386) (xy 3.774523 -157.081136) (xy 3.784092 -157.07614)
			(xy 3.805765 -157.064242) (xy 3.851524 -157.04552) (xy 3.899319 -157.032864) (xy 3.948347 -157.026487)
			(xy 3.973068 -157.026102) (xy 4.000564 -157.02658) (xy 4.054988 -157.034469) (xy 4.107715 -157.050089)
			(xy 4.157654 -157.073116) (xy 4.203771 -157.103072) (xy 4.24511 -157.139339) (xy 4.280814 -157.181164)
			(xy 4.295902 -157.204156) (xy 4.301964 -157.212996) (xy 4.319724 -157.224965) (xy 4.330192 -157.22727)
			(xy 4.413197 -157.240969) (xy 4.580104 -157.262209) (xy 4.747759 -157.276389) (xy 4.915863 -157.283483)
			(xy 4.99999 -157.283912)
		)
		(stroke
			(width 0)
			(type solid)
		)
		(fill yes)
		(layer "In5.Cu")
		(net "GND")
	)
	(gr_poly
		(pts
			(xy 423.536364 -157.283912) (xy 423.546429 -157.283478) (xy 423.565018 -157.275748) (xy 423.572432 -157.268926)
			(xy 423.592063 -157.249784) (xy 423.635828 -157.216758) (xy 423.683871 -157.190337) (xy 423.735202 -157.171066)
			(xy 423.788763 -157.159343) (xy 423.84345 -157.155408) (xy 423.898137 -157.159343) (xy 423.951698 -157.171066)
			(xy 424.003029 -157.190337) (xy 424.051072 -157.216758) (xy 424.094837 -157.249784) (xy 424.114468 -157.268926)
			(xy 424.121867 -157.27577) (xy 424.140466 -157.283491) (xy 424.150536 -157.283912) (xy 428.612046 -157.283912)
			(xy 428.622471 -157.283411) (xy 428.641618 -157.275155) (xy 428.64913 -157.26791) (xy 428.66892 -157.247516)
			(xy 428.713464 -157.21223) (xy 428.762748 -157.183941) (xy 428.815684 -157.163275) (xy 428.871099 -157.15069)
			(xy 428.927768 -157.146464) (xy 428.984437 -157.15069) (xy 429.039852 -157.163275) (xy 429.092788 -157.183941)
			(xy 429.142072 -157.21223) (xy 429.186616 -157.247516) (xy 429.206406 -157.26791) (xy 429.213905 -157.275178)
			(xy 429.233058 -157.283446) (xy 429.24349 -157.283912) (xy 433.692046 -157.283912) (xy 433.702471 -157.283411)
			(xy 433.721618 -157.275155) (xy 433.72913 -157.26791) (xy 433.74892 -157.247516) (xy 433.793464 -157.21223)
			(xy 433.842748 -157.183941) (xy 433.895684 -157.163275) (xy 433.951099 -157.15069) (xy 434.007768 -157.146464)
			(xy 434.064437 -157.15069) (xy 434.119852 -157.163275) (xy 434.172788 -157.183941) (xy 434.222072 -157.21223)
			(xy 434.266616 -157.247516) (xy 434.286406 -157.26791) (xy 434.293905 -157.275178) (xy 434.313058 -157.283446)
			(xy 434.32349 -157.283912) (xy 434.999892 -157.283912) (xy 435.090344 -157.283402) (xy 435.271063 -157.27519)
			(xy 435.451222 -157.258784) (xy 435.630451 -157.234217) (xy 435.80838 -157.20154) (xy 435.984642 -157.16082)
			(xy 436.158874 -157.112141) (xy 436.330717 -157.055603) (xy 436.499816 -156.991323) (xy 436.665823 -156.919433)
			(xy 436.828396 -156.840082) (xy 436.9872 -156.753434) (xy 437.141906 -156.659666) (xy 437.292197 -156.558972)
			(xy 437.437762 -156.45156) (xy 437.578301 -156.337652) (xy 437.713525 -156.217481) (xy 437.843155 -156.091296)
			(xy 437.966923 -155.959357) (xy 438.084575 -155.821936) (xy 438.195867 -155.679315) (xy 438.300571 -155.531791)
			(xy 438.398471 -155.379665) (xy 438.489364 -155.223252) (xy 438.573064 -155.062875) (xy 438.649397 -154.898864)
			(xy 438.718207 -154.731556) (xy 438.779351 -154.561298) (xy 438.832704 -154.38844) (xy 438.878156 -154.213338)
			(xy 438.915613 -154.036353) (xy 438.944997 -153.857851) (xy 438.966248 -153.678199) (xy 438.979322 -153.497767)
			(xy 438.982358 -153.407364) (xy 438.982175 -153.396901) (xy 438.974452 -153.377475) (xy 438.967372 -153.369772)
			(xy 438.946352 -153.348138) (xy 438.910721 -153.299471) (xy 438.883189 -153.245805) (xy 438.864442 -153.188476)
			(xy 438.854945 -153.128912) (xy 438.854342 -153.098754) (xy 438.854924 -153.068413) (xy 438.864523 -153.008494)
			(xy 438.883487 -152.950851) (xy 438.911338 -152.896937) (xy 438.947374 -152.848112) (xy 438.968642 -152.826466)
			(xy 438.975579 -152.819036) (xy 438.983417 -152.8003) (xy 438.983882 -152.790144) (xy 438.983882 -148.327364)
			(xy 438.983434 -148.317208) (xy 438.975574 -148.298478) (xy 438.968642 -148.291042) (xy 438.949305 -148.271377)
			(xy 438.915922 -148.227477) (xy 438.889209 -148.179228) (xy 438.869721 -148.127636) (xy 438.857866 -148.073775)
			(xy 438.85389 -148.018768) (xy 438.857875 -147.963761) (xy 438.86974 -147.909902) (xy 438.889236 -147.858313)
			(xy 438.915958 -147.810068) (xy 438.949348 -147.766174) (xy 438.968642 -147.746466) (xy 438.975579 -147.739036)
			(xy 438.983417 -147.7203) (xy 438.983882 -147.710144) (xy 438.983882 -143.247364) (xy 438.983434 -143.237208)
			(xy 438.975574 -143.218478) (xy 438.968642 -143.211042) (xy 438.949305 -143.191377) (xy 438.915922 -143.147477)
			(xy 438.889209 -143.099228) (xy 438.869721 -143.047636) (xy 438.857866 -142.993775) (xy 438.85389 -142.938768)
			(xy 438.857875 -142.883761) (xy 438.86974 -142.829902) (xy 438.889236 -142.778313) (xy 438.915958 -142.730068)
			(xy 438.949348 -142.686174) (xy 438.968642 -142.666466) (xy 438.975579 -142.659036) (xy 438.983417 -142.6403)
			(xy 438.983882 -142.630144) (xy 438.983882 -138.167364) (xy 438.983434 -138.157208) (xy 438.975574 -138.138478)
			(xy 438.968642 -138.131042) (xy 438.949305 -138.111377) (xy 438.915922 -138.067477) (xy 438.889209 -138.019228)
			(xy 438.869721 -137.967636) (xy 438.857866 -137.913775) (xy 438.85389 -137.858768) (xy 438.857875 -137.803761)
			(xy 438.86974 -137.749902) (xy 438.889236 -137.698313) (xy 438.915958 -137.650068) (xy 438.949348 -137.606174)
			(xy 438.968642 -137.586466) (xy 438.975579 -137.579036) (xy 438.983417 -137.5603) (xy 438.983882 -137.550144)
			(xy 438.983882 -136.77011) (xy 438.984389 -136.660226) (xy 438.992425 -136.440606) (xy 439.008477 -136.221425)
			(xy 439.032522 -136.002978) (xy 439.06453 -135.785553) (xy 439.104456 -135.569443) (xy 439.152247 -135.354935)
			(xy 439.207841 -135.142316) (xy 439.271163 -134.931868) (xy 439.342128 -134.723874) (xy 439.420641 -134.51861)
			(xy 439.506599 -134.31635) (xy 439.599885 -134.117364) (xy 439.700376 -133.921918) (xy 439.807938 -133.730272)
			(xy 439.922427 -133.542682) (xy 440.043691 -133.359399) (xy 440.171567 -133.180666) (xy 440.305885 -133.006723)
			(xy 440.446466 -132.8378) (xy 440.593123 -132.674125) (xy 440.745658 -132.515915) (xy 440.90387 -132.36338)
			(xy 441.067547 -132.216726) (xy 441.236471 -132.076147) (xy 441.410416 -131.94183) (xy 441.58915 -131.813956)
			(xy 441.772435 -131.692694) (xy 441.960026 -131.578207) (xy 442.151673 -131.470647) (xy 442.34712 -131.370158)
			(xy 442.546107 -131.276873) (xy 442.748367 -131.190918) (xy 442.953632 -131.112407) (xy 443.161627 -131.041444)
			(xy 443.372075 -130.978124) (xy 443.584696 -130.922533) (xy 443.799204 -130.874743) (xy 444.015315 -130.834819)
			(xy 444.232739 -130.802814) (xy 444.451187 -130.778771) (xy 444.670368 -130.762722) (xy 444.889988 -130.754688)
			(xy 444.999872 -130.75412) (xy 445.570356 -130.75412) (xy 445.58078 -130.753617) (xy 445.599925 -130.745359)
			(xy 445.60744 -130.738118) (xy 445.627214 -130.717848) (xy 445.671681 -130.682789) (xy 445.720842 -130.654689)
			(xy 445.773617 -130.634164) (xy 445.828846 -130.621666) (xy 445.885316 -130.617469) (xy 445.941786 -130.621666)
			(xy 445.997015 -130.634164) (xy 446.04979 -130.654689) (xy 446.098951 -130.682789) (xy 446.143418 -130.717848)
			(xy 446.163192 -130.738118) (xy 446.170691 -130.745387) (xy 446.189843 -130.753659) (xy 446.200276 -130.75412)
			(xy 450.650356 -130.75412) (xy 450.66078 -130.753617) (xy 450.679925 -130.745359) (xy 450.68744 -130.738118)
			(xy 450.707214 -130.717848) (xy 450.751681 -130.682789) (xy 450.800842 -130.654689) (xy 450.853617 -130.634164)
			(xy 450.908846 -130.621666) (xy 450.965316 -130.617469) (xy 451.021786 -130.621666) (xy 451.077015 -130.634164)
			(xy 451.12979 -130.654689) (xy 451.178951 -130.682789) (xy 451.223418 -130.717848) (xy 451.243192 -130.738118)
			(xy 451.250691 -130.745387) (xy 451.269843 -130.753659) (xy 451.280276 -130.75412) (xy 460.810356 -130.75412)
			(xy 460.82078 -130.753617) (xy 460.839925 -130.745359) (xy 460.84744 -130.738118) (xy 460.867214 -130.717848)
			(xy 460.911681 -130.682789) (xy 460.960842 -130.654689) (xy 461.013617 -130.634164) (xy 461.068846 -130.621666)
			(xy 461.125316 -130.617469) (xy 461.181786 -130.621666) (xy 461.237015 -130.634164) (xy 461.28979 -130.654689)
			(xy 461.338951 -130.682789) (xy 461.383418 -130.717848) (xy 461.403192 -130.738118) (xy 461.410691 -130.745387)
			(xy 461.429843 -130.753659) (xy 461.440276 -130.75412) (xy 465.890356 -130.75412) (xy 465.90078 -130.753617)
			(xy 465.919925 -130.745359) (xy 465.92744 -130.738118) (xy 465.947214 -130.717848) (xy 465.991681 -130.682789)
			(xy 466.040842 -130.654689) (xy 466.093617 -130.634164) (xy 466.148846 -130.621666) (xy 466.205316 -130.617469)
			(xy 466.261786 -130.621666) (xy 466.317015 -130.634164) (xy 466.36979 -130.654689) (xy 466.418951 -130.682789)
			(xy 466.463418 -130.717848) (xy 466.483192 -130.738118) (xy 466.490691 -130.745387) (xy 466.509843 -130.753659)
			(xy 466.520276 -130.75412) (xy 470.97315 -130.75412) (xy 470.984079 -130.753603) (xy 471.00396 -130.744519)
			(xy 471.011504 -130.736594) (xy 471.029713 -130.716407) (xy 471.070865 -130.680882) (xy 471.116642 -130.651559)
			(xy 471.166118 -130.629029) (xy 471.218291 -130.613751) (xy 471.272104 -130.606033) (xy 471.299286 -130.60553)
			(xy 471.326486 -130.606038) (xy 471.380328 -130.613808) (xy 471.432524 -130.629137) (xy 471.482018 -130.651715)
			(xy 471.527809 -130.681085) (xy 471.548714 -130.698494) (xy 471.557442 -130.705241) (xy 471.578633 -130.711296)
			(xy 471.589608 -130.710178) (xy 471.677102 -130.696597) (xy 471.850897 -130.662646) (xy 472.023012 -130.621006)
			(xy 472.193108 -130.57176) (xy 472.360846 -130.515005) (xy 472.525898 -130.450852) (xy 472.687936 -130.379429)
			(xy 472.84664 -130.300877) (xy 473.001697 -130.21535) (xy 473.152801 -130.123019) (xy 473.299652 -130.024064)
			(xy 473.441962 -129.918682) (xy 473.579449 -129.80708) (xy 473.711841 -129.68948) (xy 473.838877 -129.566113)
			(xy 473.960306 -129.437223) (xy 474.075888 -129.303066) (xy 474.185395 -129.163905) (xy 474.28861 -129.020015)
			(xy 474.38533 -128.871682) (xy 474.475363 -128.719197) (xy 474.558531 -128.562863) (xy 474.634672 -128.402987)
			(xy 474.703633 -128.239886) (xy 474.765278 -128.073883) (xy 474.819487 -127.905303) (xy 474.866152 -127.734482)
			(xy 474.90518 -127.561756) (xy 474.936495 -127.387466) (xy 474.960035 -127.211958) (xy 474.975753 -127.035576)
			(xy 474.983618 -126.85867) (xy 474.984064 -126.77013) (xy 474.984064 -126.575058) (xy 474.983615 -126.564903)
			(xy 474.975751 -126.546176) (xy 474.968824 -126.538736) (xy 474.949477 -126.519073) (xy 474.916074 -126.475174)
			(xy 474.889341 -126.426921) (xy 474.869837 -126.375322) (xy 474.857967 -126.321452) (xy 474.85398 -126.266434)
			(xy 474.857958 -126.211415) (xy 474.869818 -126.157542) (xy 474.889313 -126.10594) (xy 474.916037 -126.057683)
			(xy 474.949432 -126.013778) (xy 474.968824 -125.99416) (xy 474.975762 -125.986731) (xy 474.9836 -125.967994)
			(xy 474.984064 -125.957838) (xy 474.984064 -121.495058) (xy 474.983615 -121.484903) (xy 474.975751 -121.466176)
			(xy 474.968824 -121.458736) (xy 474.949477 -121.439073) (xy 474.916074 -121.395174) (xy 474.889341 -121.346921)
			(xy 474.869837 -121.295322) (xy 474.857967 -121.241452) (xy 474.85398 -121.186434) (xy 474.857958 -121.131415)
			(xy 474.869818 -121.077542) (xy 474.889313 -121.02594) (xy 474.916037 -120.977683) (xy 474.949432 -120.933778)
			(xy 474.968824 -120.91416) (xy 474.975762 -120.906731) (xy 474.9836 -120.887994) (xy 474.984064 -120.877838)
			(xy 474.984064 -116.415058) (xy 474.983615 -116.404903) (xy 474.975751 -116.386176) (xy 474.968824 -116.378736)
			(xy 474.949477 -116.359073) (xy 474.916074 -116.315174) (xy 474.889341 -116.266921) (xy 474.869837 -116.215322)
			(xy 474.857967 -116.161452) (xy 474.85398 -116.106434) (xy 474.857958 -116.051415) (xy 474.869818 -115.997542)
			(xy 474.889313 -115.94594) (xy 474.916037 -115.897683) (xy 474.949432 -115.853778) (xy 474.968824 -115.83416)
			(xy 474.975762 -115.826731) (xy 474.9836 -115.807994) (xy 474.984064 -115.797838) (xy 474.984064 -111.335058)
			(xy 474.983615 -111.324903) (xy 474.975751 -111.306176) (xy 474.968824 -111.298736) (xy 474.949477 -111.279073)
			(xy 474.916074 -111.235174) (xy 474.889341 -111.186921) (xy 474.869837 -111.135322) (xy 474.857967 -111.081452)
			(xy 474.85398 -111.026434) (xy 474.857958 -110.971415) (xy 474.869818 -110.917542) (xy 474.889313 -110.86594)
			(xy 474.916037 -110.817683) (xy 474.949432 -110.773778) (xy 474.968824 -110.75416) (xy 474.975762 -110.746731)
			(xy 474.9836 -110.727994) (xy 474.984064 -110.717838) (xy 474.984064 -106.255058) (xy 474.983615 -106.244903)
			(xy 474.975751 -106.226176) (xy 474.968824 -106.218736) (xy 474.949477 -106.199073) (xy 474.916074 -106.155174)
			(xy 474.889341 -106.106921) (xy 474.869837 -106.055322) (xy 474.857967 -106.001452) (xy 474.85398 -105.946434)
			(xy 474.857958 -105.891415) (xy 474.869818 -105.837542) (xy 474.889313 -105.78594) (xy 474.916037 -105.737683)
			(xy 474.949432 -105.693778) (xy 474.968824 -105.67416) (xy 474.975762 -105.666731) (xy 474.9836 -105.647994)
			(xy 474.984064 -105.637838) (xy 474.984064 -101.175058) (xy 474.983615 -101.164903) (xy 474.975751 -101.146176)
			(xy 474.968824 -101.138736) (xy 474.949477 -101.119073) (xy 474.916074 -101.075174) (xy 474.889341 -101.026921)
			(xy 474.869837 -100.975322) (xy 474.857967 -100.921452) (xy 474.85398 -100.866434) (xy 474.857958 -100.811415)
			(xy 474.869818 -100.757542) (xy 474.889313 -100.70594) (xy 474.916037 -100.657683) (xy 474.949432 -100.613778)
			(xy 474.968824 -100.59416) (xy 474.975762 -100.586731) (xy 474.9836 -100.567994) (xy 474.984064 -100.557838)
			(xy 474.984064 -96.095058) (xy 474.983615 -96.084903) (xy 474.975751 -96.066176) (xy 474.968824 -96.058736)
			(xy 474.949477 -96.039073) (xy 474.916074 -95.995174) (xy 474.889341 -95.946921) (xy 474.869837 -95.895322)
			(xy 474.857967 -95.841452) (xy 474.85398 -95.786434) (xy 474.857958 -95.731415) (xy 474.869818 -95.677542)
			(xy 474.889313 -95.62594) (xy 474.916037 -95.577683) (xy 474.949432 -95.533778) (xy 474.968824 -95.51416)
			(xy 474.975762 -95.506731) (xy 474.9836 -95.487994) (xy 474.984064 -95.477838) (xy 474.984064 -91.015058)
			(xy 474.983615 -91.004903) (xy 474.975751 -90.986176) (xy 474.968824 -90.978736) (xy 474.949477 -90.959073)
			(xy 474.916074 -90.915174) (xy 474.889341 -90.866921) (xy 474.869837 -90.815322) (xy 474.857967 -90.761452)
			(xy 474.85398 -90.706434) (xy 474.857958 -90.651415) (xy 474.869818 -90.597542) (xy 474.889313 -90.54594)
			(xy 474.916037 -90.497683) (xy 474.949432 -90.453778) (xy 474.968824 -90.43416) (xy 474.975762 -90.426731)
			(xy 474.9836 -90.407994) (xy 474.984064 -90.397838) (xy 474.984064 -85.935058) (xy 474.983615 -85.924903)
			(xy 474.975751 -85.906176) (xy 474.968824 -85.898736) (xy 474.949477 -85.879073) (xy 474.916074 -85.835174)
			(xy 474.889341 -85.786921) (xy 474.869837 -85.735322) (xy 474.857967 -85.681452) (xy 474.85398 -85.626434)
			(xy 474.857958 -85.571415) (xy 474.869818 -85.517542) (xy 474.889313 -85.46594) (xy 474.916037 -85.417683)
			(xy 474.949432 -85.373778) (xy 474.968824 -85.35416) (xy 474.975762 -85.346731) (xy 474.9836 -85.327994)
			(xy 474.984064 -85.317838) (xy 474.984064 -80.855058) (xy 474.983615 -80.844903) (xy 474.975751 -80.826176)
			(xy 474.968824 -80.818736) (xy 474.949477 -80.799073) (xy 474.916074 -80.755174) (xy 474.889341 -80.706921)
			(xy 474.869837 -80.655322) (xy 474.857967 -80.601452) (xy 474.85398 -80.546434) (xy 474.857958 -80.491415)
			(xy 474.869818 -80.437542) (xy 474.889313 -80.38594) (xy 474.916037 -80.337683) (xy 474.949432 -80.293778)
			(xy 474.968824 -80.27416) (xy 474.975762 -80.266731) (xy 474.9836 -80.247994) (xy 474.984064 -80.237838)
			(xy 474.984064 -75.775058) (xy 474.983615 -75.764903) (xy 474.975751 -75.746176) (xy 474.968824 -75.738736)
			(xy 474.949477 -75.719073) (xy 474.916074 -75.675174) (xy 474.889341 -75.626921) (xy 474.869837 -75.575322)
			(xy 474.857967 -75.521452) (xy 474.85398 -75.466434) (xy 474.857958 -75.411415) (xy 474.869818 -75.357542)
			(xy 474.889313 -75.30594) (xy 474.916037 -75.257683) (xy 474.949432 -75.213778) (xy 474.968824 -75.19416)
			(xy 474.975762 -75.186731) (xy 474.9836 -75.167994) (xy 474.984064 -75.157838) (xy 474.984064 -70.695058)
			(xy 474.983615 -70.684903) (xy 474.975751 -70.666176) (xy 474.968824 -70.658736) (xy 474.949477 -70.639073)
			(xy 474.916074 -70.595174) (xy 474.889341 -70.546921) (xy 474.869837 -70.495322) (xy 474.857967 -70.441452)
			(xy 474.85398 -70.386434) (xy 474.857958 -70.331415) (xy 474.869818 -70.277542) (xy 474.889313 -70.22594)
			(xy 474.916037 -70.177683) (xy 474.949432 -70.133778) (xy 474.968824 -70.11416) (xy 474.975762 -70.106731)
			(xy 474.9836 -70.087994) (xy 474.984064 -70.077838) (xy 474.984064 -65.615058) (xy 474.983615 -65.604903)
			(xy 474.975751 -65.586176) (xy 474.968824 -65.578736) (xy 474.949477 -65.559073) (xy 474.916074 -65.515174)
			(xy 474.889341 -65.466921) (xy 474.869837 -65.415322) (xy 474.857967 -65.361452) (xy 474.85398 -65.306434)
			(xy 474.857958 -65.251415) (xy 474.869818 -65.197542) (xy 474.889313 -65.14594) (xy 474.916037 -65.097683)
			(xy 474.949432 -65.053778) (xy 474.968824 -65.03416) (xy 474.975762 -65.026731) (xy 474.9836 -65.007994)
			(xy 474.984064 -64.997838) (xy 474.984064 -60.535058) (xy 474.983615 -60.524903) (xy 474.975751 -60.506176)
			(xy 474.968824 -60.498736) (xy 474.949477 -60.479073) (xy 474.916074 -60.435174) (xy 474.889341 -60.386921)
			(xy 474.869837 -60.335322) (xy 474.857967 -60.281452) (xy 474.85398 -60.226434) (xy 474.857958 -60.171415)
			(xy 474.869818 -60.117542) (xy 474.889313 -60.06594) (xy 474.916037 -60.017683) (xy 474.949432 -59.973778)
			(xy 474.968824 -59.95416) (xy 474.975762 -59.946731) (xy 474.9836 -59.927994) (xy 474.984064 -59.917838)
			(xy 474.984064 -55.455058) (xy 474.983615 -55.444903) (xy 474.975751 -55.426176) (xy 474.968824 -55.418736)
			(xy 474.949477 -55.399073) (xy 474.916074 -55.355174) (xy 474.889341 -55.306921) (xy 474.869837 -55.255322)
			(xy 474.857967 -55.201452) (xy 474.85398 -55.146434) (xy 474.857958 -55.091415) (xy 474.869818 -55.037542)
			(xy 474.889313 -54.98594) (xy 474.916037 -54.937683) (xy 474.949432 -54.893778) (xy 474.968824 -54.87416)
			(xy 474.975762 -54.866731) (xy 474.9836 -54.847994) (xy 474.984064 -54.837838) (xy 474.984064 -50.375058)
			(xy 474.983615 -50.364903) (xy 474.975751 -50.346176) (xy 474.968824 -50.338736) (xy 474.949477 -50.319073)
			(xy 474.916074 -50.275174) (xy 474.889341 -50.226921) (xy 474.869837 -50.175322) (xy 474.857967 -50.121452)
			(xy 474.85398 -50.066434) (xy 474.857958 -50.011415) (xy 474.869818 -49.957542) (xy 474.889313 -49.90594)
			(xy 474.916037 -49.857683) (xy 474.949432 -49.813778) (xy 474.968824 -49.79416) (xy 474.975762 -49.786731)
			(xy 474.9836 -49.767994) (xy 474.984064 -49.757838) (xy 474.984064 -45.295058) (xy 474.983615 -45.284903)
			(xy 474.975751 -45.266176) (xy 474.968824 -45.258736) (xy 474.949477 -45.239073) (xy 474.916074 -45.195174)
			(xy 474.889341 -45.146921) (xy 474.869837 -45.095322) (xy 474.857967 -45.041452) (xy 474.85398 -44.986434)
			(xy 474.857958 -44.931415) (xy 474.869818 -44.877542) (xy 474.889313 -44.82594) (xy 474.916037 -44.777683)
			(xy 474.949432 -44.733778) (xy 474.968824 -44.71416) (xy 474.975762 -44.706731) (xy 474.9836 -44.687994)
			(xy 474.984064 -44.677838) (xy 474.984064 -40.215058) (xy 474.983615 -40.204903) (xy 474.975751 -40.186176)
			(xy 474.968824 -40.178736) (xy 474.949477 -40.159073) (xy 474.916074 -40.115174) (xy 474.889341 -40.066921)
			(xy 474.869837 -40.015322) (xy 474.857967 -39.961452) (xy 474.85398 -39.906434) (xy 474.857958 -39.851415)
			(xy 474.869818 -39.797542) (xy 474.889313 -39.74594) (xy 474.916037 -39.697683) (xy 474.949432 -39.653778)
			(xy 474.968824 -39.63416) (xy 474.975762 -39.626731) (xy 474.9836 -39.607994) (xy 474.984064 -39.597838)
			(xy 474.984064 -35.135058) (xy 474.983615 -35.124903) (xy 474.975751 -35.106176) (xy 474.968824 -35.098736)
			(xy 474.949477 -35.079073) (xy 474.916074 -35.035174) (xy 474.889341 -34.986921) (xy 474.869837 -34.935322)
			(xy 474.857967 -34.881452) (xy 474.85398 -34.826434) (xy 474.857958 -34.771415) (xy 474.869818 -34.717542)
			(xy 474.889313 -34.66594) (xy 474.916037 -34.617683) (xy 474.949432 -34.573778) (xy 474.968824 -34.55416)
			(xy 474.975762 -34.546731) (xy 474.9836 -34.527994) (xy 474.984064 -34.517838) (xy 474.984064 -30.055058)
			(xy 474.983615 -30.044903) (xy 474.975751 -30.026176) (xy 474.968824 -30.018736) (xy 474.949477 -29.999073)
			(xy 474.916074 -29.955174) (xy 474.889341 -29.906921) (xy 474.869837 -29.855322) (xy 474.857967 -29.801452)
			(xy 474.85398 -29.746434) (xy 474.857958 -29.691415) (xy 474.869818 -29.637542) (xy 474.889313 -29.58594)
			(xy 474.916037 -29.537683) (xy 474.949432 -29.493778) (xy 474.968824 -29.47416) (xy 474.975762 -29.466731)
			(xy 474.9836 -29.447994) (xy 474.984064 -29.437838) (xy 474.984064 -24.162258) (xy 474.983615 -24.152103)
			(xy 474.975751 -24.133376) (xy 474.968824 -24.125936) (xy 474.949522 -24.106278) (xy 474.916203 -24.062405)
			(xy 474.889541 -24.014196) (xy 474.870091 -23.962653) (xy 474.858256 -23.908849) (xy 474.854284 -23.853901)
			(xy 474.858256 -23.798954) (xy 474.87009 -23.745149) (xy 474.88954 -23.693606) (xy 474.916202 -23.645397)
			(xy 474.94952 -23.601524) (xy 474.968824 -23.581868) (xy 474.975763 -23.574439) (xy 474.983605 -23.555703)
			(xy 474.984064 -23.545546) (xy 474.984064 -21.770086) (xy 474.983564 -21.680002) (xy 474.975423 -21.500018)
			(xy 474.959154 -21.320586) (xy 474.93479 -21.142073) (xy 474.90238 -20.964844) (xy 474.861992 -20.789262)
			(xy 474.813708 -20.615684) (xy 474.757626 -20.444467) (xy 474.693861 -20.27596) (xy 474.622544 -20.110509)
			(xy 474.54382 -19.94845) (xy 474.45785 -19.790116) (xy 474.364811 -19.63583) (xy 474.264892 -19.485908)
			(xy 474.158297 -19.340656) (xy 474.045245 -19.200372) (xy 473.925967 -19.065341) (xy 473.800706 -18.935841)
			(xy 473.669719 -18.812137) (xy 473.533274 -18.69448) (xy 473.391649 -18.583111) (xy 473.245134 -18.478259)
			(xy 473.09403 -18.380138) (xy 472.938643 -18.288948) (xy 472.779294 -18.204875) (xy 472.616306 -18.128093)
			(xy 472.450014 -18.058757) (xy 472.280758 -17.997009) (xy 472.108883 -17.942976) (xy 471.934742 -17.896769)
			(xy 471.758689 -17.858481) (xy 471.581085 -17.828191) (xy 471.402294 -17.805961) (xy 471.222681 -17.791836)
			(xy 471.132662 -17.788382) (xy 471.122139 -17.788535) (xy 471.102593 -17.796277) (xy 471.094816 -17.803368)
			(xy 471.073169 -17.82448) (xy 471.024442 -17.860279) (xy 470.97068 -17.887947) (xy 470.913227 -17.90679)
			(xy 470.853522 -17.916339) (xy 470.82329 -17.916906) (xy 470.797892 -17.916487) (xy 470.747545 -17.909745)
			(xy 470.698538 -17.896381) (xy 470.651738 -17.876632) (xy 470.607973 -17.850847) (xy 470.568016 -17.819483)
			(xy 470.549986 -17.80159) (xy 470.542538 -17.794529) (xy 470.523663 -17.786518) (xy 470.51341 -17.786096)
			(xy 466.05317 -17.786096) (xy 466.042924 -17.786561) (xy 466.024054 -17.794552) (xy 466.016594 -17.80159)
			(xy 465.996905 -17.821094) (xy 465.952899 -17.854782) (xy 465.904483 -17.881749) (xy 465.852674 -17.901427)
			(xy 465.798564 -17.913402) (xy 465.74329 -17.917422) (xy 465.688016 -17.913402) (xy 465.633906 -17.901427)
			(xy 465.582097 -17.881749) (xy 465.533681 -17.854782) (xy 465.489675 -17.821094) (xy 465.469986 -17.80159)
			(xy 465.462538 -17.794529) (xy 465.443663 -17.786518) (xy 465.43341 -17.786096) (xy 460.97317 -17.786096)
			(xy 460.962924 -17.786561) (xy 460.944054 -17.794552) (xy 460.936594 -17.80159) (xy 460.916905 -17.821094)
			(xy 460.872899 -17.854782) (xy 460.824483 -17.881749) (xy 460.772674 -17.901427) (xy 460.718564 -17.913402)
			(xy 460.66329 -17.917422) (xy 460.608016 -17.913402) (xy 460.553906 -17.901427) (xy 460.502097 -17.881749)
			(xy 460.453681 -17.854782) (xy 460.409675 -17.821094) (xy 460.389986 -17.80159) (xy 460.382538 -17.794529)
			(xy 460.363663 -17.786518) (xy 460.35341 -17.786096) (xy 455.89317 -17.786096) (xy 455.882924 -17.786561)
			(xy 455.864054 -17.794552) (xy 455.856594 -17.80159) (xy 455.836905 -17.821094) (xy 455.792899 -17.854782)
			(xy 455.744483 -17.881749) (xy 455.692674 -17.901427) (xy 455.638564 -17.913402) (xy 455.58329 -17.917422)
			(xy 455.528016 -17.913402) (xy 455.473906 -17.901427) (xy 455.422097 -17.881749) (xy 455.373681 -17.854782)
			(xy 455.329675 -17.821094) (xy 455.309986 -17.80159) (xy 455.302538 -17.794529) (xy 455.283663 -17.786518)
			(xy 455.27341 -17.786096) (xy 450.81317 -17.786096) (xy 450.802924 -17.786561) (xy 450.784054 -17.794552)
			(xy 450.776594 -17.80159) (xy 450.756905 -17.821094) (xy 450.712899 -17.854782) (xy 450.664483 -17.881749)
			(xy 450.612674 -17.901427) (xy 450.558564 -17.913402) (xy 450.50329 -17.917422) (xy 450.448016 -17.913402)
			(xy 450.393906 -17.901427) (xy 450.342097 -17.881749) (xy 450.293681 -17.854782) (xy 450.249675 -17.821094)
			(xy 450.229986 -17.80159) (xy 450.222538 -17.794529) (xy 450.203663 -17.786518) (xy 450.19341 -17.786096)
			(xy 445.73317 -17.786096) (xy 445.722924 -17.786561) (xy 445.704054 -17.794552) (xy 445.696594 -17.80159)
			(xy 445.676905 -17.821094) (xy 445.632899 -17.854782) (xy 445.584483 -17.881749) (xy 445.532674 -17.901427)
			(xy 445.478564 -17.913402) (xy 445.42329 -17.917422) (xy 445.368016 -17.913402) (xy 445.313906 -17.901427)
			(xy 445.262097 -17.881749) (xy 445.213681 -17.854782) (xy 445.169675 -17.821094) (xy 445.149986 -17.80159)
			(xy 445.142538 -17.794529) (xy 445.123663 -17.786518) (xy 445.11341 -17.786096) (xy 444.999872 -17.786096)
			(xy 444.889371 -17.785588) (xy 444.668519 -17.777471) (xy 444.448114 -17.761248) (xy 444.228454 -17.736942)
			(xy 444.009834 -17.704585) (xy 443.792551 -17.664222) (xy 443.576896 -17.615905) (xy 443.363161 -17.559702)
			(xy 443.151634 -17.495687) (xy 442.942601 -17.423946) (xy 442.736343 -17.344578) (xy 442.53314 -17.257688)
			(xy 442.333264 -17.163394) (xy 442.136987 -17.061823) (xy 441.944572 -16.953112) (xy 441.756279 -16.837409)
			(xy 441.572363 -16.714868) (xy 441.393071 -16.585656) (xy 441.218645 -16.449946) (xy 441.049321 -16.307922)
			(xy 440.885326 -16.159775) (xy 440.726884 -16.005706) (xy 440.574206 -15.845922) (xy 440.427499 -15.680638)
			(xy 440.286962 -15.510078) (xy 440.152783 -15.334472) (xy 440.088528 -15.244572) (xy 440.082522 -15.236833)
			(xy 440.066057 -15.226253) (xy 440.056524 -15.223998) (xy 440.030665 -15.218643) (xy 439.980632 -15.20175)
			(xy 439.933409 -15.178116) (xy 439.889898 -15.148192) (xy 439.850931 -15.112551) (xy 439.817255 -15.071875)
			(xy 439.789513 -15.026941) (xy 439.768236 -14.97861) (xy 439.753831 -14.927805) (xy 439.746573 -14.875498)
			(xy 439.746136 -14.849094) (xy 439.746529 -14.824626) (xy 439.752768 -14.77609) (xy 439.758582 -14.75232)
			(xy 439.760641 -14.742719) (xy 439.758146 -14.723259) (xy 439.753756 -14.714474) (xy 439.701459 -14.62032)
			(xy 439.60282 -14.428828) (xy 439.511099 -14.233928) (xy 439.426412 -14.03587) (xy 439.348869 -13.834908)
			(xy 439.278569 -13.631299) (xy 439.215602 -13.425304) (xy 439.160049 -13.217187) (xy 439.11198 -13.007215)
			(xy 439.071458 -12.795657) (xy 439.038534 -12.582784) (xy 439.013251 -12.368869) (xy 438.995641 -12.154187)
			(xy 438.985727 -11.939011) (xy 438.984136 -11.83132) (xy 438.983571 -11.821118) (xy 438.975441 -11.802392)
			(xy 438.968388 -11.794998) (xy 438.949927 -11.776925) (xy 438.917556 -11.736662) (xy 438.890919 -11.692397)
			(xy 438.870504 -11.644939) (xy 438.856686 -11.595159) (xy 438.849717 -11.543969) (xy 438.849262 -11.518138)
			(xy 438.849687 -11.492335) (xy 438.856643 -11.441201) (xy 438.870434 -11.391473) (xy 438.890806 -11.344059)
			(xy 438.917388 -11.299827) (xy 438.949694 -11.259585) (xy 438.968134 -11.241532) (xy 438.975286 -11.234053)
			(xy 438.983399 -11.21504) (xy 438.983882 -11.204702) (xy 438.983882 -6.751574) (xy 438.983402 -6.741237)
			(xy 438.975285 -6.722223) (xy 438.968134 -6.714744) (xy 438.948055 -6.695005) (xy 438.913344 -6.650673)
			(xy 438.88553 -6.601719) (xy 438.865218 -6.549206) (xy 438.85285 -6.494277) (xy 438.848694 -6.438126)
			(xy 438.852842 -6.381975) (xy 438.865202 -6.327044) (xy 438.885507 -6.274529) (xy 438.913314 -6.22557)
			(xy 438.948019 -6.181233) (xy 438.968134 -6.161532) (xy 438.975286 -6.154053) (xy 438.983399 -6.13504)
			(xy 438.983882 -6.124702) (xy 438.983882 -4.99999) (xy 438.98338 -4.910586) (xy 438.975357 -4.731958)
			(xy 438.959329 -4.55387) (xy 438.935326 -4.37668) (xy 438.903399 -4.200745) (xy 438.86361 -4.02642)
			(xy 438.81604 -3.854056) (xy 438.760784 -3.683999) (xy 438.697955 -3.516593) (xy 438.627679 -3.352174)
			(xy 438.550097 -3.191074) (xy 438.465365 -3.033617) (xy 438.373654 -2.880119) (xy 438.275148 -2.730891)
			(xy 438.170047 -2.586232) (xy 438.058562 -2.446435) (xy 437.940917 -2.31178) (xy 437.817349 -2.182538)
			(xy 437.688107 -2.058971) (xy 437.553451 -1.941327) (xy 437.413653 -1.829842) (xy 437.268994 -1.724741)
			(xy 437.119766 -1.626237) (xy 436.966268 -1.534527) (xy 436.80881 -1.449795) (xy 436.647709 -1.372214)
			(xy 436.48329 -1.301938) (xy 436.315884 -1.23911) (xy 436.145827 -1.183855) (xy 435.973462 -1.136286)
			(xy 435.799137 -1.096498) (xy 435.623202 -1.064571) (xy 435.446013 -1.040569) (xy 435.267924 -1.024541)
			(xy 435.089296 -1.016519) (xy 434.999892 -1.016) (xy 434.25618 -1.016) (xy 434.246111 -1.016427)
			(xy 434.227512 -1.024146) (xy 434.220112 -1.030986) (xy 434.200474 -1.050168) (xy 434.156682 -1.083267)
			(xy 434.108597 -1.109748) (xy 434.057214 -1.129064) (xy 434.003592 -1.140815) (xy 433.94884 -1.144759)
			(xy 433.894088 -1.140815) (xy 433.840466 -1.129064) (xy 433.789083 -1.109748) (xy 433.740998 -1.083267)
			(xy 433.697206 -1.050168) (xy 433.677568 -1.030986) (xy 433.670172 -1.024135) (xy 433.651573 -1.016399)
			(xy 433.6415 -1.016) (xy 424.248834 -1.016) (xy 424.238769 -1.016435) (xy 424.220182 -1.024167) (xy 424.212766 -1.030986)
			(xy 423.213276 -2.030222) (xy 423.19829 -2.044954) (xy 423.19117 -2.052378) (xy 423.18305 -2.071256)
			(xy 423.182542 -2.08153) (xy 423.182542 -11.420348) (xy 423.182975 -11.430413) (xy 423.190707 -11.449001)
			(xy 423.197528 -11.456416) (xy 428.480982 -16.73987) (xy 428.488383 -16.746707) (xy 428.506982 -16.754416)
			(xy 428.51705 -16.754856) (xy 435.235604 -16.754856) (xy 435.268864 -16.755378) (xy 435.334815 -16.764065)
			(xy 435.399066 -16.781289) (xy 435.460518 -16.806757) (xy 435.518119 -16.840031) (xy 435.57088 -16.880542)
			(xy 435.59476 -16.9037) (xy 446.877694 -28.186634) (xy 446.897252 -28.194254) (xy 446.907666 -28.194)
			(xy 446.9384 -28.193492) (xy 446.979502 -28.193967) (xy 447.061357 -28.201552) (xy 447.142162 -28.216657)
			(xy 447.221229 -28.239153) (xy 447.297883 -28.268849) (xy 447.37147 -28.305491) (xy 447.441362 -28.348766)
			(xy 447.506963 -28.398306) (xy 447.567713 -28.453687) (xy 447.623094 -28.514437) (xy 447.672634 -28.580038)
			(xy 447.715909 -28.64993) (xy 447.752551 -28.723517) (xy 447.782247 -28.800171) (xy 447.804743 -28.879238)
			(xy 447.819848 -28.960043) (xy 447.827433 -29.041898) (xy 447.827908 -29.083) (xy 447.8274 -29.113734)
			(xy 447.827146 -29.124148) (xy 447.834766 -29.143706) (xy 448.15125 -29.459936) (xy 448.166998 -29.467556)
			(xy 448.175634 -29.468318) (xy 448.218514 -29.4734) (xy 448.303091 -29.490822) (xy 448.385583 -29.516358)
			(xy 448.465212 -29.549766) (xy 448.54123 -29.590731) (xy 448.612921 -29.63887) (xy 448.679611 -29.693727)
			(xy 448.740673 -29.754789) (xy 448.79553 -29.821479) (xy 448.843669 -29.89317) (xy 448.884634 -29.969188)
			(xy 448.918042 -30.048817) (xy 448.943578 -30.131309) (xy 448.961 -30.215886) (xy 448.966082 -30.258766)
			(xy 448.966844 -30.267402) (xy 448.974464 -30.28315) (xy 450.73062 -32.03956) (xy 450.74078 -32.04591)
			(xy 450.746622 -32.047688) (xy 450.786044 -32.061146) (xy 450.862416 -32.094425) (xy 450.935342 -32.134697)
			(xy 451.004184 -32.18161) (xy 451.06834 -32.234753) (xy 451.127247 -32.29366) (xy 451.18039 -32.357816)
			(xy 451.227303 -32.426658) (xy 451.267575 -32.499584) (xy 451.300854 -32.575956) (xy 451.314312 -32.615378)
			(xy 451.31609 -32.62122) (xy 451.32244 -32.63138) (xy 453.118474 -34.427414) (xy 453.125872 -34.434258)
			(xy 453.144472 -34.441979) (xy 453.154542 -34.4424) (xy 460.502 -34.4424) (xy 460.53526 -34.442921)
			(xy 460.60121 -34.451609) (xy 460.665461 -34.468834) (xy 460.726912 -34.494303) (xy 460.784511 -34.527579)
			(xy 460.837271 -34.568092) (xy 460.861156 -34.591244) (xy 467.338156 -41.068244) (xy 467.361312 -41.092124)
			(xy 467.401818 -41.144888) (xy 467.435089 -41.202489) (xy 467.460553 -41.26394) (xy 467.477775 -41.328191)
			(xy 467.486461 -41.394141) (xy 467.487 -41.4274) (xy 467.487 -55.989982) (xy 468.668617 -55.989982)
			(xy 468.672606 -55.877017) (xy 468.684554 -55.764614) (xy 468.704401 -55.653334) (xy 468.732047 -55.543732)
			(xy 468.767357 -55.436352) (xy 468.810152 -55.331731) (xy 468.860221 -55.230389) (xy 468.917314 -55.132831)
			(xy 468.981147 -55.039544) (xy 469.0514 -54.950991) (xy 469.127725 -54.867615) (xy 469.209741 -54.789831)
			(xy 469.29704 -54.718025) (xy 469.389186 -54.652556) (xy 469.485721 -54.593751) (xy 469.586164 -54.541901)
			(xy 469.690014 -54.497266) (xy 469.796753 -54.460067) (xy 469.905851 -54.43049) (xy 470.016763 -54.408682)
			(xy 470.128937 -54.394753) (xy 470.241815 -54.38877) (xy 470.354833 -54.390765) (xy 470.467429 -54.400727)
			(xy 470.579042 -54.418607) (xy 470.689115 -54.444315) (xy 470.797101 -54.477724) (xy 470.902461 -54.518667)
			(xy 471.004671 -54.566939) (xy 471.103221 -54.622302) (xy 471.197621 -54.684477) (xy 471.287399 -54.753157)
			(xy 471.372109 -54.827999) (xy 471.451329 -54.90863) (xy 471.524664 -54.994647) (xy 471.591749 -55.085624)
			(xy 471.652249 -55.181106) (xy 471.705863 -55.280618) (xy 471.752325 -55.383664) (xy 471.791402 -55.48973)
			(xy 471.822899 -55.598289) (xy 471.846661 -55.708799) (xy 471.862568 -55.82071) (xy 471.870541 -55.933464)
			(xy 471.87104 -55.989982) (xy 471.870541 -56.0465) (xy 471.862568 -56.159254) (xy 471.846661 -56.271165)
			(xy 471.822899 -56.381675) (xy 471.791402 -56.490234) (xy 471.752325 -56.5963) (xy 471.705863 -56.699346)
			(xy 471.652249 -56.798858) (xy 471.591749 -56.89434) (xy 471.524664 -56.985317) (xy 471.451329 -57.071334)
			(xy 471.372109 -57.151965) (xy 471.287399 -57.226807) (xy 471.197621 -57.295487) (xy 471.103221 -57.357662)
			(xy 471.004671 -57.413025) (xy 470.902461 -57.461297) (xy 470.797101 -57.50224) (xy 470.689115 -57.535649)
			(xy 470.579042 -57.561357) (xy 470.467429 -57.579237) (xy 470.354833 -57.589199) (xy 470.241815 -57.591194)
			(xy 470.128937 -57.585211) (xy 470.016763 -57.571282) (xy 469.905851 -57.549474) (xy 469.796753 -57.519897)
			(xy 469.690014 -57.482698) (xy 469.586164 -57.438063) (xy 469.485721 -57.386213) (xy 469.389186 -57.327408)
			(xy 469.29704 -57.261939) (xy 469.209741 -57.190133) (xy 469.127725 -57.112349) (xy 469.0514 -57.028973)
			(xy 468.981147 -56.94042) (xy 468.917314 -56.847133) (xy 468.860221 -56.749575) (xy 468.810152 -56.648233)
			(xy 468.767357 -56.543612) (xy 468.732047 -56.436232) (xy 468.704401 -56.32663) (xy 468.684554 -56.21535)
			(xy 468.672606 -56.102947) (xy 468.668617 -55.989982) (xy 467.487 -55.989982) (xy 467.487 -66.138806)
			(xy 467.487424 -66.148876) (xy 467.49514 -66.167479) (xy 467.501986 -66.174874) (xy 468.241126 -66.914014)
			(xy 468.248522 -66.920866) (xy 468.267121 -66.928604) (xy 468.277194 -66.929) (xy 472.6686 -66.929)
			(xy 472.70186 -66.929521) (xy 472.76781 -66.938209) (xy 472.832061 -66.955434) (xy 472.893512 -66.980903)
			(xy 472.951111 -67.014179) (xy 473.003871 -67.054692) (xy 473.027756 -67.077844) (xy 473.662756 -67.712844)
			(xy 473.685912 -67.736724) (xy 473.726418 -67.789488) (xy 473.759689 -67.847089) (xy 473.785153 -67.90854)
			(xy 473.802375 -67.972791) (xy 473.811061 -68.038741) (xy 473.8116 -68.072) (xy 473.8116 -76.962)
			(xy 473.811079 -76.99526) (xy 473.802391 -77.06121) (xy 473.785166 -77.125461) (xy 473.759697 -77.186912)
			(xy 473.726421 -77.244511) (xy 473.685908 -77.297271) (xy 473.662756 -77.321156) (xy 473.027756 -77.956156)
			(xy 473.003876 -77.979312) (xy 472.951112 -78.019818) (xy 472.893511 -78.053089) (xy 472.83206 -78.078553)
			(xy 472.767809 -78.095775) (xy 472.701859 -78.104461) (xy 472.6686 -78.105) (xy 419.151816 -78.105)
			(xy 419.141793 -78.105417) (xy 419.12327 -78.113084) (xy 419.109093 -78.127257) (xy 419.10142 -78.145777)
			(xy 419.101016 -78.1558) (xy 419.101016 -91.549982) (xy 470.018627 -91.549982) (xy 470.022616 -91.437017)
			(xy 470.034564 -91.324614) (xy 470.054411 -91.213334) (xy 470.082057 -91.103732) (xy 470.117367 -90.996352)
			(xy 470.160162 -90.891731) (xy 470.210231 -90.790389) (xy 470.267324 -90.692831) (xy 470.331157 -90.599544)
			(xy 470.40141 -90.510991) (xy 470.477735 -90.427615) (xy 470.559751 -90.349831) (xy 470.64705 -90.278025)
			(xy 470.739196 -90.212556) (xy 470.835731 -90.153751) (xy 470.936174 -90.101901) (xy 471.040024 -90.057266)
			(xy 471.146763 -90.020067) (xy 471.255861 -89.99049) (xy 471.366773 -89.968682) (xy 471.478947 -89.954753)
			(xy 471.591825 -89.94877) (xy 471.704843 -89.950765) (xy 471.817439 -89.960727) (xy 471.929052 -89.978607)
			(xy 472.039125 -90.004315) (xy 472.147111 -90.037724) (xy 472.252471 -90.078667) (xy 472.354681 -90.126939)
			(xy 472.453231 -90.182302) (xy 472.547631 -90.244477) (xy 472.637409 -90.313157) (xy 472.722119 -90.387999)
			(xy 472.801339 -90.46863) (xy 472.874674 -90.554647) (xy 472.941759 -90.645624) (xy 473.002259 -90.741106)
			(xy 473.055873 -90.840618) (xy 473.102335 -90.943664) (xy 473.141412 -91.04973) (xy 473.172909 -91.158289)
			(xy 473.196671 -91.268799) (xy 473.212578 -91.38071) (xy 473.220551 -91.493464) (xy 473.22105 -91.549982)
			(xy 473.220551 -91.6065) (xy 473.212578 -91.719254) (xy 473.196671 -91.831165) (xy 473.172909 -91.941675)
			(xy 473.141412 -92.050234) (xy 473.102335 -92.1563) (xy 473.055873 -92.259346) (xy 473.002259 -92.358858)
			(xy 472.941759 -92.45434) (xy 472.874674 -92.545317) (xy 472.801339 -92.631334) (xy 472.722119 -92.711965)
			(xy 472.637409 -92.786807) (xy 472.547631 -92.855487) (xy 472.453231 -92.917662) (xy 472.354681 -92.973025)
			(xy 472.252471 -93.021297) (xy 472.147111 -93.06224) (xy 472.039125 -93.095649) (xy 471.929052 -93.121357)
			(xy 471.817439 -93.139237) (xy 471.704843 -93.149199) (xy 471.591825 -93.151194) (xy 471.478947 -93.145211)
			(xy 471.366773 -93.131282) (xy 471.255861 -93.109474) (xy 471.146763 -93.079897) (xy 471.040024 -93.042698)
			(xy 470.936174 -92.998063) (xy 470.835731 -92.946213) (xy 470.739196 -92.887408) (xy 470.64705 -92.821939)
			(xy 470.559751 -92.750133) (xy 470.477735 -92.672349) (xy 470.40141 -92.588973) (xy 470.331157 -92.50042)
			(xy 470.267324 -92.407133) (xy 470.210231 -92.309575) (xy 470.160162 -92.208233) (xy 470.117367 -92.103612)
			(xy 470.082057 -91.996232) (xy 470.054411 -91.88663) (xy 470.034564 -91.77535) (xy 470.022616 -91.662947)
			(xy 470.018627 -91.549982) (xy 419.101016 -91.549982) (xy 419.101016 -104.549956) (xy 422.484046 -104.549956)
			(xy 422.488076 -104.407621) (xy 422.500151 -104.265741) (xy 422.520234 -104.124773) (xy 422.548261 -103.985166)
			(xy 422.584141 -103.847368) (xy 422.627759 -103.711821) (xy 422.678976 -103.578959) (xy 422.737627 -103.449207)
			(xy 422.803525 -103.322981) (xy 422.876459 -103.200685) (xy 422.956196 -103.082712) (xy 423.042478 -102.969439)
			(xy 423.135031 -102.861228) (xy 423.233558 -102.758427) (xy 423.337743 -102.661365) (xy 423.447252 -102.570353)
			(xy 423.561735 -102.485681) (xy 423.680825 -102.407623) (xy 423.80414 -102.336427) (xy 423.931286 -102.272321)
			(xy 424.061855 -102.215512) (xy 424.195429 -102.16618) (xy 424.33158 -102.124484) (xy 424.469871 -102.090558)
			(xy 424.609861 -102.06451) (xy 424.7511 -102.046424) (xy 424.893136 -102.036357) (xy 425.035514 -102.034342)
			(xy 425.177778 -102.040385) (xy 425.319472 -102.054467) (xy 425.460142 -102.076543) (xy 425.599339 -102.106543)
			(xy 425.736615 -102.144369) (xy 425.871531 -102.189901) (xy 426.003655 -102.242992) (xy 426.132564 -102.303474)
			(xy 426.257845 -102.371152) (xy 426.379096 -102.445809) (xy 426.495929 -102.527207) (xy 426.60797 -102.615084)
			(xy 426.71486 -102.709159) (xy 426.816257 -102.809131) (xy 426.911835 -102.914679) (xy 427.001289 -103.025465)
			(xy 427.084331 -103.141134) (xy 427.160697 -103.261317) (xy 427.230141 -103.385627) (xy 427.292441 -103.513668)
			(xy 427.347397 -103.645027) (xy 427.394834 -103.779286) (xy 427.434598 -103.916013) (xy 427.466564 -104.054771)
			(xy 427.490629 -104.195115) (xy 427.506715 -104.336596) (xy 427.51477 -104.47876) (xy 427.515274 -104.549956)
			(xy 427.51477 -104.621152) (xy 427.506715 -104.763316) (xy 427.490629 -104.904797) (xy 427.466564 -105.045141)
			(xy 427.434598 -105.183899) (xy 427.394834 -105.320626) (xy 427.347397 -105.454885) (xy 427.292441 -105.586244)
			(xy 427.230141 -105.714285) (xy 427.160697 -105.838595) (xy 427.084331 -105.958778) (xy 427.001289 -106.074447)
			(xy 426.911835 -106.185233) (xy 426.816257 -106.290781) (xy 426.71486 -106.390753) (xy 426.60797 -106.484828)
			(xy 426.495929 -106.572705) (xy 426.379096 -106.654103) (xy 426.257845 -106.72876) (xy 426.132564 -106.796438)
			(xy 426.003655 -106.85692) (xy 425.871531 -106.910011) (xy 425.736615 -106.955543) (xy 425.599339 -106.993369)
			(xy 425.460142 -107.023369) (xy 425.319472 -107.045445) (xy 425.177778 -107.059527) (xy 425.035514 -107.06557)
			(xy 424.893136 -107.063555) (xy 424.7511 -107.053488) (xy 424.609861 -107.035402) (xy 424.469871 -107.009354)
			(xy 424.33158 -106.975428) (xy 424.195429 -106.933732) (xy 424.061855 -106.8844) (xy 423.931286 -106.827591)
			(xy 423.80414 -106.763485) (xy 423.680825 -106.692289) (xy 423.561735 -106.614231) (xy 423.447252 -106.529559)
			(xy 423.337743 -106.438547) (xy 423.233558 -106.341485) (xy 423.135031 -106.238684) (xy 423.042478 -106.130473)
			(xy 422.956196 -106.0172) (xy 422.876459 -105.899227) (xy 422.803525 -105.776931) (xy 422.737627 -105.650705)
			(xy 422.678976 -105.520953) (xy 422.627759 -105.388091) (xy 422.584141 -105.252544) (xy 422.548261 -105.114746)
			(xy 422.520234 -104.975139) (xy 422.500151 -104.834171) (xy 422.488076 -104.692291) (xy 422.484046 -104.549956)
			(xy 419.101016 -104.549956) (xy 419.101016 -156.545788) (xy 419.101437 -156.555859) (xy 419.10915 -156.574465)
			(xy 419.116002 -156.581856) (xy 419.803072 -157.268926) (xy 419.810471 -157.275769) (xy 419.82907 -157.283489)
			(xy 419.83914 -157.283912)
		)
		(stroke
			(width 0)
			(type solid)
		)
		(fill yes)
		(layer "In5.Cu")
		(net "GND")
	)
	(gr_poly
		(pts
			(xy 366.350296 -170.633898) (xy 366.36087 -170.633377) (xy 366.380219 -170.624851) (xy 366.394455 -170.609216)
			(xy 366.398302 -170.599354) (xy 366.412463 -170.559233) (xy 366.44741 -170.481655) (xy 366.489605 -170.407767)
			(xy 366.538663 -170.338246) (xy 366.594134 -170.273727) (xy 366.655512 -170.214799) (xy 366.722237 -170.162001)
			(xy 366.793698 -170.115816) (xy 366.869242 -170.076664) (xy 366.94818 -170.044905) (xy 367.029789 -170.020828)
			(xy 367.113324 -170.004654) (xy 367.198023 -169.996529) (xy 367.283109 -169.996529) (xy 367.367808 -170.004654)
			(xy 367.451343 -170.020828) (xy 367.532952 -170.044905) (xy 367.61189 -170.076664) (xy 367.687434 -170.115816)
			(xy 367.758895 -170.162001) (xy 367.82562 -170.214799) (xy 367.886998 -170.273727) (xy 367.942469 -170.338246)
			(xy 367.991527 -170.407767) (xy 368.033722 -170.481655) (xy 368.068669 -170.559233) (xy 368.08283 -170.599354)
			(xy 368.086731 -170.609178) (xy 368.100982 -170.624757) (xy 368.120282 -170.633319) (xy 368.130836 -170.633898)
			(xy 371.430296 -170.633898) (xy 371.44087 -170.633377) (xy 371.460219 -170.624851) (xy 371.474455 -170.609216)
			(xy 371.478302 -170.599354) (xy 371.492463 -170.559233) (xy 371.52741 -170.481655) (xy 371.569605 -170.407767)
			(xy 371.618663 -170.338246) (xy 371.674134 -170.273727) (xy 371.735512 -170.214799) (xy 371.802237 -170.162001)
			(xy 371.873698 -170.115816) (xy 371.949242 -170.076664) (xy 372.02818 -170.044905) (xy 372.109789 -170.020828)
			(xy 372.193324 -170.004654) (xy 372.278023 -169.996529) (xy 372.363109 -169.996529) (xy 372.447808 -170.004654)
			(xy 372.531343 -170.020828) (xy 372.612952 -170.044905) (xy 372.69189 -170.076664) (xy 372.767434 -170.115816)
			(xy 372.838895 -170.162001) (xy 372.90562 -170.214799) (xy 372.966998 -170.273727) (xy 373.022469 -170.338246)
			(xy 373.071527 -170.407767) (xy 373.113722 -170.481655) (xy 373.148669 -170.559233) (xy 373.16283 -170.599354)
			(xy 373.166731 -170.609178) (xy 373.180982 -170.624757) (xy 373.200282 -170.633319) (xy 373.210836 -170.633898)
			(xy 376.510296 -170.633898) (xy 376.52087 -170.633377) (xy 376.540219 -170.624851) (xy 376.554455 -170.609216)
			(xy 376.558302 -170.599354) (xy 376.571819 -170.561041) (xy 376.6049 -170.48683) (xy 376.644608 -170.415944)
			(xy 376.690613 -170.348972) (xy 376.74253 -170.286472) (xy 376.799928 -170.228965) (xy 376.830844 -170.202606)
			(xy 376.831098 -170.202352) (xy 376.838158 -170.19585) (xy 376.847261 -170.178968) (xy 376.849583 -170.15993)
			(xy 376.847608 -170.150536) (xy 376.823986 -170.061382) (xy 376.821121 -170.052203) (xy 376.809728 -170.036729)
			(xy 376.793472 -170.026483) (xy 376.784108 -170.024298) (xy 376.783854 -170.024298) (xy 376.732833 -170.014507)
			(xy 376.632552 -169.987334) (xy 376.53496 -169.951688) (xy 376.440773 -169.907831) (xy 376.350679 -169.856084)
			(xy 376.265338 -169.796824) (xy 376.185375 -169.730487) (xy 376.111375 -169.657557) (xy 376.077226 -169.618406)
			(xy 376.069656 -169.610377) (xy 376.049639 -169.601146) (xy 376.038618 -169.600626) (xy 375.961402 -169.600626)
			(xy 375.950384 -169.601167) (xy 375.930371 -169.610388) (xy 375.922794 -169.618406) (xy 375.891484 -169.654345)
			(xy 375.824081 -169.721752) (xy 375.751597 -169.783662) (xy 375.674479 -169.839696) (xy 375.593203 -169.889506)
			(xy 375.50827 -169.932787) (xy 375.420203 -169.969271) (xy 375.329545 -169.998734) (xy 375.236855 -170.020994)
			(xy 375.142705 -170.035913) (xy 375.047675 -170.043401) (xy 375.000012 -170.043856) (xy 374.949844 -170.043339)
			(xy 374.84985 -170.035055) (xy 374.750881 -170.018544) (xy 374.653614 -169.993917) (xy 374.558712 -169.961344)
			(xy 374.466824 -169.921046) (xy 374.378576 -169.873298) (xy 374.294573 -169.818427) (xy 374.215386 -169.756808)
			(xy 374.141558 -169.688861) (xy 374.073592 -169.61505) (xy 374.011953 -169.53588) (xy 373.957061 -169.45189)
			(xy 373.909291 -169.363655) (xy 373.868969 -169.271777) (xy 373.836371 -169.176883) (xy 373.81172 -169.079622)
			(xy 373.795183 -168.980658) (xy 373.786874 -168.880666) (xy 373.7864 -168.830498) (xy 373.7864 -168.82999)
			(xy 373.786867 -168.782334) (xy 373.794343 -168.687314) (xy 373.809246 -168.593174) (xy 373.831487 -168.500493)
			(xy 373.860927 -168.40984) (xy 373.897385 -168.321776) (xy 373.940637 -168.236842) (xy 373.990416 -168.155562)
			(xy 374.046417 -168.078435) (xy 374.108293 -168.005938) (xy 374.175664 -167.938516) (xy 374.211596 -167.907208)
			(xy 374.219622 -167.899637) (xy 374.228846 -167.87962) (xy 374.229376 -167.8686) (xy 374.229376 -167.791384)
			(xy 374.228832 -167.780368) (xy 374.219606 -167.76036) (xy 374.211596 -167.752776) (xy 374.173973 -167.719952)
			(xy 374.103654 -167.649058) (xy 374.039397 -167.572628) (xy 373.981636 -167.491176) (xy 373.930762 -167.405255)
			(xy 373.887119 -167.315445) (xy 373.851001 -167.222353) (xy 373.822653 -167.126609) (xy 373.802266 -167.028859)
			(xy 373.789979 -166.929765) (xy 373.785874 -166.829996) (xy 373.78998 -166.730228) (xy 373.802267 -166.631133)
			(xy 373.822655 -166.533384) (xy 373.851003 -166.43764) (xy 373.887122 -166.344548) (xy 373.930766 -166.254738)
			(xy 373.981641 -166.168817) (xy 374.039402 -166.087366) (xy 374.10366 -166.010936) (xy 374.173979 -165.940043)
			(xy 374.211596 -165.907212) (xy 374.219622 -165.899641) (xy 374.228848 -165.879624) (xy 374.229376 -165.868604)
			(xy 374.229376 -165.791388) (xy 374.228833 -165.780372) (xy 374.219608 -165.760363) (xy 374.211596 -165.75278)
			(xy 374.175673 -165.721462) (xy 374.108299 -165.654044) (xy 374.046421 -165.58155) (xy 373.990419 -165.504425)
			(xy 373.94064 -165.423145) (xy 373.897389 -165.338212) (xy 373.860932 -165.250148) (xy 373.831496 -165.159495)
			(xy 373.80926 -165.066813) (xy 373.794363 -164.972673) (xy 373.786895 -164.877654) (xy 373.7864 -164.829998)
			(xy 373.786918 -164.77982) (xy 373.795204 -164.679806) (xy 373.81172 -164.580818) (xy 373.836353 -164.483532)
			(xy 373.868934 -164.388611) (xy 373.909241 -164.296705) (xy 373.956999 -164.208441) (xy 374.011881 -164.124421)
			(xy 374.073514 -164.045219) (xy 374.141475 -163.971377) (xy 374.215301 -163.903399) (xy 374.294488 -163.841748)
			(xy 374.378495 -163.786845) (xy 374.466748 -163.739067) (xy 374.558645 -163.698738) (xy 374.653557 -163.666134)
			(xy 374.750838 -163.641479) (xy 374.849822 -163.62494) (xy 374.949834 -163.61663) (xy 375.000012 -163.616132)
			(xy 375.047673 -163.616611) (xy 375.1427 -163.624111) (xy 375.236846 -163.639039) (xy 375.329531 -163.661303)
			(xy 375.420186 -163.690768) (xy 375.50825 -163.72725) (xy 375.593183 -163.770526) (xy 375.67446 -163.820329)
			(xy 375.751582 -163.876352) (xy 375.824072 -163.938251) (xy 375.891486 -164.005643) (xy 375.922794 -164.041582)
			(xy 375.930364 -164.049609) (xy 375.950381 -164.058835) (xy 375.961402 -164.059362) (xy 376.038618 -164.059362)
			(xy 376.049636 -164.05882) (xy 376.069654 -164.049604) (xy 376.077226 -164.041582) (xy 376.108536 -164.005643)
			(xy 376.17594 -163.938239) (xy 376.248425 -163.87633) (xy 376.325543 -163.820298) (xy 376.406819 -163.77049)
			(xy 376.491753 -163.727211) (xy 376.579819 -163.690728) (xy 376.670477 -163.661267) (xy 376.763166 -163.639009)
			(xy 376.857316 -163.624092) (xy 376.952346 -163.616606) (xy 377.000008 -163.616132) (xy 377.050174 -163.61665)
			(xy 377.150164 -163.624935) (xy 377.249129 -163.641448) (xy 377.346392 -163.666076) (xy 377.44129 -163.698652)
			(xy 377.533173 -163.738951) (xy 377.621416 -163.7867) (xy 377.705414 -163.841571) (xy 377.784595 -163.903192)
			(xy 377.858418 -163.971139) (xy 377.926378 -164.044951) (xy 377.988011 -164.124121) (xy 378.042897 -164.208111)
			(xy 378.09066 -164.296345) (xy 378.130975 -164.388222) (xy 378.163566 -164.483114) (xy 378.18821 -164.580373)
			(xy 378.20474 -164.679335) (xy 378.213041 -164.779324) (xy 378.21362 -164.82949) (xy 378.21362 -164.829998)
			(xy 378.213153 -164.877655) (xy 378.205679 -164.972674) (xy 378.190776 -165.066816) (xy 378.168537 -165.159498)
			(xy 378.139098 -165.250151) (xy 378.102641 -165.338216) (xy 378.059389 -165.423151) (xy 378.009611 -165.504433)
			(xy 377.953612 -165.581561) (xy 377.891736 -165.65406) (xy 377.824367 -165.721483) (xy 377.788424 -165.75278)
			(xy 377.780394 -165.760349) (xy 377.771161 -165.780366) (xy 377.770644 -165.791388) (xy 377.770644 -165.868604)
			(xy 377.771183 -165.879624) (xy 377.780396 -165.899645) (xy 377.788424 -165.907212) (xy 377.826049 -165.940035)
			(xy 377.896374 -166.010926) (xy 377.960636 -166.087356) (xy 378.018401 -166.168806) (xy 378.06928 -166.254728)
			(xy 378.112927 -166.344538) (xy 378.149049 -166.437631) (xy 378.1774 -166.533377) (xy 378.197788 -166.631129)
			(xy 378.210077 -166.730225) (xy 378.214183 -166.829996) (xy 378.210078 -166.929767) (xy 378.19779 -167.028863)
			(xy 378.177402 -167.126615) (xy 378.149051 -167.222361) (xy 378.112931 -167.315455) (xy 378.069284 -167.405266)
			(xy 378.018406 -167.491187) (xy 377.960641 -167.572638) (xy 377.896379 -167.649068) (xy 377.826055 -167.71996)
			(xy 377.788424 -167.752776) (xy 377.780393 -167.760345) (xy 377.771159 -167.780362) (xy 377.770644 -167.791384)
			(xy 377.770644 -167.8686) (xy 377.771183 -167.87962) (xy 377.780395 -167.899642) (xy 377.788424 -167.907208)
			(xy 377.82435 -167.938525) (xy 377.891728 -168.00594) (xy 377.953611 -168.078433) (xy 378.009617 -168.155557)
			(xy 378.059401 -168.236836) (xy 378.102656 -168.321769) (xy 378.139115 -168.409834) (xy 378.168555 -168.500487)
			(xy 378.190793 -168.593171) (xy 378.205693 -168.687313) (xy 378.213162 -168.782333) (xy 378.21362 -168.82999)
			(xy 378.21362 -168.830244) (xy 378.213101 -168.881165) (xy 378.20457 -168.982649) (xy 378.187564 -169.083061)
			(xy 378.162202 -169.181694) (xy 378.128663 -169.277855) (xy 378.087182 -169.370866) (xy 378.038052 -169.460074)
			(xy 377.981618 -169.54485) (xy 377.918277 -169.624598) (xy 377.848476 -169.698757) (xy 377.772705 -169.766804)
			(xy 377.691497 -169.828262) (xy 377.648724 -169.855896) (xy 377.640765 -169.861405) (xy 377.629374 -169.877037)
			(xy 377.624579 -169.895775) (xy 377.625356 -169.905426) (xy 377.63704 -169.996612) (xy 377.671838 -170.038522)
			(xy 377.711227 -170.051644) (xy 377.787594 -170.084229) (xy 377.860594 -170.123786) (xy 377.929592 -170.169969)
			(xy 377.993989 -170.222379) (xy 378.053225 -170.280558) (xy 378.106785 -170.344001) (xy 378.154204 -170.412157)
			(xy 378.195068 -170.484433) (xy 378.229023 -170.5602) (xy 378.24283 -170.599354) (xy 378.246731 -170.609178)
			(xy 378.260982 -170.624757) (xy 378.280282 -170.633319) (xy 378.290836 -170.633898) (xy 381.590296 -170.633898)
			(xy 381.60087 -170.633377) (xy 381.620219 -170.624851) (xy 381.634455 -170.609216) (xy 381.638302 -170.599354)
			(xy 381.65185 -170.560908) (xy 381.685031 -170.486444) (xy 381.72489 -170.41533) (xy 381.77109 -170.348164)
			(xy 381.823245 -170.285508) (xy 381.880917 -170.22789) (xy 381.943621 -170.175793) (xy 382.01083 -170.129655)
			(xy 382.08198 -170.089862) (xy 382.156475 -170.05675) (xy 382.233688 -170.030595) (xy 382.31297 -170.011619)
			(xy 382.393657 -169.999979) (xy 382.434338 -169.997374) (xy 382.434592 -169.997374) (xy 382.444997 -169.996296)
			(xy 382.463682 -169.986941) (xy 382.477102 -169.970923) (xy 382.480566 -169.961052) (xy 382.507744 -169.869104)
			(xy 382.510253 -169.858893) (xy 382.50768 -169.838047) (xy 382.496945 -169.819995) (xy 382.488694 -169.813478)
			(xy 382.450238 -169.78511) (xy 382.37743 -169.723202) (xy 382.309716 -169.655761) (xy 382.247516 -169.583202)
			(xy 382.191215 -169.505977) (xy 382.141161 -169.424564) (xy 382.097666 -169.339466) (xy 382.060997 -169.251211)
			(xy 382.031382 -169.160345) (xy 382.009006 -169.067432) (xy 381.994006 -168.973047) (xy 381.986475 -168.877775)
			(xy 381.986028 -168.82999) (xy 381.986507 -168.782329) (xy 381.994006 -168.687302) (xy 382.008934 -168.593156)
			(xy 382.031199 -168.50047) (xy 382.060663 -168.409816) (xy 382.097145 -168.321751) (xy 382.140421 -168.236818)
			(xy 382.190224 -168.155541) (xy 382.246247 -168.078419) (xy 382.308145 -168.005928) (xy 382.375537 -167.938514)
			(xy 382.411478 -167.907208) (xy 382.419506 -167.899638) (xy 382.428734 -167.879621) (xy 382.429258 -167.8686)
			(xy 382.429258 -167.791384) (xy 382.428716 -167.780366) (xy 382.4195 -167.760348) (xy 382.411478 -167.752776)
			(xy 382.375539 -167.721466) (xy 382.308135 -167.654061) (xy 382.246226 -167.581577) (xy 382.190195 -167.504459)
			(xy 382.140386 -167.423183) (xy 382.097107 -167.338249) (xy 382.060625 -167.250183) (xy 382.031164 -167.159525)
			(xy 382.008905 -167.066836) (xy 381.993988 -166.972686) (xy 381.986502 -166.877656) (xy 381.986028 -166.829994)
			(xy 381.986507 -166.782333) (xy 381.994006 -166.687306) (xy 382.008933 -166.593159) (xy 382.031198 -166.500474)
			(xy 382.060662 -166.409819) (xy 382.097144 -166.321754) (xy 382.14042 -166.236821) (xy 382.190222 -166.155543)
			(xy 382.246245 -166.078421) (xy 382.308143 -166.00593) (xy 382.375535 -165.938516) (xy 382.411478 -165.907212)
			(xy 382.419507 -165.899642) (xy 382.428736 -165.879625) (xy 382.429258 -165.868604) (xy 382.429258 -165.791388)
			(xy 382.428717 -165.780369) (xy 382.419502 -165.76035) (xy 382.411478 -165.75278) (xy 382.375539 -165.72147)
			(xy 382.308135 -165.654066) (xy 382.246226 -165.581581) (xy 382.190194 -165.504463) (xy 382.140385 -165.423187)
			(xy 382.097106 -165.338254) (xy 382.060623 -165.250187) (xy 382.031162 -165.159529) (xy 382.008903 -165.06684)
			(xy 381.993985 -164.97269) (xy 381.986499 -164.87766) (xy 381.986028 -164.829998) (xy 381.986546 -164.779814)
			(xy 381.994835 -164.679787) (xy 382.011355 -164.580787) (xy 382.035994 -164.48349) (xy 382.068584 -164.388559)
			(xy 382.108902 -164.296644) (xy 382.156672 -164.208372) (xy 382.211569 -164.124346) (xy 382.273217 -164.045141)
			(xy 382.341194 -163.971297) (xy 382.415038 -163.903319) (xy 382.494243 -163.841671) (xy 382.578269 -163.786774)
			(xy 382.66654 -163.739004) (xy 382.758455 -163.698686) (xy 382.853386 -163.666096) (xy 382.950683 -163.641456)
			(xy 383.049683 -163.624935) (xy 383.14971 -163.616647) (xy 383.199894 -163.616132) (xy 383.247555 -163.61661)
			(xy 383.342583 -163.624109) (xy 383.43673 -163.639035) (xy 383.529416 -163.661299) (xy 383.620071 -163.690762)
			(xy 383.708137 -163.727244) (xy 383.79307 -163.770519) (xy 383.874349 -163.820322) (xy 383.951471 -163.876344)
			(xy 384.023963 -163.938242) (xy 384.091378 -164.005634) (xy 384.122676 -164.041582) (xy 384.130245 -164.049612)
			(xy 384.150262 -164.058845) (xy 384.161284 -164.059362) (xy 384.2385 -164.059362) (xy 384.24952 -164.058824)
			(xy 384.269543 -164.049612) (xy 384.277108 -164.041582) (xy 384.308418 -164.005643) (xy 384.375822 -163.938237)
			(xy 384.448306 -163.876327) (xy 384.525424 -163.820295) (xy 384.6067 -163.770485) (xy 384.691633 -163.727205)
			(xy 384.7797 -163.690721) (xy 384.870358 -163.661258) (xy 384.963047 -163.638999) (xy 385.057197 -163.62408)
			(xy 385.152228 -163.616593) (xy 385.19989 -163.616132) (xy 385.250075 -163.616636) (xy 385.350103 -163.624924)
			(xy 385.449105 -163.641443) (xy 385.546404 -163.666082) (xy 385.641337 -163.698672) (xy 385.733254 -163.73899)
			(xy 385.821527 -163.78676) (xy 385.905555 -163.841657) (xy 385.984762 -163.903306) (xy 386.058607 -163.971285)
			(xy 386.126586 -164.045129) (xy 386.188236 -164.124336) (xy 386.243134 -164.208362) (xy 386.290905 -164.296635)
			(xy 386.331224 -164.388552) (xy 386.363814 -164.483484) (xy 386.388454 -164.580783) (xy 386.404975 -164.679785)
			(xy 386.413264 -164.779813) (xy 386.413756 -164.829998) (xy 386.413277 -164.877659) (xy 386.405779 -164.972686)
			(xy 386.390852 -165.066833) (xy 386.368588 -165.159519) (xy 386.339124 -165.250174) (xy 386.302642 -165.338239)
			(xy 386.259366 -165.423172) (xy 386.209563 -165.50445) (xy 386.15354 -165.581572) (xy 386.091642 -165.654063)
			(xy 386.024249 -165.721477) (xy 385.988306 -165.75278) (xy 385.980278 -165.76035) (xy 385.971049 -165.780367)
			(xy 385.970526 -165.791388) (xy 385.970526 -165.868604) (xy 385.971068 -165.879621) (xy 385.980291 -165.899632)
			(xy 385.988306 -165.907212) (xy 386.024245 -165.938522) (xy 386.091651 -166.005926) (xy 386.153562 -166.07841)
			(xy 386.209594 -166.155528) (xy 386.259405 -166.236804) (xy 386.302685 -166.321737) (xy 386.339169 -166.409804)
			(xy 386.368631 -166.500461) (xy 386.390891 -166.593151) (xy 386.40581 -166.687301) (xy 386.413296 -166.782332)
			(xy 386.413756 -166.829994) (xy 386.413277 -166.877655) (xy 386.405779 -166.972683) (xy 386.390852 -167.066829)
			(xy 386.368589 -167.159516) (xy 386.339125 -167.250171) (xy 386.302643 -167.338236) (xy 386.259368 -167.423169)
			(xy 386.209565 -167.504447) (xy 386.153542 -167.581569) (xy 386.091644 -167.654061) (xy 386.024251 -167.721475)
			(xy 385.988306 -167.752776) (xy 385.980278 -167.760346) (xy 385.971047 -167.780363) (xy 385.970526 -167.791384)
			(xy 385.970526 -167.8686) (xy 385.971067 -167.879618) (xy 385.980289 -167.89963) (xy 385.988306 -167.907208)
			(xy 386.024245 -167.938518) (xy 386.091652 -168.005921) (xy 386.153562 -168.078406) (xy 386.209595 -168.155523)
			(xy 386.259406 -168.236799) (xy 386.302686 -168.321732) (xy 386.339171 -168.409799) (xy 386.368633 -168.500457)
			(xy 386.390893 -168.593147) (xy 386.405812 -168.687297) (xy 386.413299 -168.782328) (xy 386.413756 -168.82999)
			(xy 387.986016 -168.82999) (xy 387.986483 -168.782328) (xy 387.993969 -168.687298) (xy 388.008888 -168.593148)
			(xy 388.031147 -168.500459) (xy 388.060609 -168.409801) (xy 388.097093 -168.321734) (xy 388.140372 -168.236801)
			(xy 388.190181 -168.155525) (xy 388.246213 -168.078407) (xy 388.308123 -168.005923) (xy 388.375527 -167.938518)
			(xy 388.411466 -167.907208) (xy 388.419494 -167.899641) (xy 388.428707 -167.87962) (xy 388.429246 -167.8686)
			(xy 388.429246 -167.791384) (xy 388.428734 -167.780361) (xy 388.419498 -167.760344) (xy 388.411466 -167.752776)
			(xy 388.375515 -167.721482) (xy 388.308123 -167.654066) (xy 388.246226 -167.581574) (xy 388.190204 -167.504451)
			(xy 388.140402 -167.423172) (xy 388.097127 -167.338238) (xy 388.060646 -167.250172) (xy 388.031183 -167.159517)
			(xy 388.008919 -167.06683) (xy 387.993992 -166.972683) (xy 387.986494 -166.877655) (xy 387.986016 -166.829994)
			(xy 387.986485 -166.782332) (xy 387.993972 -166.687302) (xy 388.008891 -166.593152) (xy 388.031149 -166.500463)
			(xy 388.060611 -166.409805) (xy 388.097094 -166.321739) (xy 388.140373 -166.236806) (xy 388.190182 -166.155529)
			(xy 388.246214 -166.078411) (xy 388.308123 -166.005927) (xy 388.375527 -165.938522) (xy 388.411466 -165.907212)
			(xy 388.419492 -165.899643) (xy 388.428706 -165.879623) (xy 388.429246 -165.868604) (xy 388.429246 -165.791388)
			(xy 388.428732 -165.780366) (xy 388.419498 -165.760348) (xy 388.411466 -165.75278) (xy 388.375517 -165.721484)
			(xy 388.308125 -165.654068) (xy 388.246228 -165.581576) (xy 388.190205 -165.504453) (xy 388.140403 -165.423174)
			(xy 388.097128 -165.338241) (xy 388.060647 -165.250175) (xy 388.031184 -165.15952) (xy 388.00892 -165.066834)
			(xy 387.993993 -164.972687) (xy 387.986495 -164.877659) (xy 387.986016 -164.829998) (xy 387.98655 -164.779814)
			(xy 387.994839 -164.679789) (xy 388.011359 -164.58079) (xy 388.035998 -164.483493) (xy 388.068587 -164.388563)
			(xy 388.108904 -164.296649) (xy 388.156674 -164.208378) (xy 388.211569 -164.124353) (xy 388.273216 -164.045148)
			(xy 388.341193 -163.971304) (xy 388.415036 -163.903326) (xy 388.49424 -163.841679) (xy 388.578264 -163.786782)
			(xy 388.666534 -163.739011) (xy 388.758448 -163.698693) (xy 388.853378 -163.666102) (xy 388.950674 -163.641462)
			(xy 389.049673 -163.624941) (xy 389.149698 -163.616651) (xy 389.199882 -163.616132) (xy 389.247544 -163.616613)
			(xy 389.342574 -163.624098) (xy 389.436723 -163.639015) (xy 389.529413 -163.661272) (xy 389.62007 -163.690732)
			(xy 389.708137 -163.727214) (xy 389.79307 -163.770492) (xy 389.874346 -163.820301) (xy 389.951464 -163.876331)
			(xy 390.023949 -163.93824) (xy 390.091354 -164.005644) (xy 390.122664 -164.041582) (xy 390.13024 -164.0496)
			(xy 390.150255 -164.058818) (xy 390.161272 -164.059362) (xy 390.238488 -164.059362) (xy 390.249508 -164.05883)
			(xy 390.269525 -164.049608) (xy 390.277096 -164.041582) (xy 390.308409 -164.005648) (xy 390.375822 -163.938255)
			(xy 390.448313 -163.876357) (xy 390.525434 -163.820333) (xy 390.60671 -163.77053) (xy 390.691642 -163.727254)
			(xy 390.779706 -163.690771) (xy 390.87036 -163.661306) (xy 390.963045 -163.63904) (xy 391.057191 -163.624112)
			(xy 391.152217 -163.616612) (xy 391.199878 -163.616132) (xy 391.250063 -163.616659) (xy 391.350089 -163.624946)
			(xy 391.44909 -163.641465) (xy 391.546388 -163.666102) (xy 391.64132 -163.698691) (xy 391.733236 -163.739008)
			(xy 391.821508 -163.786777) (xy 391.905535 -163.841673) (xy 391.984741 -163.90332) (xy 392.058586 -163.971297)
			(xy 392.126565 -164.045141) (xy 392.188213 -164.124346) (xy 392.243111 -164.208371) (xy 392.290882 -164.296643)
			(xy 392.3312 -164.388558) (xy 392.363791 -164.483489) (xy 392.38843 -164.580787) (xy 392.404951 -164.679787)
			(xy 392.41324 -164.779813) (xy 392.413744 -164.829998) (xy 392.413283 -164.87766) (xy 392.405797 -164.972691)
			(xy 392.390878 -165.066841) (xy 392.368619 -165.159531) (xy 392.339157 -165.250189) (xy 392.302673 -165.338256)
			(xy 392.259393 -165.423189) (xy 392.209583 -165.504465) (xy 392.15355 -165.581583) (xy 392.09164 -165.654067)
			(xy 392.024233 -165.72147) (xy 391.988294 -165.75278) (xy 391.980281 -165.760361) (xy 391.971057 -165.780371)
			(xy 391.970514 -165.791388) (xy 391.970514 -165.868604) (xy 391.971045 -165.879624) (xy 391.980269 -165.89964)
			(xy 391.988294 -165.907212) (xy 392.024231 -165.938522) (xy 392.091624 -166.005935) (xy 392.153523 -166.078426)
			(xy 392.209546 -166.155547) (xy 392.25935 -166.236824) (xy 392.302626 -166.321756) (xy 392.339109 -166.40982)
			(xy 392.368573 -166.500475) (xy 392.390838 -166.59316) (xy 392.405766 -166.687306) (xy 392.413265 -166.782333)
			(xy 392.413744 -166.829994) (xy 392.41328 -166.877656) (xy 392.405794 -166.972687) (xy 392.390876 -167.066837)
			(xy 392.368617 -167.159527) (xy 392.339155 -167.250184) (xy 392.302672 -167.338251) (xy 392.259392 -167.423185)
			(xy 392.209582 -167.504461) (xy 392.153549 -167.581578) (xy 392.091639 -167.654063) (xy 392.024233 -167.721466)
			(xy 391.988294 -167.752776) (xy 391.980283 -167.760359) (xy 391.971058 -167.780368) (xy 391.970514 -167.791384)
			(xy 391.970514 -167.8686) (xy 391.971048 -167.879619) (xy 391.98027 -167.899636) (xy 391.988294 -167.907208)
			(xy 392.024229 -167.93852) (xy 392.091622 -168.005933) (xy 392.153521 -168.078423) (xy 392.209545 -168.155544)
			(xy 392.259348 -168.236821) (xy 392.302625 -168.321753) (xy 392.339108 -168.409817) (xy 392.368572 -168.500471)
			(xy 392.390837 -168.593157) (xy 392.405766 -168.687302) (xy 392.413265 -168.782329) (xy 392.413744 -168.82999)
			(xy 392.413252 -168.880175) (xy 392.404964 -168.980204) (xy 392.388444 -169.079206) (xy 392.363805 -169.176505)
			(xy 392.331215 -169.271438) (xy 392.290896 -169.363355) (xy 392.243125 -169.451628) (xy 392.188227 -169.535655)
			(xy 392.126578 -169.614862) (xy 392.058598 -169.688707) (xy 391.984753 -169.756686) (xy 391.905546 -169.818334)
			(xy 391.821518 -169.873231) (xy 391.733244 -169.921002) (xy 391.641327 -169.961319) (xy 391.546394 -169.993908)
			(xy 391.449094 -170.018547) (xy 391.350092 -170.035066) (xy 391.250063 -170.043352) (xy 391.199878 -170.043856)
			(xy 391.152215 -170.043408) (xy 391.057185 -170.03592) (xy 390.963034 -170.021) (xy 390.870344 -169.998739)
			(xy 390.779686 -169.969276) (xy 390.69162 -169.932791) (xy 390.606686 -169.889509) (xy 390.525411 -169.839698)
			(xy 390.448293 -169.783664) (xy 390.375809 -169.721753) (xy 390.308406 -169.654346) (xy 390.277096 -169.618406)
			(xy 390.269523 -169.610384) (xy 390.249507 -169.601165) (xy 390.238488 -169.600626) (xy 390.161272 -169.600626)
			(xy 390.15025 -169.60114) (xy 390.130233 -169.610375) (xy 390.122664 -169.618406) (xy 390.09137 -169.654357)
			(xy 390.023955 -169.721749) (xy 389.951462 -169.783647) (xy 389.874339 -169.83967) (xy 389.793061 -169.889472)
			(xy 389.708127 -169.932747) (xy 389.620061 -169.969229) (xy 389.529405 -169.998692) (xy 389.436719 -170.020955)
			(xy 389.342571 -170.035881) (xy 389.247543 -170.043378) (xy 389.199882 -170.043856) (xy 389.149697 -170.043365)
			(xy 389.04967 -170.035075) (xy 388.950669 -170.018553) (xy 388.853371 -169.993912) (xy 388.75844 -169.961321)
			(xy 388.666524 -169.921002) (xy 388.578252 -169.87323) (xy 388.494226 -169.818332) (xy 388.415021 -169.756682)
			(xy 388.341177 -169.688703) (xy 388.2732 -169.614857) (xy 388.211552 -169.535651) (xy 388.156656 -169.451624)
			(xy 388.108886 -169.363351) (xy 388.068569 -169.271434) (xy 388.03598 -169.176502) (xy 388.011341 -169.079203)
			(xy 387.994822 -168.980202) (xy 387.986534 -168.880175) (xy 387.986016 -168.82999) (xy 386.413756 -168.82999)
			(xy 386.413252 -168.880175) (xy 386.404964 -168.980203) (xy 386.388444 -169.079204) (xy 386.363806 -169.176503)
			(xy 386.331216 -169.271435) (xy 386.290898 -169.363352) (xy 386.243127 -169.451625) (xy 386.18823 -169.535652)
			(xy 386.126582 -169.614858) (xy 386.058603 -169.688703) (xy 385.984758 -169.756682) (xy 385.905552 -169.81833)
			(xy 385.821525 -169.873227) (xy 385.733252 -169.920998) (xy 385.641335 -169.961316) (xy 385.546403 -169.993906)
			(xy 385.449104 -170.018544) (xy 385.350103 -170.035064) (xy 385.250075 -170.043352) (xy 385.19989 -170.043856)
			(xy 385.152229 -170.043377) (xy 385.057202 -170.035878) (xy 384.963056 -170.02095) (xy 384.870371 -169.998685)
			(xy 384.779717 -169.96922) (xy 384.691652 -169.932738) (xy 384.60672 -169.889461) (xy 384.525443 -169.839658)
			(xy 384.448321 -169.783635) (xy 384.375831 -169.721736) (xy 384.308418 -169.654343) (xy 384.277108 -169.618406)
			(xy 384.269537 -169.61038) (xy 384.24952 -169.601156) (xy 384.2385 -169.600626) (xy 384.161284 -169.600626)
			(xy 384.150268 -169.60117) (xy 384.13026 -169.610397) (xy 384.122676 -169.618406) (xy 384.091366 -169.654345)
			(xy 384.023962 -169.72175) (xy 383.951478 -169.78366) (xy 383.87436 -169.839692) (xy 383.793084 -169.889501)
			(xy 383.70815 -169.932781) (xy 383.620084 -169.969264) (xy 383.529426 -169.998725) (xy 383.436737 -170.020984)
			(xy 383.342586 -170.035902) (xy 383.247556 -170.043388) (xy 383.199894 -170.043856) (xy 383.142998 -170.042332)
			(xy 383.14249 -170.042332) (xy 383.132013 -170.042357) (xy 383.11247 -170.049847) (xy 383.097582 -170.064557)
			(xy 383.093214 -170.074082) (xy 383.057146 -170.162728) (xy 383.053691 -170.172632) (xy 383.054234 -170.193578)
			(xy 383.063086 -170.212569) (xy 383.070608 -170.219878) (xy 383.104714 -170.250884) (xy 383.167006 -170.31883)
			(xy 383.221939 -170.392854) (xy 383.268921 -170.472161) (xy 383.30745 -170.555902) (xy 383.32283 -170.599354)
			(xy 383.326731 -170.609178) (xy 383.340982 -170.624757) (xy 383.360282 -170.633319) (xy 383.370836 -170.633898)
			(xy 386.670296 -170.633898) (xy 386.68087 -170.633377) (xy 386.700219 -170.624851) (xy 386.714455 -170.609216)
			(xy 386.718302 -170.599354) (xy 386.732463 -170.559233) (xy 386.76741 -170.481655) (xy 386.809605 -170.407767)
			(xy 386.858663 -170.338246) (xy 386.914134 -170.273727) (xy 386.975512 -170.214799) (xy 387.042237 -170.162001)
			(xy 387.113698 -170.115816) (xy 387.189242 -170.076664) (xy 387.26818 -170.044905) (xy 387.349789 -170.020828)
			(xy 387.433324 -170.004654) (xy 387.518023 -169.996529) (xy 387.603109 -169.996529) (xy 387.687808 -170.004654)
			(xy 387.771343 -170.020828) (xy 387.852952 -170.044905) (xy 387.93189 -170.076664) (xy 388.007434 -170.115816)
			(xy 388.078895 -170.162001) (xy 388.14562 -170.214799) (xy 388.206998 -170.273727) (xy 388.262469 -170.338246)
			(xy 388.311527 -170.407767) (xy 388.353722 -170.481655) (xy 388.388669 -170.559233) (xy 388.40283 -170.599354)
			(xy 388.406731 -170.609178) (xy 388.420982 -170.624757) (xy 388.440282 -170.633319) (xy 388.450836 -170.633898)
			(xy 391.750296 -170.633898) (xy 391.76087 -170.633377) (xy 391.780219 -170.624851) (xy 391.794455 -170.609216)
			(xy 391.798302 -170.599354) (xy 391.812463 -170.559233) (xy 391.84741 -170.481655) (xy 391.889605 -170.407767)
			(xy 391.938663 -170.338246) (xy 391.994134 -170.273727) (xy 392.055512 -170.214799) (xy 392.122237 -170.162001)
			(xy 392.193698 -170.115816) (xy 392.269242 -170.076664) (xy 392.34818 -170.044905) (xy 392.429789 -170.020828)
			(xy 392.513324 -170.004654) (xy 392.598023 -169.996529) (xy 392.683109 -169.996529) (xy 392.767808 -170.004654)
			(xy 392.851343 -170.020828) (xy 392.932952 -170.044905) (xy 393.01189 -170.076664) (xy 393.087434 -170.115816)
			(xy 393.158895 -170.162001) (xy 393.22562 -170.214799) (xy 393.286998 -170.273727) (xy 393.342469 -170.338246)
			(xy 393.391527 -170.407767) (xy 393.433722 -170.481655) (xy 393.468669 -170.559233) (xy 393.48283 -170.599354)
			(xy 393.486731 -170.609178) (xy 393.500982 -170.624757) (xy 393.520282 -170.633319) (xy 393.530836 -170.633898)
			(xy 396.830296 -170.633898) (xy 396.84087 -170.633377) (xy 396.860219 -170.624851) (xy 396.874455 -170.609216)
			(xy 396.878302 -170.599354) (xy 396.892463 -170.559233) (xy 396.92741 -170.481655) (xy 396.969605 -170.407767)
			(xy 397.018663 -170.338246) (xy 397.074134 -170.273727) (xy 397.135512 -170.214799) (xy 397.202237 -170.162001)
			(xy 397.273698 -170.115816) (xy 397.349242 -170.076664) (xy 397.42818 -170.044905) (xy 397.509789 -170.020828)
			(xy 397.593324 -170.004654) (xy 397.678023 -169.996529) (xy 397.763109 -169.996529) (xy 397.847808 -170.004654)
			(xy 397.931343 -170.020828) (xy 398.012952 -170.044905) (xy 398.09189 -170.076664) (xy 398.167434 -170.115816)
			(xy 398.238895 -170.162001) (xy 398.30562 -170.214799) (xy 398.366998 -170.273727) (xy 398.422469 -170.338246)
			(xy 398.471527 -170.407767) (xy 398.513722 -170.481655) (xy 398.548669 -170.559233) (xy 398.56283 -170.599354)
			(xy 398.566731 -170.609178) (xy 398.580982 -170.624757) (xy 398.600282 -170.633319) (xy 398.610836 -170.633898)
			(xy 401.910296 -170.633898) (xy 401.92087 -170.633377) (xy 401.940219 -170.624851) (xy 401.954455 -170.609216)
			(xy 401.958302 -170.599354) (xy 401.972815 -170.55828) (xy 402.008771 -170.478926) (xy 402.052316 -170.403469)
			(xy 402.103033 -170.332634) (xy 402.160436 -170.267099) (xy 402.223974 -170.207494) (xy 402.293037 -170.15439)
			(xy 402.366964 -170.108296) (xy 402.445045 -170.069654) (xy 402.485606 -170.053762) (xy 402.48586 -170.053762)
			(xy 402.494641 -170.050011) (xy 402.508764 -170.03718) (xy 402.517185 -170.020058) (xy 402.518372 -170.010582)
			(xy 402.5265 -169.91965) (xy 402.526979 -169.910149) (xy 402.521687 -169.891891) (xy 402.510089 -169.87683)
			(xy 402.502116 -169.871644) (xy 402.501862 -169.87139) (xy 402.46078 -169.846255) (xy 402.382308 -169.790405)
			(xy 402.308509 -169.728511) (xy 402.239849 -169.660962) (xy 402.176757 -169.588185) (xy 402.119633 -169.510635)
			(xy 402.068834 -169.428802) (xy 402.024682 -169.343201) (xy 401.987452 -169.254369) (xy 401.957381 -169.162866)
			(xy 401.934656 -169.069267) (xy 401.919422 -168.974162) (xy 401.911773 -168.878149) (xy 401.911312 -168.82999)
			(xy 401.911791 -168.782329) (xy 401.91929 -168.687302) (xy 401.934218 -168.593155) (xy 401.956482 -168.500469)
			(xy 401.985946 -168.409815) (xy 402.022428 -168.32175) (xy 402.065704 -168.236817) (xy 402.115506 -168.155539)
			(xy 402.171528 -168.078416) (xy 402.233426 -168.005925) (xy 402.300818 -167.93851) (xy 402.336762 -167.907208)
			(xy 402.344792 -167.899639) (xy 402.354022 -167.879622) (xy 402.354542 -167.8686) (xy 402.354542 -167.791384)
			(xy 402.353999 -167.780366) (xy 402.344782 -167.76035) (xy 402.336762 -167.752776) (xy 402.300824 -167.721466)
			(xy 402.23342 -167.654061) (xy 402.171512 -167.581576) (xy 402.115482 -167.504458) (xy 402.065673 -167.423181)
			(xy 402.022395 -167.338248) (xy 401.985913 -167.250181) (xy 401.956452 -167.159524) (xy 401.934195 -167.066835)
			(xy 401.919277 -166.972686) (xy 401.911792 -166.877656) (xy 401.911312 -166.829994) (xy 401.911791 -166.782333)
			(xy 401.91929 -166.687306) (xy 401.934217 -166.593159) (xy 401.956481 -166.500473) (xy 401.985945 -166.409818)
			(xy 402.022427 -166.321753) (xy 402.065702 -166.23682) (xy 402.115504 -166.155541) (xy 402.171527 -166.078419)
			(xy 402.233424 -166.005927) (xy 402.300816 -165.938512) (xy 402.336762 -165.907212) (xy 402.344793 -165.899643)
			(xy 402.354025 -165.879626) (xy 402.354542 -165.868604) (xy 402.354542 -165.791388) (xy 402.354 -165.78037)
			(xy 402.344784 -165.760353) (xy 402.336762 -165.75278) (xy 402.300824 -165.72147) (xy 402.23342 -165.654065)
			(xy 402.171512 -165.58158) (xy 402.115481 -165.504462) (xy 402.065672 -165.423186) (xy 402.022394 -165.338252)
			(xy 401.985911 -165.250186) (xy 401.95645 -165.159528) (xy 401.934192 -165.066839) (xy 401.919275 -164.97269)
			(xy 401.911789 -164.87766) (xy 401.911312 -164.829998) (xy 401.911791 -164.782337) (xy 401.919289 -164.687309)
			(xy 401.934217 -164.593163) (xy 401.95648 -164.500476) (xy 401.985944 -164.409821) (xy 402.022425 -164.321756)
			(xy 402.065701 -164.236822) (xy 402.115503 -164.155544) (xy 402.171525 -164.078421) (xy 402.233422 -164.005929)
			(xy 402.300814 -163.938513) (xy 402.336762 -163.907216) (xy 402.344793 -163.899648) (xy 402.354027 -163.87963)
			(xy 402.354542 -163.868608) (xy 402.354542 -163.791392) (xy 402.354001 -163.780373) (xy 402.344785 -163.760355)
			(xy 402.336762 -163.752784) (xy 402.300824 -163.721474) (xy 402.23342 -163.654069) (xy 402.171511 -163.581584)
			(xy 402.11548 -163.504466) (xy 402.065671 -163.42319) (xy 402.022392 -163.338257) (xy 401.98591 -163.25019)
			(xy 401.956449 -163.159533) (xy 401.93419 -163.066844) (xy 401.919272 -162.972694) (xy 401.911786 -162.877664)
			(xy 401.911312 -162.830002) (xy 401.911791 -162.782341) (xy 401.919289 -162.687313) (xy 401.934216 -162.593166)
			(xy 401.956479 -162.50048) (xy 401.985943 -162.409825) (xy 402.022424 -162.321759) (xy 402.065699 -162.236825)
			(xy 402.115501 -162.155546) (xy 402.171523 -162.078423) (xy 402.23342 -162.005931) (xy 402.300812 -161.938515)
			(xy 402.336762 -161.90722) (xy 402.344794 -161.899652) (xy 402.354029 -161.879634) (xy 402.354542 -161.868612)
			(xy 402.354542 -161.791396) (xy 402.354002 -161.780377) (xy 402.344787 -161.760358) (xy 402.336762 -161.752788)
			(xy 402.300824 -161.721478) (xy 402.233419 -161.654073) (xy 402.17151 -161.581588) (xy 402.115479 -161.50447)
			(xy 402.06567 -161.423194) (xy 402.022391 -161.338261) (xy 401.985908 -161.250194) (xy 401.956447 -161.159537)
			(xy 401.934188 -161.066848) (xy 401.919269 -160.972698) (xy 401.911783 -160.877668) (xy 401.911312 -160.830006)
			(xy 401.91179 -160.782345) (xy 401.919288 -160.687317) (xy 401.934215 -160.59317) (xy 401.956478 -160.500483)
			(xy 401.985942 -160.409828) (xy 402.022423 -160.321762) (xy 402.065697 -160.236828) (xy 402.115499 -160.155549)
			(xy 402.171521 -160.078426) (xy 402.233419 -160.005933) (xy 402.30081 -159.938517) (xy 402.336762 -159.907224)
			(xy 402.344795 -159.899656) (xy 402.354031 -159.879639) (xy 402.354542 -159.868616) (xy 402.354542 -159.7914)
			(xy 402.354003 -159.780381) (xy 402.344789 -159.76036) (xy 402.336762 -159.752792) (xy 402.300823 -159.721482)
			(xy 402.233419 -159.654077) (xy 402.17151 -159.581593) (xy 402.115478 -159.504474) (xy 402.065669 -159.423198)
			(xy 402.02239 -159.338265) (xy 401.985906 -159.250199) (xy 401.956445 -159.159541) (xy 401.934186 -159.066852)
			(xy 401.919267 -158.972702) (xy 401.91178 -158.877672) (xy 401.911312 -158.83001) (xy 401.91179 -158.782349)
			(xy 401.919288 -158.687321) (xy 401.934214 -158.593173) (xy 401.956477 -158.500487) (xy 401.98594 -158.409831)
			(xy 402.022421 -158.321765) (xy 402.065696 -158.236831) (xy 402.115498 -158.155552) (xy 402.171519 -158.078428)
			(xy 402.233417 -158.005935) (xy 402.300808 -157.938519) (xy 402.336762 -157.907228) (xy 402.344795 -157.89966)
			(xy 402.354034 -157.879643) (xy 402.354542 -157.86862) (xy 402.354542 -157.791404) (xy 402.354003 -157.780384)
			(xy 402.344791 -157.760362) (xy 402.336762 -157.752796) (xy 402.300823 -157.721486) (xy 402.233419 -157.654081)
			(xy 402.171509 -157.581597) (xy 402.115477 -157.504479) (xy 402.065668 -157.423203) (xy 402.022388 -157.338269)
			(xy 401.985905 -157.250203) (xy 401.956443 -157.159545) (xy 401.934183 -157.066856) (xy 401.919264 -156.972706)
			(xy 401.911777 -156.877676) (xy 401.911312 -156.830014) (xy 401.91179 -156.782352) (xy 401.919288 -156.687324)
			(xy 401.934214 -156.593177) (xy 401.956477 -156.50049) (xy 401.985939 -156.409834) (xy 402.02242 -156.321768)
			(xy 402.065694 -156.236833) (xy 402.115496 -156.155554) (xy 402.171518 -156.07843) (xy 402.233415 -156.005937)
			(xy 402.300806 -155.938521) (xy 402.336762 -155.907232) (xy 402.344796 -155.899665) (xy 402.354036 -155.879647)
			(xy 402.354542 -155.868624) (xy 402.354542 -155.791408) (xy 402.354004 -155.780388) (xy 402.344793 -155.760365)
			(xy 402.336762 -155.7528) (xy 402.300823 -155.72149) (xy 402.233418 -155.654085) (xy 402.171509 -155.581601)
			(xy 402.115476 -155.504483) (xy 402.065667 -155.423207) (xy 402.022387 -155.338274) (xy 401.985903 -155.250207)
			(xy 401.956441 -155.15955) (xy 401.934181 -155.06686) (xy 401.919262 -154.97271) (xy 401.911774 -154.87768)
			(xy 401.911312 -154.830018) (xy 401.91179 -154.782356) (xy 401.919287 -154.687328) (xy 401.934213 -154.593181)
			(xy 401.956476 -154.500493) (xy 401.985938 -154.409837) (xy 402.022419 -154.321771) (xy 402.065693 -154.236836)
			(xy 402.115494 -154.155557) (xy 402.171516 -154.078433) (xy 402.233413 -154.005939) (xy 402.300804 -153.938523)
			(xy 402.336762 -153.907236) (xy 402.344797 -153.899669) (xy 402.354038 -153.879651) (xy 402.354542 -153.868628)
			(xy 402.354542 -153.791412) (xy 402.354005 -153.780391) (xy 402.344794 -153.760367) (xy 402.336762 -153.752804)
			(xy 402.300823 -153.721494) (xy 402.233418 -153.65409) (xy 402.171508 -153.581605) (xy 402.115476 -153.504487)
			(xy 402.065666 -153.423211) (xy 402.022385 -153.338278) (xy 401.985901 -153.250211) (xy 401.956439 -153.159554)
			(xy 401.934179 -153.066865) (xy 401.919259 -152.972715) (xy 401.911771 -152.877684) (xy 401.911312 -152.830022)
			(xy 401.911829 -152.779837) (xy 401.920116 -152.679809) (xy 401.936635 -152.580807) (xy 401.961273 -152.483507)
			(xy 401.993861 -152.388574) (xy 402.034178 -152.296656) (xy 402.081948 -152.208382) (xy 402.136844 -152.124354)
			(xy 402.198491 -152.045146) (xy 402.266469 -151.9713) (xy 402.340313 -151.90332) (xy 402.419518 -151.841669)
			(xy 402.503544 -151.78677) (xy 402.591817 -151.738997) (xy 402.683733 -151.698677) (xy 402.778665 -151.666085)
			(xy 402.875964 -151.641444) (xy 402.974965 -151.624922) (xy 403.074993 -151.616631) (xy 403.125178 -151.616156)
			(xy 403.172839 -151.616634) (xy 403.267867 -151.624131) (xy 403.362015 -151.639057) (xy 403.454701 -151.66132)
			(xy 403.545357 -151.690783) (xy 403.633423 -151.727264) (xy 403.718357 -151.770539) (xy 403.799635 -151.820342)
			(xy 403.876758 -151.876365) (xy 403.94925 -151.938263) (xy 404.016665 -152.005655) (xy 404.04796 -152.041606)
			(xy 404.05553 -152.049636) (xy 404.075546 -152.05887) (xy 404.086568 -152.059386) (xy 404.163784 -152.059386)
			(xy 404.174803 -152.058848) (xy 404.194822 -152.049632) (xy 404.202392 -152.041606) (xy 404.233701 -152.005666)
			(xy 404.301104 -151.938258) (xy 404.373588 -151.876346) (xy 404.450706 -151.820311) (xy 404.531981 -151.770499)
			(xy 404.616914 -151.727217) (xy 404.704981 -151.690731) (xy 404.795639 -151.661267) (xy 404.888329 -151.639006)
			(xy 404.98248 -151.624085) (xy 405.077511 -151.616597) (xy 405.125174 -151.616156) (xy 405.175359 -151.616659)
			(xy 405.275387 -151.624946) (xy 405.37439 -151.641465) (xy 405.471689 -151.666103) (xy 405.566622 -151.698692)
			(xy 405.658539 -151.739009) (xy 405.746813 -151.78678) (xy 405.830841 -151.841677) (xy 405.910047 -151.903325)
			(xy 405.983893 -151.971304) (xy 406.051872 -152.045149) (xy 406.113521 -152.124356) (xy 406.168418 -152.208383)
			(xy 406.216189 -152.296657) (xy 406.256507 -152.388574) (xy 406.289096 -152.483507) (xy 406.313734 -152.580807)
			(xy 406.330254 -152.679809) (xy 406.33854 -152.779837) (xy 406.33904 -152.830022) (xy 406.33856 -152.877683)
			(xy 406.33106 -152.972709) (xy 406.316131 -153.066854) (xy 406.293865 -153.159539) (xy 406.2644 -153.250192)
			(xy 406.227916 -153.338256) (xy 406.184639 -153.423187) (xy 406.134835 -153.504463) (xy 406.078811 -153.581583)
			(xy 406.016912 -153.654072) (xy 405.949518 -153.721484) (xy 405.91359 -153.752804) (xy 405.905568 -153.760377)
			(xy 405.896351 -153.780393) (xy 405.89581 -153.791412) (xy 405.89581 -153.868628) (xy 405.896356 -153.879643)
			(xy 405.905584 -153.899649) (xy 405.91359 -153.907236) (xy 405.949529 -153.938546) (xy 406.016934 -154.00595)
			(xy 406.078844 -154.078434) (xy 406.134876 -154.155552) (xy 406.184685 -154.236828) (xy 406.227965 -154.321761)
			(xy 406.264447 -154.409828) (xy 406.293908 -154.500486) (xy 406.316166 -154.593175) (xy 406.331084 -154.687326)
			(xy 406.338569 -154.782356) (xy 406.33904 -154.830018) (xy 406.338561 -154.877679) (xy 406.331061 -154.972705)
			(xy 406.316132 -155.066851) (xy 406.293866 -155.159536) (xy 406.264401 -155.250189) (xy 406.227918 -155.338253)
			(xy 406.184641 -155.423184) (xy 406.134837 -155.50446) (xy 406.078813 -155.581581) (xy 406.016913 -155.65407)
			(xy 405.94952 -155.721482) (xy 405.91359 -155.7528) (xy 405.905567 -155.760372) (xy 405.896349 -155.780389)
			(xy 405.89581 -155.791408) (xy 405.89581 -155.868624) (xy 405.896356 -155.87964) (xy 405.905582 -155.899647)
			(xy 405.91359 -155.907232) (xy 405.949529 -155.938542) (xy 406.016935 -156.005945) (xy 406.078845 -156.07843)
			(xy 406.134877 -156.155548) (xy 406.184687 -156.236824) (xy 406.227966 -156.321757) (xy 406.264449 -156.409824)
			(xy 406.29391 -156.500482) (xy 406.316169 -156.593171) (xy 406.331086 -156.687321) (xy 406.338572 -156.782352)
			(xy 406.33904 -156.830014) (xy 406.338561 -156.877675) (xy 406.331061 -156.972701) (xy 406.316133 -157.066847)
			(xy 406.293867 -157.159532) (xy 406.264402 -157.250186) (xy 406.227919 -157.33825) (xy 406.184642 -157.423181)
			(xy 406.134839 -157.504458) (xy 406.078815 -157.581578) (xy 406.016915 -157.654068) (xy 405.949522 -157.72148)
			(xy 405.91359 -157.752796) (xy 405.905567 -157.760368) (xy 405.896347 -157.780385) (xy 405.89581 -157.791404)
			(xy 405.89581 -157.86862) (xy 405.896355 -157.879636) (xy 405.90558 -157.899644) (xy 405.91359 -157.907228)
			(xy 405.949529 -157.938538) (xy 406.016935 -158.005941) (xy 406.078845 -158.078425) (xy 406.134878 -158.155543)
			(xy 406.184688 -158.236819) (xy 406.227968 -158.321753) (xy 406.264451 -158.40982) (xy 406.293912 -158.500477)
			(xy 406.316171 -158.593167) (xy 406.331089 -158.687317) (xy 406.338574 -158.782348) (xy 406.33904 -158.83001)
			(xy 406.338561 -158.877671) (xy 406.331062 -158.972698) (xy 406.316133 -159.066843) (xy 406.293868 -159.159529)
			(xy 406.264404 -159.250183) (xy 406.227921 -159.338247) (xy 406.184644 -159.423179) (xy 406.13484 -159.504455)
			(xy 406.078816 -159.581576) (xy 406.016917 -159.654066) (xy 405.949524 -159.721479) (xy 405.91359 -159.752792)
			(xy 405.905566 -159.760364) (xy 405.896345 -159.780381) (xy 405.89581 -159.7914) (xy 405.89581 -159.868616)
			(xy 405.896354 -159.879632) (xy 405.905578 -159.899642) (xy 405.91359 -159.907224) (xy 405.949529 -159.938534)
			(xy 406.016935 -160.005937) (xy 406.078846 -160.078421) (xy 406.134879 -160.155539) (xy 406.184689 -160.236815)
			(xy 406.227969 -160.321748) (xy 406.264452 -160.409815) (xy 406.293914 -160.500473) (xy 406.316173 -160.593163)
			(xy 406.331091 -160.687313) (xy 406.338577 -160.782344) (xy 406.33904 -160.830006) (xy 406.338561 -160.877667)
			(xy 406.331062 -160.972694) (xy 406.316134 -161.06684) (xy 406.293869 -161.159525) (xy 406.264405 -161.250179)
			(xy 406.227922 -161.338244) (xy 406.184645 -161.423176) (xy 406.134842 -161.504453) (xy 406.078818 -161.581574)
			(xy 406.016919 -161.654064) (xy 405.949526 -161.721477) (xy 405.91359 -161.752788) (xy 405.905566 -161.76036)
			(xy 405.896343 -161.780376) (xy 405.89581 -161.791396) (xy 405.89581 -161.868612) (xy 405.896353 -161.879629)
			(xy 405.905576 -161.899639) (xy 405.91359 -161.90722) (xy 405.949529 -161.93853) (xy 406.016936 -162.005933)
			(xy 406.078846 -162.078417) (xy 406.13488 -162.155535) (xy 406.18469 -162.236811) (xy 406.22797 -162.321744)
			(xy 406.264454 -162.409811) (xy 406.293916 -162.500469) (xy 406.316175 -162.593159) (xy 406.331094 -162.687309)
			(xy 406.33858 -162.78234) (xy 406.33904 -162.830002) (xy 406.338561 -162.877663) (xy 406.331062 -162.97269)
			(xy 406.316135 -163.066836) (xy 406.29387 -163.159522) (xy 406.264406 -163.250176) (xy 406.227923 -163.338241)
			(xy 406.184647 -163.423173) (xy 406.134844 -163.50445) (xy 406.07882 -163.581571) (xy 406.016921 -163.654062)
			(xy 405.949528 -163.721475) (xy 405.91359 -163.752784) (xy 405.905565 -163.760356) (xy 405.896341 -163.780372)
			(xy 405.89581 -163.791392) (xy 405.89581 -163.868608) (xy 405.896352 -163.879625) (xy 405.905575 -163.899637)
			(xy 405.91359 -163.907216) (xy 405.94953 -163.938526) (xy 406.016936 -164.005929) (xy 406.078847 -164.078413)
			(xy 406.13488 -164.155531) (xy 406.184691 -164.236807) (xy 406.227972 -164.32174) (xy 406.264456 -164.409807)
			(xy 406.293918 -164.500465) (xy 406.316178 -164.593154) (xy 406.331097 -164.687305) (xy 406.338583 -164.782335)
			(xy 406.33904 -164.829998) (xy 406.338561 -164.877659) (xy 406.331063 -164.972686) (xy 406.316136 -165.066833)
			(xy 406.293871 -165.159518) (xy 406.264407 -165.250173) (xy 406.227925 -165.338238) (xy 406.184649 -165.42317)
			(xy 406.134845 -165.504448) (xy 406.078822 -165.581569) (xy 406.016923 -165.65406) (xy 405.94953 -165.721473)
			(xy 405.91359 -165.75278) (xy 405.905564 -165.760351) (xy 405.896338 -165.780368) (xy 405.89581 -165.791388)
			(xy 405.89581 -165.868604) (xy 405.896352 -165.879622) (xy 405.905573 -165.899635) (xy 405.91359 -165.907212)
			(xy 405.94953 -165.938521) (xy 406.016936 -166.005925) (xy 406.078848 -166.078409) (xy 406.134881 -166.155526)
			(xy 406.184692 -166.236802) (xy 406.227973 -166.321736) (xy 406.264457 -166.409802) (xy 406.29392 -166.50046)
			(xy 406.31618 -166.59315) (xy 406.331099 -166.687301) (xy 406.338586 -166.782331) (xy 406.33904 -166.829994)
			(xy 406.338561 -166.877655) (xy 406.331063 -166.972682) (xy 406.316136 -167.066829) (xy 406.293872 -167.159515)
			(xy 406.264408 -167.25017) (xy 406.227926 -167.338235) (xy 406.18465 -167.423167) (xy 406.134847 -167.504445)
			(xy 406.078824 -167.581567) (xy 406.016925 -167.654058) (xy 405.949532 -167.721471) (xy 405.91359 -167.752776)
			(xy 405.905563 -167.760347) (xy 405.896336 -167.780364) (xy 405.89581 -167.791384) (xy 405.89581 -167.8686)
			(xy 405.896351 -167.879618) (xy 405.905571 -167.899632) (xy 405.91359 -167.907208) (xy 405.952204 -167.940888)
			(xy 406.024236 -168.01377) (xy 406.089866 -168.092466) (xy 406.148626 -168.176416) (xy 406.200097 -168.265022)
			(xy 406.243913 -168.357654) (xy 406.279761 -168.45365) (xy 406.307387 -168.552327) (xy 406.326593 -168.652982)
			(xy 406.337242 -168.754899) (xy 406.338786 -168.806114) (xy 406.338786 -168.806368) (xy 406.339394 -168.8158)
			(xy 406.346684 -168.833224) (xy 406.359822 -168.846793) (xy 406.36825 -168.851072) (xy 406.449784 -168.889172)
			(xy 406.458545 -168.892789) (xy 406.47745 -168.893951) (xy 406.495494 -168.888193) (xy 406.503124 -168.882568)
			(xy 406.536984 -168.856106) (xy 406.608922 -168.809085) (xy 406.685054 -168.769211) (xy 406.764672 -168.736853)
			(xy 406.847036 -168.712313) (xy 406.93138 -168.695818) (xy 407.016921 -168.687522) (xy 407.059892 -168.686988)
			(xy 407.060146 -168.686988) (xy 407.109004 -168.687695) (xy 407.206126 -168.69847) (xy 407.301488 -168.719798)
			(xy 407.347928 -168.734994) (xy 407.364438 -168.737788) (xy 407.373164 -168.737432) (xy 407.389593 -168.731543)
			(xy 407.403057 -168.720439) (xy 407.407872 -168.71315) (xy 407.454243 -168.635581) (xy 407.540748 -168.476883)
			(xy 407.619968 -168.314425) (xy 407.69174 -168.148543) (xy 407.755916 -167.979577) (xy 407.812365 -167.807874)
			(xy 407.860969 -167.633788) (xy 407.90163 -167.457678) (xy 407.934263 -167.279905) (xy 407.958801 -167.100835)
			(xy 407.975194 -166.920836) (xy 407.983408 -166.74028) (xy 407.983944 -166.649908) (xy 407.983944 -166.104062)
			(xy 407.983414 -166.093496) (xy 407.974875 -166.074169) (xy 407.959236 -166.059961) (xy 407.9494 -166.056056)
			(xy 407.909271 -166.041904) (xy 407.831674 -166.006972) (xy 407.757768 -165.964789) (xy 407.688229 -165.91574)
			(xy 407.623692 -165.860274) (xy 407.564747 -165.798899) (xy 407.511933 -165.732174) (xy 407.465733 -165.66071)
			(xy 407.426569 -165.585161) (xy 407.3948 -165.506216) (xy 407.370715 -165.424599) (xy 407.354535 -165.341054)
			(xy 407.346408 -165.256346) (xy 407.346408 -165.171249) (xy 407.354536 -165.086541) (xy 407.370716 -165.002996)
			(xy 407.394801 -164.921379) (xy 407.426571 -164.842435) (xy 407.465735 -164.766885) (xy 407.511936 -164.695422)
			(xy 407.56475 -164.628697) (xy 407.623695 -164.567322) (xy 407.688233 -164.511857) (xy 407.757773 -164.462808)
			(xy 407.831679 -164.420626) (xy 407.909276 -164.385694) (xy 407.9494 -164.371528) (xy 407.959213 -164.36762)
			(xy 407.974766 -164.353363) (xy 407.983304 -164.334069) (xy 407.983944 -164.323522) (xy 407.983944 -163.299648)
			(xy 407.98443 -163.191212) (xy 407.992244 -162.974482) (xy 408.007865 -162.758173) (xy 408.031272 -162.542569)
			(xy 408.062434 -162.327948) (xy 408.101311 -162.114589) (xy 408.147852 -161.902771) (xy 408.201998 -161.692767)
			(xy 408.263677 -161.484851) (xy 408.332809 -161.279294) (xy 408.409305 -161.076361) (xy 408.493065 -160.876318)
			(xy 408.583981 -160.679423) (xy 408.681934 -160.485933) (xy 408.786797 -160.296098) (xy 408.898433 -160.110167)
			(xy 409.016699 -159.92838) (xy 409.078684 -159.839406) (xy 409.087828 -159.810196) (xy 409.080208 -159.783272)
			(xy 409.058868 -159.748013) (xy 409.022058 -159.674267) (xy 408.992222 -159.597434) (xy 408.969618 -159.518172)
			(xy 408.954437 -159.43716) (xy 408.94681 -159.355091) (xy 408.94635 -159.31388) (xy 408.946826 -159.272777)
			(xy 408.954412 -159.190923) (xy 408.969518 -159.110118) (xy 408.992016 -159.031051) (xy 409.021712 -158.954397)
			(xy 409.058354 -158.88081) (xy 409.10163 -158.810918) (xy 409.151169 -158.745316) (xy 409.20655 -158.684565)
			(xy 409.267299 -158.629183) (xy 409.332899 -158.579642) (xy 409.402791 -158.536365) (xy 409.476377 -158.499721)
			(xy 409.55303 -158.470023) (xy 409.632096 -158.447523) (xy 409.712901 -158.432415) (xy 409.794755 -158.424827)
			(xy 409.835858 -158.424372) (xy 409.881425 -158.424963) (xy 409.972077 -158.434313) (xy 410.061298 -158.452888)
			(xy 410.14815 -158.480494) (xy 410.231721 -158.51684) (xy 410.271722 -158.538672) (xy 410.280647 -158.543133)
			(xy 410.300433 -158.545559) (xy 410.319662 -158.540303) (xy 410.327856 -158.534608) (xy 410.43606 -158.453074)
			(xy 410.522722 -158.389943) (xy 410.699899 -158.269153) (xy 410.881268 -158.154752) (xy 411.066598 -158.046887)
			(xy 411.255654 -157.945694) (xy 411.448196 -157.851302) (xy 411.643979 -157.763832) (xy 411.842755 -157.683393)
			(xy 412.044271 -157.610089) (xy 412.248271 -157.544012) (xy 412.454496 -157.485247) (xy 412.662684 -157.433867)
			(xy 412.767526 -157.41142) (xy 412.806896 -157.371796) (xy 412.81598 -157.329112) (xy 412.841402 -157.245621)
			(xy 412.874878 -157.165023) (xy 412.916087 -157.08809) (xy 412.964632 -157.015563) (xy 413.020048 -156.948139)
			(xy 413.0818 -156.886467) (xy 413.149296 -156.83114) (xy 413.221887 -156.782689) (xy 413.298873 -156.74158)
			(xy 413.379516 -156.70821) (xy 413.463039 -156.682898) (xy 413.54864 -156.665887) (xy 413.635495 -156.657343)
			(xy 413.679132 -156.656786) (xy 413.721267 -156.657276) (xy 413.805161 -156.665241) (xy 413.887925 -156.681105)
			(xy 413.968818 -156.704727) (xy 414.047113 -156.735895) (xy 414.122109 -156.774328) (xy 414.193134 -156.819683)
			(xy 414.25955 -156.871553) (xy 414.320762 -156.929472) (xy 414.376221 -156.992922) (xy 414.42543 -157.061333)
			(xy 414.467947 -157.134092) (xy 414.503392 -157.210547) (xy 414.51784 -157.25013) (xy 414.52183 -157.25977)
			(xy 414.53607 -157.274989) (xy 414.555173 -157.283322) (xy 414.565592 -157.283912) (xy 417.346892 -157.283912)
			(xy 417.356963 -157.283491) (xy 417.375571 -157.27578) (xy 417.38296 -157.268926) (xy 418.07003 -156.581856)
			(xy 418.076877 -156.574459) (xy 418.084607 -156.55586) (xy 418.085016 -156.545788) (xy 418.085016 -78.1558)
			(xy 418.084528 -78.145791) (xy 418.076869 -78.127297) (xy 418.062717 -78.11314) (xy 418.044225 -78.105475)
			(xy 418.034216 -78.105) (xy 405.6634 -78.105) (xy 405.63014 -78.104479) (xy 405.56419 -78.095791)
			(xy 405.499939 -78.078566) (xy 405.438488 -78.053097) (xy 405.380889 -78.019821) (xy 405.328129 -77.979308)
			(xy 405.304244 -77.956156) (xy 401.748244 -74.400156) (xy 401.725088 -74.376276) (xy 401.684582 -74.323512)
			(xy 401.651311 -74.265911) (xy 401.625847 -74.20446) (xy 401.608625 -74.140209) (xy 401.599939 -74.074259)
			(xy 401.5994 -74.041) (xy 401.5994 -44.782486) (xy 401.598974 -44.772417) (xy 401.591256 -44.753816)
			(xy 401.584414 -44.746418) (xy 389.364982 -32.526986) (xy 389.357587 -32.520133) (xy 389.338988 -32.512392)
			(xy 389.328914 -32.512) (xy 370.3066 -32.512) (xy 370.27334 -32.511479) (xy 370.20739 -32.502791)
			(xy 370.143139 -32.485566) (xy 370.081688 -32.460097) (xy 370.024089 -32.426821) (xy 369.971329 -32.386308)
			(xy 369.947444 -32.363156) (xy 353.702874 -16.118586) (xy 353.695478 -16.111734) (xy 353.676879 -16.103996)
			(xy 353.666806 -16.1036) (xy 337.280758 -16.1036) (xy 337.270756 -16.104095) (xy 337.252279 -16.111762)
			(xy 337.238139 -16.125914) (xy 337.230487 -16.144398) (xy 337.229958 -16.1544) (xy 337.229958 -17.939512)
			(xy 337.229436 -17.972772) (xy 337.220748 -18.038722) (xy 337.203523 -18.102974) (xy 337.178055 -18.164425)
			(xy 337.144781 -18.222025) (xy 337.10427 -18.274787) (xy 337.081114 -18.298668) (xy 336.569304 -18.810478)
			(xy 336.545426 -18.83364) (xy 336.492666 -18.874157) (xy 336.435067 -18.907438) (xy 336.373615 -18.932912)
			(xy 336.309362 -18.950143) (xy 336.243409 -18.958836) (xy 336.210148 -18.959322) (xy 330.42733 -18.959322)
			(xy 330.417266 -18.959758) (xy 330.398682 -18.967493) (xy 330.391262 -18.974308) (xy 330.143104 -19.222466)
			(xy 330.136267 -19.229868) (xy 330.128556 -19.248466) (xy 330.128118 -19.258534) (xy 330.128118 -23.370286)
			(xy 330.128557 -23.380349) (xy 330.136296 -23.398929) (xy 330.143104 -23.406354) (xy 330.551282 -23.814532)
			(xy 330.558682 -23.821373) (xy 330.577281 -23.829088) (xy 330.58735 -23.829518) (xy 336.050128 -23.829518)
			(xy 336.083387 -23.830041) (xy 336.149335 -23.838732) (xy 336.213584 -23.855961) (xy 336.275032 -23.881433)
			(xy 336.332627 -23.914712) (xy 336.385383 -23.955227) (xy 336.409284 -23.978362) (xy 337.017106 -24.586184)
			(xy 337.040262 -24.610064) (xy 337.080768 -24.662827) (xy 337.114037 -24.720428) (xy 337.139499 -24.78188)
			(xy 337.156718 -24.846131) (xy 337.1654 -24.912081) (xy 337.16595 -24.94534) (xy 337.16595 -29.360114)
			(xy 337.165428 -29.393374) (xy 337.15674 -29.459324) (xy 337.139514 -29.523575) (xy 337.114046 -29.585026)
			(xy 337.080771 -29.642626) (xy 337.04026 -29.695387) (xy 337.017106 -29.71927) (xy 336.5373 -30.199076)
			(xy 336.513422 -30.222237) (xy 336.460662 -30.262755) (xy 336.403063 -30.296035) (xy 336.34161 -30.321509)
			(xy 336.277358 -30.33874) (xy 336.211405 -30.347432) (xy 336.178144 -30.34792) (xy 330.331064 -30.34792)
			(xy 330.320997 -30.34835) (xy 330.302404 -30.356076) (xy 330.294996 -30.362906) (xy 330.142596 -30.515306)
			(xy 330.135751 -30.522705) (xy 330.128019 -30.541303) (xy 330.12761 -30.551374) (xy 330.12761 -35.809428)
			(xy 330.128039 -35.819496) (xy 330.135761 -35.838092) (xy 330.142596 -35.845496) (xy 331.586529 -37.289429)
			(xy 337.982302 -37.289429) (xy 337.982302 -37.204707) (xy 337.990355 -37.12037) (xy 338.006389 -37.03718)
			(xy 338.030257 -36.95589) (xy 338.061745 -36.877238) (xy 338.100567 -36.801935) (xy 338.14637 -36.730663)
			(xy 338.198741 -36.664067) (xy 338.257206 -36.602752) (xy 338.321234 -36.547271) (xy 338.390246 -36.498128)
			(xy 338.463616 -36.455768) (xy 338.540681 -36.420573) (xy 338.620743 -36.392864) (xy 338.703076 -36.37289)
			(xy 338.786935 -36.360833) (xy 338.87156 -36.356802) (xy 338.956185 -36.360833) (xy 339.040044 -36.37289)
			(xy 339.122377 -36.392864) (xy 339.202439 -36.420573) (xy 339.279504 -36.455768) (xy 339.352874 -36.498128)
			(xy 339.421886 -36.547271) (xy 339.485914 -36.602752) (xy 339.544379 -36.664067) (xy 339.59675 -36.730663)
			(xy 339.642553 -36.801935) (xy 339.681375 -36.877238) (xy 339.712863 -36.95589) (xy 339.736731 -37.03718)
			(xy 339.752765 -37.12037) (xy 339.760818 -37.204707) (xy 339.761322 -37.247068) (xy 339.760818 -37.289429)
			(xy 339.752765 -37.373766) (xy 339.736731 -37.456956) (xy 339.712863 -37.538246) (xy 339.681375 -37.616898)
			(xy 339.642553 -37.692201) (xy 339.59675 -37.763473) (xy 339.544379 -37.830069) (xy 339.485914 -37.891384)
			(xy 339.421886 -37.946865) (xy 339.352874 -37.996008) (xy 339.279504 -38.038368) (xy 339.202439 -38.073563)
			(xy 339.122377 -38.101272) (xy 339.040044 -38.121246) (xy 338.956185 -38.133303) (xy 338.87156 -38.137335)
			(xy 338.786935 -38.133303) (xy 338.703076 -38.121246) (xy 338.620743 -38.101272) (xy 338.540681 -38.073563)
			(xy 338.463616 -38.038368) (xy 338.390246 -37.996008) (xy 338.321234 -37.946865) (xy 338.257206 -37.891384)
			(xy 338.198741 -37.830069) (xy 338.14637 -37.763473) (xy 338.100567 -37.692201) (xy 338.061745 -37.616898)
			(xy 338.030257 -37.538246) (xy 338.006389 -37.456956) (xy 337.990355 -37.373766) (xy 337.982302 -37.289429)
			(xy 331.586529 -37.289429) (xy 332.461362 -38.164262) (xy 332.468762 -38.171103) (xy 332.487361 -38.178821)
			(xy 332.49743 -38.179248) (xy 335.386172 -38.179248) (xy 335.395513 -38.178836) (xy 335.41296 -38.172154)
			(xy 335.426856 -38.159667) (xy 335.435357 -38.143031) (xy 335.436718 -38.133782) (xy 335.441792 -38.090601)
			(xy 335.45929 -38.005429) (xy 335.485015 -37.922372) (xy 335.518721 -37.84222) (xy 335.560088 -37.765741)
			(xy 335.608721 -37.693663) (xy 335.664154 -37.626674) (xy 335.72586 -37.565415) (xy 335.793249 -37.510469)
			(xy 335.865678 -37.462361) (xy 335.942456 -37.42155) (xy 336.02285 -37.388426) (xy 336.106092 -37.363305)
			(xy 336.191389 -37.346426) (xy 336.277925 -37.337951) (xy 336.3214 -37.337492) (xy 336.362502 -37.337967)
			(xy 336.444357 -37.345552) (xy 336.525162 -37.360657) (xy 336.604229 -37.383153) (xy 336.680883 -37.412849)
			(xy 336.75447 -37.449491) (xy 336.824362 -37.492766) (xy 336.889963 -37.542306) (xy 336.950713 -37.597687)
			(xy 337.006094 -37.658437) (xy 337.055634 -37.724038) (xy 337.098909 -37.79393) (xy 337.135551 -37.867517)
			(xy 337.165247 -37.944171) (xy 337.187743 -38.023238) (xy 337.202848 -38.104043) (xy 337.210433 -38.185898)
			(xy 337.210908 -38.227) (xy 337.210387 -38.269941) (xy 337.202102 -38.355423) (xy 337.185618 -38.439708)
			(xy 337.161089 -38.522013) (xy 337.128744 -38.601571) (xy 337.088883 -38.677642) (xy 337.041877 -38.749519)
			(xy 336.988164 -38.816531) (xy 336.928244 -38.878056) (xy 336.862674 -38.93352) (xy 336.792064 -38.982408)
			(xy 336.717073 -39.024265) (xy 336.638397 -39.058701) (xy 336.597752 -39.072566) (xy 336.5627 -39.120826)
			(xy 336.562954 -39.125144) (xy 336.564732 -39.167054) (xy 336.564732 -40.030908) (xy 336.56421 -40.064168)
			(xy 336.555522 -40.130118) (xy 336.538297 -40.194369) (xy 336.512829 -40.255821) (xy 336.479553 -40.31342)
			(xy 336.439042 -40.366181) (xy 336.415888 -40.390064) (xy 336.123591 -40.682361) (xy 343.306142 -40.682361)
			(xy 343.306142 -40.597639) (xy 343.314195 -40.513302) (xy 343.330229 -40.430112) (xy 343.354097 -40.348822)
			(xy 343.385585 -40.27017) (xy 343.424407 -40.194867) (xy 343.47021 -40.123595) (xy 343.522581 -40.056999)
			(xy 343.581046 -39.995684) (xy 343.645074 -39.940203) (xy 343.714086 -39.89106) (xy 343.787456 -39.8487)
			(xy 343.864521 -39.813505) (xy 343.944583 -39.785796) (xy 344.026916 -39.765822) (xy 344.110775 -39.753765)
			(xy 344.1954 -39.749734) (xy 344.280025 -39.753765) (xy 344.363884 -39.765822) (xy 344.446217 -39.785796)
			(xy 344.526279 -39.813505) (xy 344.603344 -39.8487) (xy 344.676714 -39.89106) (xy 344.745726 -39.940203)
			(xy 344.809754 -39.995684) (xy 344.868219 -40.056999) (xy 344.92059 -40.123595) (xy 344.966393 -40.194867)
			(xy 345.005215 -40.27017) (xy 345.036703 -40.348822) (xy 345.060571 -40.430112) (xy 345.076605 -40.513302)
			(xy 345.084658 -40.597639) (xy 345.085162 -40.64) (xy 345.084658 -40.682361) (xy 345.076605 -40.766698)
			(xy 345.060571 -40.849888) (xy 345.036703 -40.931178) (xy 345.005215 -41.00983) (xy 344.966393 -41.085133)
			(xy 344.92059 -41.156405) (xy 344.868219 -41.223001) (xy 344.809754 -41.284316) (xy 344.745726 -41.339797)
			(xy 344.676714 -41.38894) (xy 344.603344 -41.4313) (xy 344.526279 -41.466495) (xy 344.446217 -41.494204)
			(xy 344.363884 -41.514178) (xy 344.280025 -41.526235) (xy 344.1954 -41.530267) (xy 344.110775 -41.526235)
			(xy 344.026916 -41.514178) (xy 343.944583 -41.494204) (xy 343.864521 -41.466495) (xy 343.787456 -41.4313)
			(xy 343.714086 -41.38894) (xy 343.645074 -41.339797) (xy 343.581046 -41.284316) (xy 343.522581 -41.223001)
			(xy 343.47021 -41.156405) (xy 343.424407 -41.085133) (xy 343.385585 -41.00983) (xy 343.354097 -40.931178)
			(xy 343.330229 -40.849888) (xy 343.314195 -40.766698) (xy 343.306142 -40.682361) (xy 336.123591 -40.682361)
			(xy 336.018124 -40.787828) (xy 335.994244 -40.810984) (xy 335.94148 -40.851489) (xy 335.883879 -40.884757)
			(xy 335.822427 -40.910219) (xy 335.758176 -40.927438) (xy 335.692227 -40.93612) (xy 335.658968 -40.936672)
			(xy 325.1708 -40.936672) (xy 325.16079 -40.93716) (xy 325.142294 -40.944818) (xy 325.128134 -40.95897)
			(xy 325.120465 -40.977463) (xy 325.12 -40.987472) (xy 325.12 -48.465937) (xy 337.609176 -48.465937)
			(xy 337.609176 -48.381215) (xy 337.617229 -48.296878) (xy 337.633263 -48.213688) (xy 337.657131 -48.132398)
			(xy 337.688619 -48.053746) (xy 337.727441 -47.978443) (xy 337.773244 -47.907171) (xy 337.825615 -47.840575)
			(xy 337.88408 -47.77926) (xy 337.948108 -47.723779) (xy 338.01712 -47.674636) (xy 338.09049 -47.632276)
			(xy 338.167555 -47.597081) (xy 338.247617 -47.569372) (xy 338.32995 -47.549398) (xy 338.413809 -47.537341)
			(xy 338.498434 -47.53331) (xy 338.583059 -47.537341) (xy 338.666918 -47.549398) (xy 338.749251 -47.569372)
			(xy 338.829313 -47.597081) (xy 338.906378 -47.632276) (xy 338.979748 -47.674636) (xy 339.04876 -47.723779)
			(xy 339.112788 -47.77926) (xy 339.171253 -47.840575) (xy 339.223624 -47.907171) (xy 339.269427 -47.978443)
			(xy 339.308249 -48.053746) (xy 339.339737 -48.132398) (xy 339.363605 -48.213688) (xy 339.379639 -48.296878)
			(xy 339.387692 -48.381215) (xy 339.388196 -48.423576) (xy 339.387692 -48.465937) (xy 339.379639 -48.550274)
			(xy 339.363605 -48.633464) (xy 339.339737 -48.714754) (xy 339.308249 -48.793406) (xy 339.269427 -48.868709)
			(xy 339.223624 -48.939981) (xy 339.171253 -49.006577) (xy 339.112788 -49.067892) (xy 339.04876 -49.123373)
			(xy 338.979748 -49.172516) (xy 338.906378 -49.214876) (xy 338.829313 -49.250071) (xy 338.749251 -49.27778)
			(xy 338.666918 -49.297754) (xy 338.583059 -49.309811) (xy 338.498434 -49.313843) (xy 338.413809 -49.309811)
			(xy 338.32995 -49.297754) (xy 338.247617 -49.27778) (xy 338.167555 -49.250071) (xy 338.09049 -49.214876)
			(xy 338.01712 -49.172516) (xy 337.948108 -49.123373) (xy 337.88408 -49.067892) (xy 337.825615 -49.006577)
			(xy 337.773244 -48.939981) (xy 337.727441 -48.868709) (xy 337.688619 -48.793406) (xy 337.657131 -48.714754)
			(xy 337.633263 -48.633464) (xy 337.617229 -48.550274) (xy 337.609176 -48.465937) (xy 325.12 -48.465937)
			(xy 325.12 -48.668432) (xy 325.120494 -48.678435) (xy 325.128159 -48.696916) (xy 325.142311 -48.711059)
			(xy 325.160796 -48.718713) (xy 325.1708 -48.719232) (xy 335.25587 -48.719232) (xy 335.289131 -48.719751)
			(xy 335.355084 -48.728434) (xy 335.419339 -48.745655) (xy 335.480795 -48.771119) (xy 335.538399 -48.804389)
			(xy 335.591166 -48.844898) (xy 335.615026 -48.868076) (xy 335.62163 -48.87468) (xy 335.629042 -48.881364)
			(xy 335.647475 -48.888961) (xy 335.667413 -48.888961) (xy 335.685846 -48.881364) (xy 335.693258 -48.87468)
			(xy 335.724509 -48.844278) (xy 335.791985 -48.789057) (xy 335.864539 -48.740702) (xy 335.941475 -48.699675)
			(xy 336.022056 -48.666372) (xy 336.105508 -48.641111) (xy 336.191031 -48.624134) (xy 336.277804 -48.615605)
			(xy 336.3214 -48.615092) (xy 336.362502 -48.615567) (xy 336.444357 -48.623152) (xy 336.525162 -48.638257)
			(xy 336.604229 -48.660753) (xy 336.680883 -48.690449) (xy 336.75447 -48.727091) (xy 336.824362 -48.770366)
			(xy 336.889963 -48.819906) (xy 336.950713 -48.875287) (xy 337.006094 -48.936037) (xy 337.055634 -49.001638)
			(xy 337.098909 -49.07153) (xy 337.135551 -49.145117) (xy 337.165247 -49.221771) (xy 337.187743 -49.300838)
			(xy 337.202848 -49.381643) (xy 337.210433 -49.463498) (xy 337.210908 -49.5046) (xy 337.2104 -49.547722)
			(xy 337.202058 -49.633561) (xy 337.185451 -49.71819) (xy 337.160736 -49.800817) (xy 337.128145 -49.880665)
			(xy 337.087983 -49.956986) (xy 337.040626 -50.029065) (xy 336.98652 -50.096225) (xy 336.926171 -50.157836)
			(xy 336.860145 -50.21332) (xy 336.789062 -50.262158) (xy 336.713588 -50.303891) (xy 336.674206 -50.321464)
			(xy 336.643472 -50.367946) (xy 336.643472 -50.919888) (xy 376.553741 -50.919888) (xy 376.557716 -50.809829)
			(xy 376.569624 -50.700343) (xy 376.5894 -50.592002) (xy 376.616943 -50.485371) (xy 376.652108 -50.381005)
			(xy 376.694712 -50.279448) (xy 376.744533 -50.181231) (xy 376.801312 -50.086864) (xy 376.864751 -49.99684)
			(xy 376.934522 -49.911629) (xy 377.010259 -49.831674) (xy 377.091568 -49.757393) (xy 377.178025 -49.689173)
			(xy 377.269179 -49.627368) (xy 377.364556 -49.572303) (xy 377.463657 -49.524263) (xy 377.565966 -49.483499)
			(xy 377.67095 -49.450224) (xy 377.778061 -49.424611) (xy 377.886741 -49.406794) (xy 377.996424 -49.396865)
			(xy 378.106537 -49.394877) (xy 378.216507 -49.400839) (xy 378.32576 -49.414721) (xy 378.433726 -49.436451)
			(xy 378.539843 -49.465914) (xy 378.643557 -49.502957) (xy 378.744328 -49.547388) (xy 378.84163 -49.598975)
			(xy 378.934956 -49.657447) (xy 379.023819 -49.722502) (xy 379.107757 -49.7938) (xy 379.186332 -49.870968)
			(xy 379.259133 -49.953605) (xy 379.325781 -50.041279) (xy 379.38593 -50.133535) (xy 379.439264 -50.22989)
			(xy 379.485507 -50.329842) (xy 379.524417 -50.43287) (xy 379.555791 -50.538438) (xy 379.579466 -50.645994)
			(xy 379.595318 -50.754978) (xy 379.603265 -50.864822) (xy 379.603762 -50.919888) (xy 396.111741 -50.919888)
			(xy 396.115716 -50.809829) (xy 396.127624 -50.700343) (xy 396.1474 -50.592002) (xy 396.174943 -50.485371)
			(xy 396.210108 -50.381005) (xy 396.252712 -50.279448) (xy 396.302533 -50.181231) (xy 396.359312 -50.086864)
			(xy 396.422751 -49.99684) (xy 396.492522 -49.911629) (xy 396.568259 -49.831674) (xy 396.649568 -49.757393)
			(xy 396.736025 -49.689173) (xy 396.827179 -49.627368) (xy 396.922556 -49.572303) (xy 397.021657 -49.524263)
			(xy 397.123966 -49.483499) (xy 397.22895 -49.450224) (xy 397.336061 -49.424611) (xy 397.444741 -49.406794)
			(xy 397.554424 -49.396865) (xy 397.664537 -49.394877) (xy 397.774507 -49.400839) (xy 397.88376 -49.414721)
			(xy 397.991726 -49.436451) (xy 398.097843 -49.465914) (xy 398.201557 -49.502957) (xy 398.302328 -49.547388)
			(xy 398.39963 -49.598975) (xy 398.492956 -49.657447) (xy 398.581819 -49.722502) (xy 398.665757 -49.7938)
			(xy 398.744332 -49.870968) (xy 398.817133 -49.953605) (xy 398.883781 -50.041279) (xy 398.94393 -50.133535)
			(xy 398.997264 -50.22989) (xy 399.043507 -50.329842) (xy 399.082417 -50.43287) (xy 399.113791 -50.538438)
			(xy 399.137466 -50.645994) (xy 399.153318 -50.754978) (xy 399.161265 -50.864822) (xy 399.161762 -50.919888)
			(xy 399.161265 -50.974954) (xy 399.153318 -51.084798) (xy 399.137466 -51.193782) (xy 399.113791 -51.301338)
			(xy 399.082417 -51.406906) (xy 399.043507 -51.509934) (xy 398.997264 -51.609886) (xy 398.94393 -51.706241)
			(xy 398.883781 -51.798497) (xy 398.817133 -51.886171) (xy 398.744332 -51.968808) (xy 398.665757 -52.045976)
			(xy 398.581819 -52.117274) (xy 398.492956 -52.182329) (xy 398.39963 -52.240801) (xy 398.302328 -52.292388)
			(xy 398.201557 -52.336819) (xy 398.097843 -52.373862) (xy 397.991726 -52.403325) (xy 397.88376 -52.425055)
			(xy 397.774507 -52.438937) (xy 397.664537 -52.444899) (xy 397.554424 -52.442911) (xy 397.444741 -52.432982)
			(xy 397.336061 -52.415165) (xy 397.22895 -52.389552) (xy 397.123966 -52.356277) (xy 397.021657 -52.315513)
			(xy 396.922556 -52.267473) (xy 396.827179 -52.212408) (xy 396.736025 -52.150603) (xy 396.649568 -52.082383)
			(xy 396.568259 -52.008102) (xy 396.492522 -51.928147) (xy 396.422751 -51.842936) (xy 396.359312 -51.752912)
			(xy 396.302533 -51.658545) (xy 396.252712 -51.560328) (xy 396.210108 -51.458771) (xy 396.174943 -51.354405)
			(xy 396.1474 -51.247774) (xy 396.127624 -51.139433) (xy 396.115716 -51.029947) (xy 396.111741 -50.919888)
			(xy 379.603762 -50.919888) (xy 379.603265 -50.974954) (xy 379.595318 -51.084798) (xy 379.579466 -51.193782)
			(xy 379.555791 -51.301338) (xy 379.524417 -51.406906) (xy 379.485507 -51.509934) (xy 379.439264 -51.609886)
			(xy 379.38593 -51.706241) (xy 379.325781 -51.798497) (xy 379.259133 -51.886171) (xy 379.186332 -51.968808)
			(xy 379.107757 -52.045976) (xy 379.023819 -52.117274) (xy 378.934956 -52.182329) (xy 378.84163 -52.240801)
			(xy 378.744328 -52.292388) (xy 378.643557 -52.336819) (xy 378.539843 -52.373862) (xy 378.433726 -52.403325)
			(xy 378.32576 -52.425055) (xy 378.216507 -52.438937) (xy 378.106537 -52.444899) (xy 377.996424 -52.442911)
			(xy 377.886741 -52.432982) (xy 377.778061 -52.415165) (xy 377.67095 -52.389552) (xy 377.565966 -52.356277)
			(xy 377.463657 -52.315513) (xy 377.364556 -52.267473) (xy 377.269179 -52.212408) (xy 377.178025 -52.150603)
			(xy 377.091568 -52.082383) (xy 377.010259 -52.008102) (xy 376.934522 -51.928147) (xy 376.864751 -51.842936)
			(xy 376.801312 -51.752912) (xy 376.744533 -51.658545) (xy 376.694712 -51.560328) (xy 376.652108 -51.458771)
			(xy 376.616943 -51.354405) (xy 376.5894 -51.247774) (xy 376.569624 -51.139433) (xy 376.557716 -51.029947)
			(xy 376.553741 -50.919888) (xy 336.643472 -50.919888) (xy 336.643472 -51.41849) (xy 336.642951 -51.451751)
			(xy 336.634266 -51.517703) (xy 336.617044 -51.581956) (xy 336.591578 -51.64341) (xy 336.558306 -51.701013)
			(xy 336.517798 -51.753778) (xy 336.494628 -51.777646) (xy 336.312313 -51.959961) (xy 343.280742 -51.959961)
			(xy 343.280742 -51.875239) (xy 343.288795 -51.790902) (xy 343.304829 -51.707712) (xy 343.328697 -51.626422)
			(xy 343.360185 -51.54777) (xy 343.399007 -51.472467) (xy 343.44481 -51.401195) (xy 343.497181 -51.334599)
			(xy 343.555646 -51.273284) (xy 343.619674 -51.217803) (xy 343.688686 -51.16866) (xy 343.762056 -51.1263)
			(xy 343.839121 -51.091105) (xy 343.919183 -51.063396) (xy 344.001516 -51.043422) (xy 344.085375 -51.031365)
			(xy 344.17 -51.027334) (xy 344.254625 -51.031365) (xy 344.338484 -51.043422) (xy 344.420817 -51.063396)
			(xy 344.500879 -51.091105) (xy 344.577944 -51.1263) (xy 344.651314 -51.16866) (xy 344.720326 -51.217803)
			(xy 344.784354 -51.273284) (xy 344.842819 -51.334599) (xy 344.89519 -51.401195) (xy 344.940993 -51.472467)
			(xy 344.979815 -51.54777) (xy 345.011303 -51.626422) (xy 345.035171 -51.707712) (xy 345.051205 -51.790902)
			(xy 345.059258 -51.875239) (xy 345.059762 -51.9176) (xy 345.059258 -51.959961) (xy 345.051205 -52.044298)
			(xy 345.035171 -52.127488) (xy 345.011303 -52.208778) (xy 344.979815 -52.28743) (xy 344.940993 -52.362733)
			(xy 344.89519 -52.434005) (xy 344.842819 -52.500601) (xy 344.784354 -52.561916) (xy 344.720326 -52.617397)
			(xy 344.651314 -52.66654) (xy 344.577944 -52.7089) (xy 344.500879 -52.744095) (xy 344.420817 -52.771804)
			(xy 344.338484 -52.791778) (xy 344.254625 -52.803835) (xy 344.17 -52.807867) (xy 344.085375 -52.803835)
			(xy 344.001516 -52.791778) (xy 343.919183 -52.771804) (xy 343.839121 -52.744095) (xy 343.762056 -52.7089)
			(xy 343.688686 -52.66654) (xy 343.619674 -52.617397) (xy 343.555646 -52.561916) (xy 343.497181 -52.500601)
			(xy 343.44481 -52.434005) (xy 343.399007 -52.362733) (xy 343.360185 -52.28743) (xy 343.328697 -52.208778)
			(xy 343.304829 -52.127488) (xy 343.288795 -52.044298) (xy 343.280742 -51.959961) (xy 336.312313 -51.959961)
			(xy 335.679796 -52.592478) (xy 335.655918 -52.615639) (xy 335.603158 -52.656156) (xy 335.545558 -52.689436)
			(xy 335.484106 -52.714909) (xy 335.419854 -52.732139) (xy 335.353901 -52.740831) (xy 335.32064 -52.741322)
			(xy 330.298298 -52.741322) (xy 330.288228 -52.741746) (xy 330.269627 -52.749463) (xy 330.26223 -52.756308)
			(xy 330.255118 -52.76342) (xy 330.255118 -58.01614) (xy 330.255549 -58.026207) (xy 330.263276 -58.044799)
			(xy 330.270104 -58.052208) (xy 330.42225 -58.204354) (xy 330.429649 -58.211198) (xy 330.448248 -58.218921)
			(xy 330.458318 -58.21934) (xy 336.081116 -58.21934) (xy 336.114376 -58.219862) (xy 336.180326 -58.228551)
			(xy 336.244577 -58.245776) (xy 336.306029 -58.271244) (xy 336.363628 -58.304518) (xy 336.41639 -58.345029)
			(xy 336.440272 -58.368184) (xy 336.492088 -58.42) (xy 377.061486 -58.42) (xy 377.065468 -58.330072)
			(xy 377.077382 -58.240848) (xy 377.097135 -58.153026) (xy 377.124572 -58.067293) (xy 377.159479 -57.984321)
			(xy 377.201583 -57.904758) (xy 377.250553 -57.829228) (xy 377.306008 -57.758322) (xy 377.367512 -57.692594)
			(xy 377.434584 -57.632559) (xy 377.5067 -57.578687) (xy 377.583295 -57.531399) (xy 377.663769 -57.491066)
			(xy 377.747493 -57.458003) (xy 377.833812 -57.432469) (xy 377.92205 -57.414664) (xy 378.011515 -57.404726)
			(xy 378.10151 -57.402735) (xy 378.191327 -57.408705) (xy 378.280266 -57.42259) (xy 378.36763 -57.444281)
			(xy 378.452735 -57.473608) (xy 378.534914 -57.510342) (xy 378.613526 -57.554196) (xy 378.687954 -57.604825)
			(xy 378.757616 -57.661835) (xy 378.821967 -57.724778) (xy 378.880504 -57.793162) (xy 378.932767 -57.866452)
			(xy 378.978349 -57.944074) (xy 379.016892 -58.025421) (xy 379.048095 -58.109856) (xy 379.071713 -58.196718)
			(xy 379.087562 -58.285328) (xy 379.095518 -58.374992) (xy 379.096016 -58.42) (xy 396.619486 -58.42)
			(xy 396.623468 -58.330072) (xy 396.635382 -58.240848) (xy 396.655135 -58.153026) (xy 396.682572 -58.067293)
			(xy 396.717479 -57.984321) (xy 396.759583 -57.904758) (xy 396.808553 -57.829228) (xy 396.864008 -57.758322)
			(xy 396.925512 -57.692594) (xy 396.992584 -57.632559) (xy 397.0647 -57.578687) (xy 397.141295 -57.531399)
			(xy 397.221769 -57.491066) (xy 397.305493 -57.458003) (xy 397.391812 -57.432469) (xy 397.48005 -57.414664)
			(xy 397.569515 -57.404726) (xy 397.65951 -57.402735) (xy 397.749327 -57.408705) (xy 397.838266 -57.42259)
			(xy 397.92563 -57.444281) (xy 398.010735 -57.473608) (xy 398.092914 -57.510342) (xy 398.171526 -57.554196)
			(xy 398.245954 -57.604825) (xy 398.315616 -57.661835) (xy 398.379967 -57.724778) (xy 398.438504 -57.793162)
			(xy 398.490767 -57.866452) (xy 398.536349 -57.944074) (xy 398.574892 -58.025421) (xy 398.606095 -58.109856)
			(xy 398.629713 -58.196718) (xy 398.645562 -58.285328) (xy 398.653518 -58.374992) (xy 398.654016 -58.42)
			(xy 398.653518 -58.465008) (xy 398.645562 -58.554672) (xy 398.629713 -58.643282) (xy 398.606095 -58.730144)
			(xy 398.574892 -58.814579) (xy 398.536349 -58.895926) (xy 398.490767 -58.973548) (xy 398.438504 -59.046838)
			(xy 398.379967 -59.115222) (xy 398.315616 -59.178165) (xy 398.245954 -59.235175) (xy 398.171526 -59.285804)
			(xy 398.092914 -59.329658) (xy 398.010735 -59.366392) (xy 397.92563 -59.395719) (xy 397.838266 -59.41741)
			(xy 397.749327 -59.431295) (xy 397.65951 -59.437265) (xy 397.569515 -59.435274) (xy 397.48005 -59.425336)
			(xy 397.391812 -59.407531) (xy 397.305493 -59.381997) (xy 397.221769 -59.348934) (xy 397.141295 -59.308601)
			(xy 397.0647 -59.261313) (xy 396.992584 -59.207441) (xy 396.925512 -59.147406) (xy 396.864008 -59.081678)
			(xy 396.808553 -59.010772) (xy 396.759583 -58.935242) (xy 396.717479 -58.855679) (xy 396.682572 -58.772707)
			(xy 396.655135 -58.686974) (xy 396.635382 -58.599152) (xy 396.623468 -58.509928) (xy 396.619486 -58.42)
			(xy 379.096016 -58.42) (xy 379.095518 -58.465008) (xy 379.087562 -58.554672) (xy 379.071713 -58.643282)
			(xy 379.048095 -58.730144) (xy 379.016892 -58.814579) (xy 378.978349 -58.895926) (xy 378.932767 -58.973548)
			(xy 378.880504 -59.046838) (xy 378.821967 -59.115222) (xy 378.757616 -59.178165) (xy 378.687954 -59.235175)
			(xy 378.613526 -59.285804) (xy 378.534914 -59.329658) (xy 378.452735 -59.366392) (xy 378.36763 -59.395719)
			(xy 378.280266 -59.41741) (xy 378.191327 -59.431295) (xy 378.10151 -59.437265) (xy 378.011515 -59.435274)
			(xy 377.92205 -59.425336) (xy 377.833812 -59.407531) (xy 377.747493 -59.381997) (xy 377.663769 -59.348934)
			(xy 377.583295 -59.308601) (xy 377.5067 -59.261313) (xy 377.434584 -59.207441) (xy 377.367512 -59.147406)
			(xy 377.306008 -59.081678) (xy 377.250553 -59.010772) (xy 377.201583 -58.935242) (xy 377.159479 -58.855679)
			(xy 377.124572 -58.772707) (xy 377.097135 -58.686974) (xy 377.077382 -58.599152) (xy 377.065468 -58.509928)
			(xy 377.061486 -58.42) (xy 336.492088 -58.42) (xy 336.98434 -58.912252) (xy 337.007496 -58.936132)
			(xy 337.048003 -58.988895) (xy 337.081273 -59.046496) (xy 337.106738 -59.107948) (xy 337.123959 -59.172199)
			(xy 337.132644 -59.238149) (xy 337.133184 -59.271408) (xy 337.133184 -62.310518) (xy 337.132661 -62.343777)
			(xy 337.123972 -62.409726) (xy 337.106744 -62.473975) (xy 337.081273 -62.535425) (xy 337.047995 -62.593021)
			(xy 337.00748 -62.645778) (xy 336.98434 -62.669674) (xy 336.184748 -63.469266) (xy 336.16087 -63.492425)
			(xy 336.108108 -63.532938) (xy 336.050508 -63.566213) (xy 335.989056 -63.591681) (xy 335.924804 -63.608906)
			(xy 335.858852 -63.617592) (xy 335.825592 -63.61811) (xy 330.938378 -63.61811) (xy 330.92831 -63.618537)
			(xy 330.909712 -63.626259) (xy 330.90231 -63.633096) (xy 330.04633 -64.489076) (xy 330.039492 -64.496477)
			(xy 330.031781 -64.515076) (xy 330.031344 -64.525144) (xy 330.031344 -68.892928) (xy 330.031774 -68.902995)
			(xy 330.0395 -68.921588) (xy 330.04633 -68.928996) (xy 330.358496 -69.241162) (xy 330.365893 -69.248013)
			(xy 330.384491 -69.255755) (xy 330.394564 -69.256148) (xy 336.177382 -69.256148) (xy 336.210643 -69.256668)
			(xy 336.276595 -69.265353) (xy 336.340848 -69.282575) (xy 336.402303 -69.30804) (xy 336.459905 -69.341313)
			(xy 336.51267 -69.381822) (xy 336.536538 -69.404992) (xy 337.14436 -70.012814) (xy 337.167518 -70.036693)
			(xy 337.208027 -70.089456) (xy 337.2413 -70.147057) (xy 337.266768 -70.208509) (xy 337.283994 -70.27276)
			(xy 337.292683 -70.33871) (xy 337.293204 -70.37197) (xy 337.293204 -71.239888) (xy 376.553741 -71.239888)
			(xy 376.557716 -71.129829) (xy 376.569624 -71.020343) (xy 376.5894 -70.912002) (xy 376.616943 -70.805371)
			(xy 376.652108 -70.701005) (xy 376.694712 -70.599448) (xy 376.744533 -70.501231) (xy 376.801312 -70.406864)
			(xy 376.864751 -70.31684) (xy 376.934522 -70.231629) (xy 377.010259 -70.151674) (xy 377.091568 -70.077393)
			(xy 377.178025 -70.009173) (xy 377.269179 -69.947368) (xy 377.364556 -69.892303) (xy 377.463657 -69.844263)
			(xy 377.565966 -69.803499) (xy 377.67095 -69.770224) (xy 377.778061 -69.744611) (xy 377.886741 -69.726794)
			(xy 377.996424 -69.716865) (xy 378.106537 -69.714877) (xy 378.216507 -69.720839) (xy 378.32576 -69.734721)
			(xy 378.433726 -69.756451) (xy 378.539843 -69.785914) (xy 378.643557 -69.822957) (xy 378.744328 -69.867388)
			(xy 378.84163 -69.918975) (xy 378.934956 -69.977447) (xy 379.023819 -70.042502) (xy 379.107757 -70.1138)
			(xy 379.186332 -70.190968) (xy 379.259133 -70.273605) (xy 379.325781 -70.361279) (xy 379.38593 -70.453535)
			(xy 379.439264 -70.54989) (xy 379.485507 -70.649842) (xy 379.524417 -70.75287) (xy 379.555791 -70.858438)
			(xy 379.579466 -70.965994) (xy 379.595318 -71.074978) (xy 379.603265 -71.184822) (xy 379.603762 -71.239888)
			(xy 396.111741 -71.239888) (xy 396.115716 -71.129829) (xy 396.127624 -71.020343) (xy 396.1474 -70.912002)
			(xy 396.174943 -70.805371) (xy 396.210108 -70.701005) (xy 396.252712 -70.599448) (xy 396.302533 -70.501231)
			(xy 396.359312 -70.406864) (xy 396.422751 -70.31684) (xy 396.492522 -70.231629) (xy 396.568259 -70.151674)
			(xy 396.649568 -70.077393) (xy 396.736025 -70.009173) (xy 396.827179 -69.947368) (xy 396.922556 -69.892303)
			(xy 397.021657 -69.844263) (xy 397.123966 -69.803499) (xy 397.22895 -69.770224) (xy 397.336061 -69.744611)
			(xy 397.444741 -69.726794) (xy 397.554424 -69.716865) (xy 397.664537 -69.714877) (xy 397.774507 -69.720839)
			(xy 397.88376 -69.734721) (xy 397.991726 -69.756451) (xy 398.097843 -69.785914) (xy 398.201557 -69.822957)
			(xy 398.302328 -69.867388) (xy 398.39963 -69.918975) (xy 398.492956 -69.977447) (xy 398.581819 -70.042502)
			(xy 398.665757 -70.1138) (xy 398.744332 -70.190968) (xy 398.817133 -70.273605) (xy 398.883781 -70.361279)
			(xy 398.94393 -70.453535) (xy 398.997264 -70.54989) (xy 399.043507 -70.649842) (xy 399.082417 -70.75287)
			(xy 399.113791 -70.858438) (xy 399.137466 -70.965994) (xy 399.153318 -71.074978) (xy 399.161265 -71.184822)
			(xy 399.161762 -71.239888) (xy 399.161265 -71.294954) (xy 399.153318 -71.404798) (xy 399.137466 -71.513782)
			(xy 399.113791 -71.621338) (xy 399.082417 -71.726906) (xy 399.043507 -71.829934) (xy 398.997264 -71.929886)
			(xy 398.94393 -72.026241) (xy 398.883781 -72.118497) (xy 398.817133 -72.206171) (xy 398.744332 -72.288808)
			(xy 398.665757 -72.365976) (xy 398.581819 -72.437274) (xy 398.492956 -72.502329) (xy 398.39963 -72.560801)
			(xy 398.302328 -72.612388) (xy 398.201557 -72.656819) (xy 398.097843 -72.693862) (xy 397.991726 -72.723325)
			(xy 397.88376 -72.745055) (xy 397.774507 -72.758937) (xy 397.664537 -72.764899) (xy 397.554424 -72.762911)
			(xy 397.444741 -72.752982) (xy 397.336061 -72.735165) (xy 397.22895 -72.709552) (xy 397.123966 -72.676277)
			(xy 397.021657 -72.635513) (xy 396.922556 -72.587473) (xy 396.827179 -72.532408) (xy 396.736025 -72.470603)
			(xy 396.649568 -72.402383) (xy 396.568259 -72.328102) (xy 396.492522 -72.248147) (xy 396.422751 -72.162936)
			(xy 396.359312 -72.072912) (xy 396.302533 -71.978545) (xy 396.252712 -71.880328) (xy 396.210108 -71.778771)
			(xy 396.174943 -71.674405) (xy 396.1474 -71.567774) (xy 396.127624 -71.459433) (xy 396.115716 -71.349947)
			(xy 396.111741 -71.239888) (xy 379.603762 -71.239888) (xy 379.603265 -71.294954) (xy 379.595318 -71.404798)
			(xy 379.579466 -71.513782) (xy 379.555791 -71.621338) (xy 379.524417 -71.726906) (xy 379.485507 -71.829934)
			(xy 379.439264 -71.929886) (xy 379.38593 -72.026241) (xy 379.325781 -72.118497) (xy 379.259133 -72.206171)
			(xy 379.186332 -72.288808) (xy 379.107757 -72.365976) (xy 379.023819 -72.437274) (xy 378.934956 -72.502329)
			(xy 378.84163 -72.560801) (xy 378.744328 -72.612388) (xy 378.643557 -72.656819) (xy 378.539843 -72.693862)
			(xy 378.433726 -72.723325) (xy 378.32576 -72.745055) (xy 378.216507 -72.758937) (xy 378.106537 -72.764899)
			(xy 377.996424 -72.762911) (xy 377.886741 -72.752982) (xy 377.778061 -72.735165) (xy 377.67095 -72.709552)
			(xy 377.565966 -72.676277) (xy 377.463657 -72.635513) (xy 377.364556 -72.587473) (xy 377.269179 -72.532408)
			(xy 377.178025 -72.470603) (xy 377.091568 -72.402383) (xy 377.010259 -72.328102) (xy 376.934522 -72.248147)
			(xy 376.864751 -72.162936) (xy 376.801312 -72.072912) (xy 376.744533 -71.978545) (xy 376.694712 -71.880328)
			(xy 376.652108 -71.778771) (xy 376.616943 -71.674405) (xy 376.5894 -71.567774) (xy 376.569624 -71.459433)
			(xy 376.557716 -71.349947) (xy 376.553741 -71.239888) (xy 337.293204 -71.239888) (xy 337.293204 -74.674476)
			(xy 337.292684 -74.707737) (xy 337.284 -74.773688) (xy 337.266777 -74.837941) (xy 337.24131 -74.899395)
			(xy 337.208036 -74.956996) (xy 337.167524 -75.009758) (xy 337.14436 -75.033632) (xy 336.616548 -75.561444)
			(xy 336.592668 -75.5846) (xy 336.539905 -75.625107) (xy 336.482304 -75.658377) (xy 336.420852 -75.683841)
			(xy 336.356601 -75.701062) (xy 336.290651 -75.709747) (xy 336.257392 -75.710288) (xy 330.218542 -75.710288)
			(xy 330.208476 -75.710721) (xy 330.189886 -75.718449) (xy 330.182474 -75.725274) (xy 330.126086 -75.781662)
			(xy 330.11924 -75.78906) (xy 330.111515 -75.807659) (xy 330.1111 -75.81773) (xy 330.1111 -78.74)
			(xy 377.061486 -78.74) (xy 377.065468 -78.650072) (xy 377.077382 -78.560848) (xy 377.097135 -78.473026)
			(xy 377.124572 -78.387293) (xy 377.159479 -78.304321) (xy 377.201583 -78.224758) (xy 377.250553 -78.149228)
			(xy 377.306008 -78.078322) (xy 377.367512 -78.012594) (xy 377.434584 -77.952559) (xy 377.5067 -77.898687)
			(xy 377.583295 -77.851399) (xy 377.663769 -77.811066) (xy 377.747493 -77.778003) (xy 377.833812 -77.752469)
			(xy 377.92205 -77.734664) (xy 378.011515 -77.724726) (xy 378.10151 -77.722735) (xy 378.191327 -77.728705)
			(xy 378.280266 -77.74259) (xy 378.36763 -77.764281) (xy 378.452735 -77.793608) (xy 378.534914 -77.830342)
			(xy 378.613526 -77.874196) (xy 378.687954 -77.924825) (xy 378.757616 -77.981835) (xy 378.821967 -78.044778)
			(xy 378.880504 -78.113162) (xy 378.932767 -78.186452) (xy 378.978349 -78.264074) (xy 379.016892 -78.345421)
			(xy 379.048095 -78.429856) (xy 379.071713 -78.516718) (xy 379.087562 -78.605328) (xy 379.095518 -78.694992)
			(xy 379.096016 -78.74) (xy 396.619486 -78.74) (xy 396.623468 -78.650072) (xy 396.635382 -78.560848)
			(xy 396.655135 -78.473026) (xy 396.682572 -78.387293) (xy 396.717479 -78.304321) (xy 396.759583 -78.224758)
			(xy 396.808553 -78.149228) (xy 396.864008 -78.078322) (xy 396.925512 -78.012594) (xy 396.992584 -77.952559)
			(xy 397.0647 -77.898687) (xy 397.141295 -77.851399) (xy 397.221769 -77.811066) (xy 397.305493 -77.778003)
			(xy 397.391812 -77.752469) (xy 397.48005 -77.734664) (xy 397.569515 -77.724726) (xy 397.65951 -77.722735)
			(xy 397.749327 -77.728705) (xy 397.838266 -77.74259) (xy 397.92563 -77.764281) (xy 398.010735 -77.793608)
			(xy 398.092914 -77.830342) (xy 398.171526 -77.874196) (xy 398.245954 -77.924825) (xy 398.315616 -77.981835)
			(xy 398.379967 -78.044778) (xy 398.438504 -78.113162) (xy 398.490767 -78.186452) (xy 398.536349 -78.264074)
			(xy 398.574892 -78.345421) (xy 398.606095 -78.429856) (xy 398.629713 -78.516718) (xy 398.645562 -78.605328)
			(xy 398.653518 -78.694992) (xy 398.654016 -78.74) (xy 398.653518 -78.785008) (xy 398.645562 -78.874672)
			(xy 398.629713 -78.963282) (xy 398.606095 -79.050144) (xy 398.574892 -79.134579) (xy 398.536349 -79.215926)
			(xy 398.490767 -79.293548) (xy 398.438504 -79.366838) (xy 398.379967 -79.435222) (xy 398.315616 -79.498165)
			(xy 398.245954 -79.555175) (xy 398.171526 -79.605804) (xy 398.092914 -79.649658) (xy 398.010735 -79.686392)
			(xy 397.92563 -79.715719) (xy 397.838266 -79.73741) (xy 397.749327 -79.751295) (xy 397.65951 -79.757265)
			(xy 397.569515 -79.755274) (xy 397.48005 -79.745336) (xy 397.391812 -79.727531) (xy 397.305493 -79.701997)
			(xy 397.221769 -79.668934) (xy 397.141295 -79.628601) (xy 397.0647 -79.581313) (xy 396.992584 -79.527441)
			(xy 396.925512 -79.467406) (xy 396.864008 -79.401678) (xy 396.808553 -79.330772) (xy 396.759583 -79.255242)
			(xy 396.717479 -79.175679) (xy 396.682572 -79.092707) (xy 396.655135 -79.006974) (xy 396.635382 -78.919152)
			(xy 396.623468 -78.829928) (xy 396.619486 -78.74) (xy 379.096016 -78.74) (xy 379.095518 -78.785008)
			(xy 379.087562 -78.874672) (xy 379.071713 -78.963282) (xy 379.048095 -79.050144) (xy 379.016892 -79.134579)
			(xy 378.978349 -79.215926) (xy 378.932767 -79.293548) (xy 378.880504 -79.366838) (xy 378.821967 -79.435222)
			(xy 378.757616 -79.498165) (xy 378.687954 -79.555175) (xy 378.613526 -79.605804) (xy 378.534914 -79.649658)
			(xy 378.452735 -79.686392) (xy 378.36763 -79.715719) (xy 378.280266 -79.73741) (xy 378.191327 -79.751295)
			(xy 378.10151 -79.757265) (xy 378.011515 -79.755274) (xy 377.92205 -79.745336) (xy 377.833812 -79.727531)
			(xy 377.747493 -79.701997) (xy 377.663769 -79.668934) (xy 377.583295 -79.628601) (xy 377.5067 -79.581313)
			(xy 377.434584 -79.527441) (xy 377.367512 -79.467406) (xy 377.306008 -79.401678) (xy 377.250553 -79.330772)
			(xy 377.201583 -79.255242) (xy 377.159479 -79.175679) (xy 377.124572 -79.092707) (xy 377.097135 -79.006974)
			(xy 377.077382 -78.919152) (xy 377.065468 -78.829928) (xy 377.061486 -78.74) (xy 330.1111 -78.74)
			(xy 330.1111 -79.654146) (xy 330.110582 -79.687407) (xy 330.101901 -79.753361) (xy 330.084681 -79.817616)
			(xy 330.059217 -79.879072) (xy 330.025944 -79.936676) (xy 329.985434 -79.989441) (xy 329.962256 -80.013302)
			(xy 329.503786 -80.471772) (xy 329.496942 -80.47917) (xy 329.48922 -80.49777) (xy 329.4888 -80.50784)
			(xy 329.4888 -92.500196) (xy 334.864964 -92.500196) (xy 334.864964 -87.500206) (xy 334.865459 -87.399365)
			(xy 334.873377 -87.197838) (xy 334.889201 -86.996778) (xy 334.912906 -86.796494) (xy 334.944456 -86.597295)
			(xy 334.983802 -86.399488) (xy 335.030884 -86.203379) (xy 335.085629 -86.009269) (xy 335.147952 -85.817458)
			(xy 335.217757 -85.628241) (xy 335.294938 -85.441912) (xy 335.379374 -85.258755) (xy 335.470936 -85.079055)
			(xy 335.569482 -84.903089) (xy 335.67486 -84.731126) (xy 335.786909 -84.563434) (xy 335.905455 -84.40027)
			(xy 336.030315 -84.241885) (xy 336.161297 -84.088525) (xy 336.298199 -83.940425) (xy 336.440809 -83.797815)
			(xy 336.588909 -83.660913) (xy 336.742269 -83.529931) (xy 336.900654 -83.405071) (xy 337.063818 -83.286525)
			(xy 337.23151 -83.174476) (xy 337.403473 -83.069098) (xy 337.579439 -82.970552) (xy 337.759139 -82.87899)
			(xy 337.942296 -82.794554) (xy 338.128625 -82.717373) (xy 338.317842 -82.647568) (xy 338.509653 -82.585245)
			(xy 338.703763 -82.5305) (xy 338.899872 -82.483418) (xy 339.097679 -82.444072) (xy 339.296878 -82.412522)
			(xy 339.497162 -82.388817) (xy 339.698222 -82.372993) (xy 339.899749 -82.365075) (xy 340.101431 -82.365075)
			(xy 340.302958 -82.372993) (xy 340.504018 -82.388817) (xy 340.704302 -82.412522) (xy 340.903501 -82.444072)
			(xy 341.101308 -82.483418) (xy 341.297417 -82.5305) (xy 341.491527 -82.585245) (xy 341.683338 -82.647568)
			(xy 341.872555 -82.717373) (xy 342.058884 -82.794554) (xy 342.242041 -82.87899) (xy 342.421741 -82.970552)
			(xy 342.597707 -83.069098) (xy 342.76967 -83.174476) (xy 342.937362 -83.286525) (xy 343.100526 -83.405071)
			(xy 343.258911 -83.529931) (xy 343.412271 -83.660913) (xy 343.560371 -83.797815) (xy 343.702981 -83.940425)
			(xy 343.839883 -84.088525) (xy 343.970865 -84.241885) (xy 344.095725 -84.40027) (xy 344.214271 -84.563434)
			(xy 344.32632 -84.731126) (xy 344.431698 -84.903089) (xy 344.530244 -85.079055) (xy 344.621806 -85.258755)
			(xy 344.706242 -85.441912) (xy 344.783423 -85.628241) (xy 344.853228 -85.817458) (xy 344.915551 -86.009269)
			(xy 344.970296 -86.203379) (xy 345.017378 -86.399488) (xy 345.056724 -86.597295) (xy 345.088274 -86.796494)
			(xy 345.111979 -86.996778) (xy 345.127803 -87.197838) (xy 345.135721 -87.399365) (xy 345.136216 -87.500206)
			(xy 345.136216 -91.559888) (xy 376.553741 -91.559888) (xy 376.557716 -91.449829) (xy 376.569624 -91.340343)
			(xy 376.5894 -91.232002) (xy 376.616943 -91.125371) (xy 376.652108 -91.021005) (xy 376.694712 -90.919448)
			(xy 376.744533 -90.821231) (xy 376.801312 -90.726864) (xy 376.864751 -90.63684) (xy 376.934522 -90.551629)
			(xy 377.010259 -90.471674) (xy 377.091568 -90.397393) (xy 377.178025 -90.329173) (xy 377.269179 -90.267368)
			(xy 377.364556 -90.212303) (xy 377.463657 -90.164263) (xy 377.565966 -90.123499) (xy 377.67095 -90.090224)
			(xy 377.778061 -90.064611) (xy 377.886741 -90.046794) (xy 377.996424 -90.036865) (xy 378.106537 -90.034877)
			(xy 378.216507 -90.040839) (xy 378.32576 -90.054721) (xy 378.433726 -90.076451) (xy 378.539843 -90.105914)
			(xy 378.643557 -90.142957) (xy 378.744328 -90.187388) (xy 378.84163 -90.238975) (xy 378.934956 -90.297447)
			(xy 379.023819 -90.362502) (xy 379.107757 -90.4338) (xy 379.186332 -90.510968) (xy 379.259133 -90.593605)
			(xy 379.325781 -90.681279) (xy 379.38593 -90.773535) (xy 379.439264 -90.86989) (xy 379.485507 -90.969842)
			(xy 379.524417 -91.07287) (xy 379.555791 -91.178438) (xy 379.579466 -91.285994) (xy 379.595318 -91.394978)
			(xy 379.603265 -91.504822) (xy 379.603762 -91.559888) (xy 396.111741 -91.559888) (xy 396.115716 -91.449829)
			(xy 396.127624 -91.340343) (xy 396.1474 -91.232002) (xy 396.174943 -91.125371) (xy 396.210108 -91.021005)
			(xy 396.252712 -90.919448) (xy 396.302533 -90.821231) (xy 396.359312 -90.726864) (xy 396.422751 -90.63684)
			(xy 396.492522 -90.551629) (xy 396.568259 -90.471674) (xy 396.649568 -90.397393) (xy 396.736025 -90.329173)
			(xy 396.827179 -90.267368) (xy 396.922556 -90.212303) (xy 397.021657 -90.164263) (xy 397.123966 -90.123499)
			(xy 397.22895 -90.090224) (xy 397.336061 -90.064611) (xy 397.444741 -90.046794) (xy 397.554424 -90.036865)
			(xy 397.664537 -90.034877) (xy 397.774507 -90.040839) (xy 397.88376 -90.054721) (xy 397.991726 -90.076451)
			(xy 398.097843 -90.105914) (xy 398.201557 -90.142957) (xy 398.302328 -90.187388) (xy 398.39963 -90.238975)
			(xy 398.492956 -90.297447) (xy 398.581819 -90.362502) (xy 398.665757 -90.4338) (xy 398.744332 -90.510968)
			(xy 398.817133 -90.593605) (xy 398.883781 -90.681279) (xy 398.94393 -90.773535) (xy 398.997264 -90.86989)
			(xy 399.043507 -90.969842) (xy 399.082417 -91.07287) (xy 399.113791 -91.178438) (xy 399.137466 -91.285994)
			(xy 399.153318 -91.394978) (xy 399.161265 -91.504822) (xy 399.161762 -91.559888) (xy 399.161265 -91.614954)
			(xy 399.153318 -91.724798) (xy 399.137466 -91.833782) (xy 399.113791 -91.941338) (xy 399.082417 -92.046906)
			(xy 399.043507 -92.149934) (xy 398.997264 -92.249886) (xy 398.94393 -92.346241) (xy 398.883781 -92.438497)
			(xy 398.817133 -92.526171) (xy 398.744332 -92.608808) (xy 398.665757 -92.685976) (xy 398.581819 -92.757274)
			(xy 398.492956 -92.822329) (xy 398.39963 -92.880801) (xy 398.302328 -92.932388) (xy 398.201557 -92.976819)
			(xy 398.097843 -93.013862) (xy 397.991726 -93.043325) (xy 397.88376 -93.065055) (xy 397.774507 -93.078937)
			(xy 397.664537 -93.084899) (xy 397.554424 -93.082911) (xy 397.444741 -93.072982) (xy 397.336061 -93.055165)
			(xy 397.22895 -93.029552) (xy 397.123966 -92.996277) (xy 397.021657 -92.955513) (xy 396.922556 -92.907473)
			(xy 396.827179 -92.852408) (xy 396.736025 -92.790603) (xy 396.649568 -92.722383) (xy 396.568259 -92.648102)
			(xy 396.492522 -92.568147) (xy 396.422751 -92.482936) (xy 396.359312 -92.392912) (xy 396.302533 -92.298545)
			(xy 396.252712 -92.200328) (xy 396.210108 -92.098771) (xy 396.174943 -91.994405) (xy 396.1474 -91.887774)
			(xy 396.127624 -91.779433) (xy 396.115716 -91.669947) (xy 396.111741 -91.559888) (xy 379.603762 -91.559888)
			(xy 379.603265 -91.614954) (xy 379.595318 -91.724798) (xy 379.579466 -91.833782) (xy 379.555791 -91.941338)
			(xy 379.524417 -92.046906) (xy 379.485507 -92.149934) (xy 379.439264 -92.249886) (xy 379.38593 -92.346241)
			(xy 379.325781 -92.438497) (xy 379.259133 -92.526171) (xy 379.186332 -92.608808) (xy 379.107757 -92.685976)
			(xy 379.023819 -92.757274) (xy 378.934956 -92.822329) (xy 378.84163 -92.880801) (xy 378.744328 -92.932388)
			(xy 378.643557 -92.976819) (xy 378.539843 -93.013862) (xy 378.433726 -93.043325) (xy 378.32576 -93.065055)
			(xy 378.216507 -93.078937) (xy 378.106537 -93.084899) (xy 377.996424 -93.082911) (xy 377.886741 -93.072982)
			(xy 377.778061 -93.055165) (xy 377.67095 -93.029552) (xy 377.565966 -92.996277) (xy 377.463657 -92.955513)
			(xy 377.364556 -92.907473) (xy 377.269179 -92.852408) (xy 377.178025 -92.790603) (xy 377.091568 -92.722383)
			(xy 377.010259 -92.648102) (xy 376.934522 -92.568147) (xy 376.864751 -92.482936) (xy 376.801312 -92.392912)
			(xy 376.744533 -92.298545) (xy 376.694712 -92.200328) (xy 376.652108 -92.098771) (xy 376.616943 -91.994405)
			(xy 376.5894 -91.887774) (xy 376.569624 -91.779433) (xy 376.557716 -91.669947) (xy 376.553741 -91.559888)
			(xy 345.136216 -91.559888) (xy 345.136216 -92.500196) (xy 345.135721 -92.601037) (xy 345.127803 -92.802564)
			(xy 345.111979 -93.003624) (xy 345.088274 -93.203908) (xy 345.056724 -93.403107) (xy 345.017378 -93.600914)
			(xy 344.970296 -93.797023) (xy 344.915551 -93.991133) (xy 344.853228 -94.182944) (xy 344.783423 -94.372161)
			(xy 344.706242 -94.55849) (xy 344.621806 -94.741647) (xy 344.530244 -94.921347) (xy 344.431698 -95.097313)
			(xy 344.32632 -95.269276) (xy 344.214271 -95.436968) (xy 344.095725 -95.600132) (xy 343.970865 -95.758517)
			(xy 343.839883 -95.911877) (xy 343.702981 -96.059977) (xy 343.560371 -96.202587) (xy 343.412271 -96.339489)
			(xy 343.258911 -96.470471) (xy 343.100526 -96.595331) (xy 342.937362 -96.713877) (xy 342.76967 -96.825926)
			(xy 342.597707 -96.931304) (xy 342.421741 -97.02985) (xy 342.242041 -97.121412) (xy 342.058884 -97.205848)
			(xy 341.872555 -97.283029) (xy 341.683338 -97.352834) (xy 341.491527 -97.415157) (xy 341.297417 -97.469902)
			(xy 341.101308 -97.516984) (xy 340.903501 -97.55633) (xy 340.704302 -97.58788) (xy 340.504018 -97.611585)
			(xy 340.302958 -97.627409) (xy 340.101431 -97.635327) (xy 339.899749 -97.635327) (xy 339.698222 -97.627409)
			(xy 339.497162 -97.611585) (xy 339.296878 -97.58788) (xy 339.097679 -97.55633) (xy 338.899872 -97.516984)
			(xy 338.703763 -97.469902) (xy 338.509653 -97.415157) (xy 338.317842 -97.352834) (xy 338.128625 -97.283029)
			(xy 337.942296 -97.205848) (xy 337.759139 -97.121412) (xy 337.579439 -97.02985) (xy 337.403473 -96.931304)
			(xy 337.23151 -96.825926) (xy 337.063818 -96.713877) (xy 336.900654 -96.595331) (xy 336.742269 -96.470471)
			(xy 336.588909 -96.339489) (xy 336.440809 -96.202587) (xy 336.298199 -96.059977) (xy 336.161297 -95.911877)
			(xy 336.030315 -95.758517) (xy 335.905455 -95.600132) (xy 335.786909 -95.436968) (xy 335.67486 -95.269276)
			(xy 335.569482 -95.097313) (xy 335.470936 -94.921347) (xy 335.379374 -94.741647) (xy 335.294938 -94.55849)
			(xy 335.217757 -94.372161) (xy 335.147952 -94.182944) (xy 335.085629 -93.991133) (xy 335.030884 -93.797023)
			(xy 334.983802 -93.600914) (xy 334.944456 -93.403107) (xy 334.912906 -93.203908) (xy 334.889201 -93.003624)
			(xy 334.873377 -92.802564) (xy 334.865459 -92.601037) (xy 334.864964 -92.500196) (xy 329.4888 -92.500196)
			(xy 329.4888 -99.06) (xy 377.061486 -99.06) (xy 377.065468 -98.970072) (xy 377.077382 -98.880848)
			(xy 377.097135 -98.793026) (xy 377.124572 -98.707293) (xy 377.159479 -98.624321) (xy 377.201583 -98.544758)
			(xy 377.250553 -98.469228) (xy 377.306008 -98.398322) (xy 377.367512 -98.332594) (xy 377.434584 -98.272559)
			(xy 377.5067 -98.218687) (xy 377.583295 -98.171399) (xy 377.663769 -98.131066) (xy 377.747493 -98.098003)
			(xy 377.833812 -98.072469) (xy 377.92205 -98.054664) (xy 378.011515 -98.044726) (xy 378.10151 -98.042735)
			(xy 378.191327 -98.048705) (xy 378.280266 -98.06259) (xy 378.36763 -98.084281) (xy 378.452735 -98.113608)
			(xy 378.534914 -98.150342) (xy 378.613526 -98.194196) (xy 378.687954 -98.244825) (xy 378.757616 -98.301835)
			(xy 378.821967 -98.364778) (xy 378.880504 -98.433162) (xy 378.932767 -98.506452) (xy 378.978349 -98.584074)
			(xy 379.016892 -98.665421) (xy 379.048095 -98.749856) (xy 379.071713 -98.836718) (xy 379.087562 -98.925328)
			(xy 379.095518 -99.014992) (xy 379.096016 -99.06) (xy 396.619486 -99.06) (xy 396.623468 -98.970072)
			(xy 396.635382 -98.880848) (xy 396.655135 -98.793026) (xy 396.682572 -98.707293) (xy 396.717479 -98.624321)
			(xy 396.759583 -98.544758) (xy 396.808553 -98.469228) (xy 396.864008 -98.398322) (xy 396.925512 -98.332594)
			(xy 396.992584 -98.272559) (xy 397.0647 -98.218687) (xy 397.141295 -98.171399) (xy 397.221769 -98.131066)
			(xy 397.305493 -98.098003) (xy 397.391812 -98.072469) (xy 397.48005 -98.054664) (xy 397.569515 -98.044726)
			(xy 397.65951 -98.042735) (xy 397.749327 -98.048705) (xy 397.838266 -98.06259) (xy 397.92563 -98.084281)
			(xy 398.010735 -98.113608) (xy 398.092914 -98.150342) (xy 398.171526 -98.194196) (xy 398.245954 -98.244825)
			(xy 398.315616 -98.301835) (xy 398.379967 -98.364778) (xy 398.438504 -98.433162) (xy 398.490767 -98.506452)
			(xy 398.536349 -98.584074) (xy 398.574892 -98.665421) (xy 398.606095 -98.749856) (xy 398.629713 -98.836718)
			(xy 398.645562 -98.925328) (xy 398.653518 -99.014992) (xy 398.654016 -99.06) (xy 398.653518 -99.105008)
			(xy 398.645562 -99.194672) (xy 398.629713 -99.283282) (xy 398.606095 -99.370144) (xy 398.574892 -99.454579)
			(xy 398.536349 -99.535926) (xy 398.490767 -99.613548) (xy 398.438504 -99.686838) (xy 398.379967 -99.755222)
			(xy 398.315616 -99.818165) (xy 398.245954 -99.875175) (xy 398.171526 -99.925804) (xy 398.092914 -99.969658)
			(xy 398.010735 -100.006392) (xy 397.92563 -100.035719) (xy 397.838266 -100.05741) (xy 397.749327 -100.071295)
			(xy 397.65951 -100.077265) (xy 397.569515 -100.075274) (xy 397.48005 -100.065336) (xy 397.391812 -100.047531)
			(xy 397.305493 -100.021997) (xy 397.221769 -99.988934) (xy 397.141295 -99.948601) (xy 397.0647 -99.901313)
			(xy 396.992584 -99.847441) (xy 396.925512 -99.787406) (xy 396.864008 -99.721678) (xy 396.808553 -99.650772)
			(xy 396.759583 -99.575242) (xy 396.717479 -99.495679) (xy 396.682572 -99.412707) (xy 396.655135 -99.326974)
			(xy 396.635382 -99.239152) (xy 396.623468 -99.149928) (xy 396.619486 -99.06) (xy 379.096016 -99.06)
			(xy 379.095518 -99.105008) (xy 379.087562 -99.194672) (xy 379.071713 -99.283282) (xy 379.048095 -99.370144)
			(xy 379.016892 -99.454579) (xy 378.978349 -99.535926) (xy 378.932767 -99.613548) (xy 378.880504 -99.686838)
			(xy 378.821967 -99.755222) (xy 378.757616 -99.818165) (xy 378.687954 -99.875175) (xy 378.613526 -99.925804)
			(xy 378.534914 -99.969658) (xy 378.452735 -100.006392) (xy 378.36763 -100.035719) (xy 378.280266 -100.05741)
			(xy 378.191327 -100.071295) (xy 378.10151 -100.077265) (xy 378.011515 -100.075274) (xy 377.92205 -100.065336)
			(xy 377.833812 -100.047531) (xy 377.747493 -100.021997) (xy 377.663769 -99.988934) (xy 377.583295 -99.948601)
			(xy 377.5067 -99.901313) (xy 377.434584 -99.847441) (xy 377.367512 -99.787406) (xy 377.306008 -99.721678)
			(xy 377.250553 -99.650772) (xy 377.201583 -99.575242) (xy 377.159479 -99.495679) (xy 377.124572 -99.412707)
			(xy 377.097135 -99.326974) (xy 377.077382 -99.239152) (xy 377.065468 -99.149928) (xy 377.061486 -99.06)
			(xy 329.4888 -99.06) (xy 329.4888 -101.399086) (xy 329.48916 -101.408135) (xy 329.495436 -101.425111)
			(xy 329.507211 -101.438854) (xy 329.514962 -101.443536) (xy 329.59294 -101.486462) (xy 329.598604 -101.489401)
			(xy 329.610946 -101.492625) (xy 329.617324 -101.492812) (xy 329.644502 -101.484938) (xy 329.680034 -101.463133)
			(xy 329.754426 -101.425494) (xy 329.832013 -101.394979) (xy 329.912114 -101.371856) (xy 329.994027 -101.356328)
			(xy 330.077034 -101.348531) (xy 330.11872 -101.348032) (xy 330.161198 -101.348532) (xy 330.245766 -101.356641)
			(xy 330.329177 -101.372774) (xy 330.41067 -101.396784) (xy 330.489503 -101.428452) (xy 330.564959 -101.46749)
			(xy 330.63635 -101.513543) (xy 330.703026 -101.566191) (xy 330.764381 -101.624955) (xy 330.819855 -101.689299)
			(xy 330.868944 -101.758637) (xy 330.9112 -101.83234) (xy 330.946238 -101.909734) (xy 330.960476 -101.949758)
			(xy 330.96581 -101.965252) (xy 330.991972 -101.984048) (xy 334.325468 -101.984048) (xy 334.35163 -101.965252)
			(xy 334.356964 -101.949758) (xy 334.371175 -101.90972) (xy 334.406201 -101.832311) (xy 334.448448 -101.758595)
			(xy 334.497531 -101.689242) (xy 334.553003 -101.624885) (xy 334.614358 -101.56611) (xy 334.681038 -101.513453)
			(xy 334.752434 -101.467393) (xy 334.827897 -101.428351) (xy 334.906739 -101.396681) (xy 334.988241 -101.372673)
			(xy 335.07166 -101.356545) (xy 335.156238 -101.348444) (xy 335.241202 -101.348444) (xy 335.32578 -101.356545)
			(xy 335.409199 -101.372673) (xy 335.490701 -101.396681) (xy 335.569543 -101.428351) (xy 335.645006 -101.467393)
			(xy 335.716402 -101.513453) (xy 335.783082 -101.56611) (xy 335.844437 -101.624885) (xy 335.899909 -101.689242)
			(xy 335.948992 -101.758595) (xy 335.991239 -101.832311) (xy 336.026265 -101.90972) (xy 336.040476 -101.949758)
			(xy 336.04581 -101.965252) (xy 336.071972 -101.984048) (xy 339.405468 -101.984048) (xy 339.43163 -101.965252)
			(xy 339.436964 -101.949758) (xy 339.451175 -101.90972) (xy 339.486201 -101.832311) (xy 339.528448 -101.758595)
			(xy 339.577531 -101.689242) (xy 339.633003 -101.624885) (xy 339.694358 -101.56611) (xy 339.761038 -101.513453)
			(xy 339.832434 -101.467393) (xy 339.907897 -101.428351) (xy 339.986739 -101.396681) (xy 340.068241 -101.372673)
			(xy 340.15166 -101.356545) (xy 340.236238 -101.348444) (xy 340.321202 -101.348444) (xy 340.40578 -101.356545)
			(xy 340.489199 -101.372673) (xy 340.570701 -101.396681) (xy 340.649543 -101.428351) (xy 340.725006 -101.467393)
			(xy 340.796402 -101.513453) (xy 340.863082 -101.56611) (xy 340.924437 -101.624885) (xy 340.979909 -101.689242)
			(xy 341.028992 -101.758595) (xy 341.071239 -101.832311) (xy 341.106265 -101.90972) (xy 341.120476 -101.949758)
			(xy 341.12581 -101.965252) (xy 341.151972 -101.984048) (xy 344.000074 -101.984048) (xy 344.122446 -101.984525)
			(xy 344.367086 -101.991637) (xy 344.489278 -101.998272) (xy 344.499435 -101.998447) (xy 344.518585 -101.99172)
			(xy 344.533609 -101.978073) (xy 344.5383 -101.969062) (xy 344.556553 -101.931268) (xy 344.599182 -101.858962)
			(xy 344.648434 -101.790994) (xy 344.703872 -101.72797) (xy 344.765002 -101.67045) (xy 344.83128 -101.618946)
			(xy 344.902117 -101.573917) (xy 344.976881 -101.535764) (xy 345.054908 -101.504825) (xy 345.135502 -101.481376)
			(xy 345.217948 -101.465625) (xy 345.301512 -101.457714) (xy 345.34348 -101.457252) (xy 345.386739 -101.457766)
			(xy 345.472848 -101.466164) (xy 345.557735 -101.482882) (xy 345.640598 -101.507763) (xy 345.720654 -101.540571)
			(xy 345.797147 -101.580996) (xy 345.869353 -101.628657) (xy 345.936591 -101.683103) (xy 345.998226 -101.74382)
			(xy 346.053674 -101.810234) (xy 346.102413 -101.881717) (xy 346.143981 -101.957595) (xy 346.177986 -102.03715)
			(xy 346.204107 -102.11963) (xy 346.222097 -102.204257) (xy 346.2274 -102.247192) (xy 346.228993 -102.257191)
			(xy 346.238893 -102.274833) (xy 346.254844 -102.287275) (xy 346.264484 -102.290372) (xy 346.388577 -102.325108)
			(xy 346.634834 -102.401133) (xy 346.878677 -102.484575) (xy 347.119884 -102.575356) (xy 347.358234 -102.673394)
			(xy 347.593508 -102.778599) (xy 347.825491 -102.890874) (xy 348.053971 -103.010118) (xy 348.278738 -103.13622)
			(xy 348.499587 -103.269065) (xy 348.716315 -103.408532) (xy 348.928723 -103.554493) (xy 349.136618 -103.706814)
			(xy 349.339809 -103.865355) (xy 349.53811 -104.029972) (xy 349.731339 -104.200514) (xy 349.91932 -104.376825)
			(xy 350.10188 -104.558742) (xy 350.278851 -104.7461) (xy 350.450073 -104.938727) (xy 350.615388 -105.136447)
			(xy 350.774644 -105.339078) (xy 350.927697 -105.546435) (xy 351.074405 -105.758328) (xy 351.214635 -105.974563)
			(xy 351.348257 -106.194943) (xy 351.475151 -106.419264) (xy 351.595198 -106.647322) (xy 351.708291 -106.878908)
			(xy 351.814324 -107.11381) (xy 351.913201 -107.351813) (xy 352.004832 -107.592699) (xy 352.089132 -107.836247)
			(xy 352.166024 -108.082234) (xy 352.235437 -108.330435) (xy 352.29731 -108.580622) (xy 352.351583 -108.832568)
			(xy 352.398209 -109.08604) (xy 352.437144 -109.340806) (xy 352.453194 -109.468666) (xy 352.49104 -109.511592)
			(xy 352.531446 -109.522561) (xy 352.610166 -109.55109) (xy 352.685858 -109.586889) (xy 352.757853 -109.629641)
			(xy 352.825512 -109.678967) (xy 352.888238 -109.734431) (xy 352.945476 -109.795543) (xy 352.99672 -109.861762)
			(xy 353.041515 -109.932502) (xy 353.079467 -110.007138) (xy 353.11024 -110.085009) (xy 353.13356 -110.165427)
			(xy 353.149222 -110.24768) (xy 353.157088 -110.331041) (xy 353.157536 -110.372906) (xy 353.157031 -110.415602)
			(xy 353.148849 -110.5006) (xy 353.132559 -110.584423) (xy 353.108313 -110.6663) (xy 353.076333 -110.745477)
			(xy 353.036914 -110.821225) (xy 352.990418 -110.892848) (xy 352.937273 -110.959686) (xy 352.877968 -111.021124)
			(xy 352.813049 -111.076597) (xy 352.743114 -111.125595) (xy 352.668806 -111.167666) (xy 352.590808 -111.202423)
			(xy 352.550476 -111.21644) (xy 352.534982 -111.221774) (xy 352.515932 -111.24819) (xy 352.515932 -111.879888)
			(xy 376.553741 -111.879888) (xy 376.557716 -111.769829) (xy 376.569624 -111.660343) (xy 376.5894 -111.552002)
			(xy 376.616943 -111.445371) (xy 376.652108 -111.341005) (xy 376.694712 -111.239448) (xy 376.744533 -111.141231)
			(xy 376.801312 -111.046864) (xy 376.864751 -110.95684) (xy 376.934522 -110.871629) (xy 377.010259 -110.791674)
			(xy 377.091568 -110.717393) (xy 377.178025 -110.649173) (xy 377.269179 -110.587368) (xy 377.364556 -110.532303)
			(xy 377.463657 -110.484263) (xy 377.565966 -110.443499) (xy 377.67095 -110.410224) (xy 377.778061 -110.384611)
			(xy 377.886741 -110.366794) (xy 377.996424 -110.356865) (xy 378.106537 -110.354877) (xy 378.216507 -110.360839)
			(xy 378.32576 -110.374721) (xy 378.433726 -110.396451) (xy 378.539843 -110.425914) (xy 378.643557 -110.462957)
			(xy 378.744328 -110.507388) (xy 378.84163 -110.558975) (xy 378.934956 -110.617447) (xy 379.023819 -110.682502)
			(xy 379.107757 -110.7538) (xy 379.186332 -110.830968) (xy 379.259133 -110.913605) (xy 379.325781 -111.001279)
			(xy 379.38593 -111.093535) (xy 379.439264 -111.18989) (xy 379.485507 -111.289842) (xy 379.524417 -111.39287)
			(xy 379.555791 -111.498438) (xy 379.579466 -111.605994) (xy 379.595318 -111.714978) (xy 379.603265 -111.824822)
			(xy 379.603762 -111.879888) (xy 396.111741 -111.879888) (xy 396.115716 -111.769829) (xy 396.127624 -111.660343)
			(xy 396.1474 -111.552002) (xy 396.174943 -111.445371) (xy 396.210108 -111.341005) (xy 396.252712 -111.239448)
			(xy 396.302533 -111.141231) (xy 396.359312 -111.046864) (xy 396.422751 -110.95684) (xy 396.492522 -110.871629)
			(xy 396.568259 -110.791674) (xy 396.649568 -110.717393) (xy 396.736025 -110.649173) (xy 396.827179 -110.587368)
			(xy 396.922556 -110.532303) (xy 397.021657 -110.484263) (xy 397.123966 -110.443499) (xy 397.22895 -110.410224)
			(xy 397.336061 -110.384611) (xy 397.444741 -110.366794) (xy 397.554424 -110.356865) (xy 397.664537 -110.354877)
			(xy 397.774507 -110.360839) (xy 397.88376 -110.374721) (xy 397.991726 -110.396451) (xy 398.097843 -110.425914)
			(xy 398.201557 -110.462957) (xy 398.302328 -110.507388) (xy 398.39963 -110.558975) (xy 398.492956 -110.617447)
			(xy 398.581819 -110.682502) (xy 398.665757 -110.7538) (xy 398.744332 -110.830968) (xy 398.817133 -110.913605)
			(xy 398.883781 -111.001279) (xy 398.94393 -111.093535) (xy 398.997264 -111.18989) (xy 399.043507 -111.289842)
			(xy 399.082417 -111.39287) (xy 399.113791 -111.498438) (xy 399.137466 -111.605994) (xy 399.153318 -111.714978)
			(xy 399.161265 -111.824822) (xy 399.161762 -111.879888) (xy 399.161265 -111.934954) (xy 399.153318 -112.044798)
			(xy 399.137466 -112.153782) (xy 399.113791 -112.261338) (xy 399.082417 -112.366906) (xy 399.043507 -112.469934)
			(xy 398.997264 -112.569886) (xy 398.94393 -112.666241) (xy 398.883781 -112.758497) (xy 398.817133 -112.846171)
			(xy 398.744332 -112.928808) (xy 398.665757 -113.005976) (xy 398.581819 -113.077274) (xy 398.492956 -113.142329)
			(xy 398.39963 -113.200801) (xy 398.302328 -113.252388) (xy 398.201557 -113.296819) (xy 398.097843 -113.333862)
			(xy 397.991726 -113.363325) (xy 397.88376 -113.385055) (xy 397.774507 -113.398937) (xy 397.664537 -113.404899)
			(xy 397.554424 -113.402911) (xy 397.444741 -113.392982) (xy 397.336061 -113.375165) (xy 397.22895 -113.349552)
			(xy 397.123966 -113.316277) (xy 397.021657 -113.275513) (xy 396.922556 -113.227473) (xy 396.827179 -113.172408)
			(xy 396.736025 -113.110603) (xy 396.649568 -113.042383) (xy 396.568259 -112.968102) (xy 396.492522 -112.888147)
			(xy 396.422751 -112.802936) (xy 396.359312 -112.712912) (xy 396.302533 -112.618545) (xy 396.252712 -112.520328)
			(xy 396.210108 -112.418771) (xy 396.174943 -112.314405) (xy 396.1474 -112.207774) (xy 396.127624 -112.099433)
			(xy 396.115716 -111.989947) (xy 396.111741 -111.879888) (xy 379.603762 -111.879888) (xy 379.603265 -111.934954)
			(xy 379.595318 -112.044798) (xy 379.579466 -112.153782) (xy 379.555791 -112.261338) (xy 379.524417 -112.366906)
			(xy 379.485507 -112.469934) (xy 379.439264 -112.569886) (xy 379.38593 -112.666241) (xy 379.325781 -112.758497)
			(xy 379.259133 -112.846171) (xy 379.186332 -112.928808) (xy 379.107757 -113.005976) (xy 379.023819 -113.077274)
			(xy 378.934956 -113.142329) (xy 378.84163 -113.200801) (xy 378.744328 -113.252388) (xy 378.643557 -113.296819)
			(xy 378.539843 -113.333862) (xy 378.433726 -113.363325) (xy 378.32576 -113.385055) (xy 378.216507 -113.398937)
			(xy 378.106537 -113.404899) (xy 377.996424 -113.402911) (xy 377.886741 -113.392982) (xy 377.778061 -113.375165)
			(xy 377.67095 -113.349552) (xy 377.565966 -113.316277) (xy 377.463657 -113.275513) (xy 377.364556 -113.227473)
			(xy 377.269179 -113.172408) (xy 377.178025 -113.110603) (xy 377.091568 -113.042383) (xy 377.010259 -112.968102)
			(xy 376.934522 -112.888147) (xy 376.864751 -112.802936) (xy 376.801312 -112.712912) (xy 376.744533 -112.618545)
			(xy 376.694712 -112.520328) (xy 376.652108 -112.418771) (xy 376.616943 -112.314405) (xy 376.5894 -112.207774)
			(xy 376.569624 -112.099433) (xy 376.557716 -111.989947) (xy 376.553741 -111.879888) (xy 352.515932 -111.879888)
			(xy 352.515932 -114.561366) (xy 352.516448 -114.571942) (xy 352.524971 -114.591297) (xy 352.540609 -114.605534)
			(xy 352.550476 -114.609372) (xy 352.590802 -114.623408) (xy 352.668804 -114.658159) (xy 352.743117 -114.700224)
			(xy 352.813057 -114.749217) (xy 352.87798 -114.804686) (xy 352.93729 -114.866121) (xy 352.990439 -114.932958)
			(xy 353.036938 -115.004579) (xy 353.076361 -115.080327) (xy 353.108343 -115.159504) (xy 353.132591 -115.241382)
			(xy 353.148881 -115.325206) (xy 353.157064 -115.410206) (xy 353.157064 -115.495598) (xy 353.148881 -115.580598)
			(xy 353.13259 -115.664422) (xy 353.108342 -115.746299) (xy 353.076359 -115.825476) (xy 353.036936 -115.901224)
			(xy 352.990436 -115.972846) (xy 352.937287 -116.039681) (xy 352.877978 -116.101117) (xy 352.813054 -116.156586)
			(xy 352.743114 -116.205578) (xy 352.668801 -116.247643) (xy 352.590799 -116.282393) (xy 352.550476 -116.29644)
			(xy 352.534982 -116.301774) (xy 352.515932 -116.32819) (xy 352.515932 -119.38) (xy 377.061486 -119.38)
			(xy 377.065468 -119.290072) (xy 377.077382 -119.200848) (xy 377.097135 -119.113026) (xy 377.124572 -119.027293)
			(xy 377.159479 -118.944321) (xy 377.201583 -118.864758) (xy 377.250553 -118.789228) (xy 377.306008 -118.718322)
			(xy 377.367512 -118.652594) (xy 377.434584 -118.592559) (xy 377.5067 -118.538687) (xy 377.583295 -118.491399)
			(xy 377.663769 -118.451066) (xy 377.747493 -118.418003) (xy 377.833812 -118.392469) (xy 377.92205 -118.374664)
			(xy 378.011515 -118.364726) (xy 378.10151 -118.362735) (xy 378.191327 -118.368705) (xy 378.280266 -118.38259)
			(xy 378.36763 -118.404281) (xy 378.452735 -118.433608) (xy 378.534914 -118.470342) (xy 378.613526 -118.514196)
			(xy 378.687954 -118.564825) (xy 378.757616 -118.621835) (xy 378.821967 -118.684778) (xy 378.880504 -118.753162)
			(xy 378.932767 -118.826452) (xy 378.978349 -118.904074) (xy 379.016892 -118.985421) (xy 379.048095 -119.069856)
			(xy 379.071713 -119.156718) (xy 379.087562 -119.245328) (xy 379.095518 -119.334992) (xy 379.096016 -119.38)
			(xy 396.619486 -119.38) (xy 396.623468 -119.290072) (xy 396.635382 -119.200848) (xy 396.655135 -119.113026)
			(xy 396.682572 -119.027293) (xy 396.717479 -118.944321) (xy 396.759583 -118.864758) (xy 396.808553 -118.789228)
			(xy 396.864008 -118.718322) (xy 396.925512 -118.652594) (xy 396.992584 -118.592559) (xy 397.0647 -118.538687)
			(xy 397.141295 -118.491399) (xy 397.221769 -118.451066) (xy 397.305493 -118.418003) (xy 397.391812 -118.392469)
			(xy 397.48005 -118.374664) (xy 397.569515 -118.364726) (xy 397.65951 -118.362735) (xy 397.749327 -118.368705)
			(xy 397.838266 -118.38259) (xy 397.92563 -118.404281) (xy 398.010735 -118.433608) (xy 398.092914 -118.470342)
			(xy 398.171526 -118.514196) (xy 398.245954 -118.564825) (xy 398.315616 -118.621835) (xy 398.379967 -118.684778)
			(xy 398.438504 -118.753162) (xy 398.490767 -118.826452) (xy 398.536349 -118.904074) (xy 398.574892 -118.985421)
			(xy 398.606095 -119.069856) (xy 398.629713 -119.156718) (xy 398.645562 -119.245328) (xy 398.653518 -119.334992)
			(xy 398.654016 -119.38) (xy 398.653518 -119.425008) (xy 398.645562 -119.514672) (xy 398.629713 -119.603282)
			(xy 398.606095 -119.690144) (xy 398.574892 -119.774579) (xy 398.536349 -119.855926) (xy 398.490767 -119.933548)
			(xy 398.438504 -120.006838) (xy 398.379967 -120.075222) (xy 398.315616 -120.138165) (xy 398.245954 -120.195175)
			(xy 398.171526 -120.245804) (xy 398.092914 -120.289658) (xy 398.010735 -120.326392) (xy 397.92563 -120.355719)
			(xy 397.838266 -120.37741) (xy 397.749327 -120.391295) (xy 397.65951 -120.397265) (xy 397.569515 -120.395274)
			(xy 397.48005 -120.385336) (xy 397.391812 -120.367531) (xy 397.305493 -120.341997) (xy 397.221769 -120.308934)
			(xy 397.141295 -120.268601) (xy 397.0647 -120.221313) (xy 396.992584 -120.167441) (xy 396.925512 -120.107406)
			(xy 396.864008 -120.041678) (xy 396.808553 -119.970772) (xy 396.759583 -119.895242) (xy 396.717479 -119.815679)
			(xy 396.682572 -119.732707) (xy 396.655135 -119.646974) (xy 396.635382 -119.559152) (xy 396.623468 -119.469928)
			(xy 396.619486 -119.38) (xy 379.096016 -119.38) (xy 379.095518 -119.425008) (xy 379.087562 -119.514672)
			(xy 379.071713 -119.603282) (xy 379.048095 -119.690144) (xy 379.016892 -119.774579) (xy 378.978349 -119.855926)
			(xy 378.932767 -119.933548) (xy 378.880504 -120.006838) (xy 378.821967 -120.075222) (xy 378.757616 -120.138165)
			(xy 378.687954 -120.195175) (xy 378.613526 -120.245804) (xy 378.534914 -120.289658) (xy 378.452735 -120.326392)
			(xy 378.36763 -120.355719) (xy 378.280266 -120.37741) (xy 378.191327 -120.391295) (xy 378.10151 -120.397265)
			(xy 378.011515 -120.395274) (xy 377.92205 -120.385336) (xy 377.833812 -120.367531) (xy 377.747493 -120.341997)
			(xy 377.663769 -120.308934) (xy 377.583295 -120.268601) (xy 377.5067 -120.221313) (xy 377.434584 -120.167441)
			(xy 377.367512 -120.107406) (xy 377.306008 -120.041678) (xy 377.250553 -119.970772) (xy 377.201583 -119.895242)
			(xy 377.159479 -119.815679) (xy 377.124572 -119.732707) (xy 377.097135 -119.646974) (xy 377.077382 -119.559152)
			(xy 377.065468 -119.469928) (xy 377.061486 -119.38) (xy 352.515932 -119.38) (xy 352.515932 -119.641366)
			(xy 352.516448 -119.651942) (xy 352.524971 -119.671297) (xy 352.540609 -119.685534) (xy 352.550476 -119.689372)
			(xy 352.590802 -119.703408) (xy 352.668804 -119.738159) (xy 352.743117 -119.780224) (xy 352.813057 -119.829217)
			(xy 352.87798 -119.884686) (xy 352.93729 -119.946121) (xy 352.990439 -120.012958) (xy 353.036938 -120.084579)
			(xy 353.076361 -120.160327) (xy 353.108343 -120.239504) (xy 353.132591 -120.321382) (xy 353.148881 -120.405206)
			(xy 353.157064 -120.490206) (xy 353.157064 -120.575598) (xy 353.148881 -120.660598) (xy 353.13259 -120.744422)
			(xy 353.108342 -120.826299) (xy 353.076359 -120.905476) (xy 353.036936 -120.981224) (xy 352.990436 -121.052846)
			(xy 352.937287 -121.119681) (xy 352.877978 -121.181117) (xy 352.813054 -121.236586) (xy 352.743114 -121.285578)
			(xy 352.668801 -121.327643) (xy 352.590799 -121.362393) (xy 352.550476 -121.37644) (xy 352.534982 -121.381774)
			(xy 352.515932 -121.40819) (xy 352.515932 -124.721366) (xy 352.516448 -124.731942) (xy 352.524971 -124.751297)
			(xy 352.540609 -124.765534) (xy 352.550476 -124.769372) (xy 352.590802 -124.783408) (xy 352.668804 -124.818159)
			(xy 352.743117 -124.860224) (xy 352.813057 -124.909217) (xy 352.87798 -124.964686) (xy 352.93729 -125.026121)
			(xy 352.990439 -125.092958) (xy 353.036938 -125.164579) (xy 353.076361 -125.240327) (xy 353.108343 -125.319504)
			(xy 353.132591 -125.401382) (xy 353.148881 -125.485206) (xy 353.157064 -125.570206) (xy 353.157064 -125.655598)
			(xy 353.148881 -125.740598) (xy 353.13259 -125.824422) (xy 353.108342 -125.906299) (xy 353.076359 -125.985476)
			(xy 353.036936 -126.061224) (xy 352.990436 -126.132846) (xy 352.937287 -126.199681) (xy 352.877978 -126.261117)
			(xy 352.813054 -126.316586) (xy 352.743114 -126.365578) (xy 352.668801 -126.407643) (xy 352.590799 -126.442393)
			(xy 352.550476 -126.45644) (xy 352.534982 -126.461774) (xy 352.515932 -126.48819) (xy 352.515932 -129.801366)
			(xy 352.516448 -129.811942) (xy 352.524971 -129.831297) (xy 352.540609 -129.845534) (xy 352.550476 -129.849372)
			(xy 352.590802 -129.863408) (xy 352.668804 -129.898159) (xy 352.743117 -129.940224) (xy 352.813057 -129.989217)
			(xy 352.87798 -130.044686) (xy 352.93729 -130.106121) (xy 352.990439 -130.172958) (xy 353.036938 -130.244579)
			(xy 353.076361 -130.320327) (xy 353.108343 -130.399504) (xy 353.132591 -130.481382) (xy 353.148881 -130.565206)
			(xy 353.157064 -130.650206) (xy 353.157064 -130.735598) (xy 353.148881 -130.820598) (xy 353.13259 -130.904422)
			(xy 353.108342 -130.986299) (xy 353.076359 -131.065476) (xy 353.036936 -131.141224) (xy 352.990436 -131.212846)
			(xy 352.937287 -131.279681) (xy 352.877978 -131.341117) (xy 352.813054 -131.396586) (xy 352.743114 -131.445578)
			(xy 352.668801 -131.487643) (xy 352.590799 -131.522393) (xy 352.550476 -131.53644) (xy 352.534982 -131.541774)
			(xy 352.515932 -131.56819) (xy 352.515932 -132.199888) (xy 376.553741 -132.199888) (xy 376.557716 -132.089829)
			(xy 376.569624 -131.980343) (xy 376.5894 -131.872002) (xy 376.616943 -131.765371) (xy 376.652108 -131.661005)
			(xy 376.694712 -131.559448) (xy 376.744533 -131.461231) (xy 376.801312 -131.366864) (xy 376.864751 -131.27684)
			(xy 376.934522 -131.191629) (xy 377.010259 -131.111674) (xy 377.091568 -131.037393) (xy 377.178025 -130.969173)
			(xy 377.269179 -130.907368) (xy 377.364556 -130.852303) (xy 377.463657 -130.804263) (xy 377.565966 -130.763499)
			(xy 377.67095 -130.730224) (xy 377.778061 -130.704611) (xy 377.886741 -130.686794) (xy 377.996424 -130.676865)
			(xy 378.106537 -130.674877) (xy 378.216507 -130.680839) (xy 378.32576 -130.694721) (xy 378.433726 -130.716451)
			(xy 378.539843 -130.745914) (xy 378.643557 -130.782957) (xy 378.744328 -130.827388) (xy 378.84163 -130.878975)
			(xy 378.934956 -130.937447) (xy 379.023819 -131.002502) (xy 379.107757 -131.0738) (xy 379.186332 -131.150968)
			(xy 379.259133 -131.233605) (xy 379.325781 -131.321279) (xy 379.38593 -131.413535) (xy 379.439264 -131.50989)
			(xy 379.485507 -131.609842) (xy 379.524417 -131.71287) (xy 379.555791 -131.818438) (xy 379.579466 -131.925994)
			(xy 379.595318 -132.034978) (xy 379.603265 -132.144822) (xy 379.603762 -132.199888) (xy 396.111741 -132.199888)
			(xy 396.115716 -132.089829) (xy 396.127624 -131.980343) (xy 396.1474 -131.872002) (xy 396.174943 -131.765371)
			(xy 396.210108 -131.661005) (xy 396.252712 -131.559448) (xy 396.302533 -131.461231) (xy 396.359312 -131.366864)
			(xy 396.422751 -131.27684) (xy 396.492522 -131.191629) (xy 396.568259 -131.111674) (xy 396.649568 -131.037393)
			(xy 396.736025 -130.969173) (xy 396.827179 -130.907368) (xy 396.922556 -130.852303) (xy 397.021657 -130.804263)
			(xy 397.123966 -130.763499) (xy 397.22895 -130.730224) (xy 397.336061 -130.704611) (xy 397.444741 -130.686794)
			(xy 397.554424 -130.676865) (xy 397.664537 -130.674877) (xy 397.774507 -130.680839) (xy 397.88376 -130.694721)
			(xy 397.991726 -130.716451) (xy 398.097843 -130.745914) (xy 398.201557 -130.782957) (xy 398.302328 -130.827388)
			(xy 398.39963 -130.878975) (xy 398.492956 -130.937447) (xy 398.581819 -131.002502) (xy 398.665757 -131.0738)
			(xy 398.744332 -131.150968) (xy 398.817133 -131.233605) (xy 398.883781 -131.321279) (xy 398.94393 -131.413535)
			(xy 398.997264 -131.50989) (xy 399.043507 -131.609842) (xy 399.082417 -131.71287) (xy 399.113791 -131.818438)
			(xy 399.137466 -131.925994) (xy 399.153318 -132.034978) (xy 399.161265 -132.144822) (xy 399.161762 -132.199888)
			(xy 399.161265 -132.254954) (xy 399.153318 -132.364798) (xy 399.137466 -132.473782) (xy 399.113791 -132.581338)
			(xy 399.082417 -132.686906) (xy 399.043507 -132.789934) (xy 398.997264 -132.889886) (xy 398.94393 -132.986241)
			(xy 398.883781 -133.078497) (xy 398.817133 -133.166171) (xy 398.744332 -133.248808) (xy 398.665757 -133.325976)
			(xy 398.581819 -133.397274) (xy 398.492956 -133.462329) (xy 398.39963 -133.520801) (xy 398.302328 -133.572388)
			(xy 398.201557 -133.616819) (xy 398.097843 -133.653862) (xy 397.991726 -133.683325) (xy 397.88376 -133.705055)
			(xy 397.774507 -133.718937) (xy 397.664537 -133.724899) (xy 397.554424 -133.722911) (xy 397.444741 -133.712982)
			(xy 397.336061 -133.695165) (xy 397.22895 -133.669552) (xy 397.123966 -133.636277) (xy 397.021657 -133.595513)
			(xy 396.922556 -133.547473) (xy 396.827179 -133.492408) (xy 396.736025 -133.430603) (xy 396.649568 -133.362383)
			(xy 396.568259 -133.288102) (xy 396.492522 -133.208147) (xy 396.422751 -133.122936) (xy 396.359312 -133.032912)
			(xy 396.302533 -132.938545) (xy 396.252712 -132.840328) (xy 396.210108 -132.738771) (xy 396.174943 -132.634405)
			(xy 396.1474 -132.527774) (xy 396.127624 -132.419433) (xy 396.115716 -132.309947) (xy 396.111741 -132.199888)
			(xy 379.603762 -132.199888) (xy 379.603265 -132.254954) (xy 379.595318 -132.364798) (xy 379.579466 -132.473782)
			(xy 379.555791 -132.581338) (xy 379.524417 -132.686906) (xy 379.485507 -132.789934) (xy 379.439264 -132.889886)
			(xy 379.38593 -132.986241) (xy 379.325781 -133.078497) (xy 379.259133 -133.166171) (xy 379.186332 -133.248808)
			(xy 379.107757 -133.325976) (xy 379.023819 -133.397274) (xy 378.934956 -133.462329) (xy 378.84163 -133.520801)
			(xy 378.744328 -133.572388) (xy 378.643557 -133.616819) (xy 378.539843 -133.653862) (xy 378.433726 -133.683325)
			(xy 378.32576 -133.705055) (xy 378.216507 -133.718937) (xy 378.106537 -133.724899) (xy 377.996424 -133.722911)
			(xy 377.886741 -133.712982) (xy 377.778061 -133.695165) (xy 377.67095 -133.669552) (xy 377.565966 -133.636277)
			(xy 377.463657 -133.595513) (xy 377.364556 -133.547473) (xy 377.269179 -133.492408) (xy 377.178025 -133.430603)
			(xy 377.091568 -133.362383) (xy 377.010259 -133.288102) (xy 376.934522 -133.208147) (xy 376.864751 -133.122936)
			(xy 376.801312 -133.032912) (xy 376.744533 -132.938545) (xy 376.694712 -132.840328) (xy 376.652108 -132.738771)
			(xy 376.616943 -132.634405) (xy 376.5894 -132.527774) (xy 376.569624 -132.419433) (xy 376.557716 -132.309947)
			(xy 376.553741 -132.199888) (xy 352.515932 -132.199888) (xy 352.515932 -134.881366) (xy 352.516448 -134.891942)
			(xy 352.524971 -134.911297) (xy 352.540609 -134.925534) (xy 352.550476 -134.929372) (xy 352.590802 -134.943408)
			(xy 352.668804 -134.978159) (xy 352.743117 -135.020224) (xy 352.813057 -135.069217) (xy 352.87798 -135.124686)
			(xy 352.93729 -135.186121) (xy 352.990439 -135.252958) (xy 353.036938 -135.324579) (xy 353.076361 -135.400327)
			(xy 353.108343 -135.479504) (xy 353.132591 -135.561382) (xy 353.148881 -135.645206) (xy 353.157064 -135.730206)
			(xy 353.157064 -135.815598) (xy 353.148881 -135.900598) (xy 353.13259 -135.984422) (xy 353.108342 -136.066299)
			(xy 353.076359 -136.145476) (xy 353.036936 -136.221224) (xy 352.990436 -136.292846) (xy 352.937287 -136.359681)
			(xy 352.877978 -136.421117) (xy 352.813054 -136.476586) (xy 352.743114 -136.525578) (xy 352.668801 -136.567643)
			(xy 352.590799 -136.602393) (xy 352.550476 -136.61644) (xy 352.534982 -136.621774) (xy 352.515932 -136.64819)
			(xy 352.515932 -139.961366) (xy 352.516448 -139.971942) (xy 352.524971 -139.991297) (xy 352.540609 -140.005534)
			(xy 352.550476 -140.009372) (xy 352.590802 -140.023408) (xy 352.668804 -140.058159) (xy 352.743117 -140.100224)
			(xy 352.813057 -140.149217) (xy 352.87798 -140.204686) (xy 352.93729 -140.266121) (xy 352.990439 -140.332958)
			(xy 353.036938 -140.404579) (xy 353.076361 -140.480327) (xy 353.108343 -140.559504) (xy 353.132591 -140.641382)
			(xy 353.148881 -140.725206) (xy 353.157064 -140.810206) (xy 353.157064 -140.895598) (xy 353.148881 -140.980598)
			(xy 353.13259 -141.064422) (xy 353.108342 -141.146299) (xy 353.076359 -141.225476) (xy 353.036936 -141.301224)
			(xy 352.990436 -141.372846) (xy 352.937287 -141.439681) (xy 352.877978 -141.501117) (xy 352.813054 -141.556586)
			(xy 352.743114 -141.605578) (xy 352.668801 -141.647643) (xy 352.590799 -141.682393) (xy 352.550476 -141.69644)
			(xy 352.534982 -141.701774) (xy 352.515932 -141.72819) (xy 352.515932 -145.041366) (xy 352.516448 -145.051942)
			(xy 352.524971 -145.071297) (xy 352.540609 -145.085534) (xy 352.550476 -145.089372) (xy 352.590802 -145.103408)
			(xy 352.668804 -145.138159) (xy 352.743117 -145.180224) (xy 352.813057 -145.229217) (xy 352.87798 -145.284686)
			(xy 352.93729 -145.346121) (xy 352.990439 -145.412958) (xy 353.036938 -145.484579) (xy 353.076361 -145.560327)
			(xy 353.108343 -145.639504) (xy 353.132591 -145.721382) (xy 353.148881 -145.805206) (xy 353.157064 -145.890206)
			(xy 353.157064 -145.975598) (xy 353.148881 -146.060598) (xy 353.13259 -146.144422) (xy 353.108342 -146.226299)
			(xy 353.076359 -146.305476) (xy 353.036936 -146.381224) (xy 352.990436 -146.452846) (xy 352.937287 -146.519681)
			(xy 352.877978 -146.581117) (xy 352.813054 -146.636586) (xy 352.743114 -146.685578) (xy 352.668801 -146.727643)
			(xy 352.590799 -146.762393) (xy 352.550476 -146.77644) (xy 352.534982 -146.781774) (xy 352.515932 -146.80819)
			(xy 352.515932 -147.500086) (xy 354.864924 -147.500086) (xy 354.864924 -142.500096) (xy 354.865419 -142.399255)
			(xy 354.873337 -142.197728) (xy 354.889161 -141.996668) (xy 354.912866 -141.796384) (xy 354.944416 -141.597185)
			(xy 354.983762 -141.399378) (xy 355.030844 -141.203269) (xy 355.085589 -141.009159) (xy 355.147912 -140.817348)
			(xy 355.217717 -140.628131) (xy 355.294898 -140.441802) (xy 355.379334 -140.258645) (xy 355.470896 -140.078945)
			(xy 355.569442 -139.902979) (xy 355.67482 -139.731016) (xy 355.786869 -139.563324) (xy 355.905415 -139.40016)
			(xy 356.030275 -139.241775) (xy 356.161257 -139.088415) (xy 356.298159 -138.940315) (xy 356.440769 -138.797705)
			(xy 356.588869 -138.660803) (xy 356.742229 -138.529821) (xy 356.900614 -138.404961) (xy 357.063778 -138.286415)
			(xy 357.23147 -138.174366) (xy 357.403433 -138.068988) (xy 357.579399 -137.970442) (xy 357.759099 -137.87888)
			(xy 357.942256 -137.794444) (xy 358.128585 -137.717263) (xy 358.317802 -137.647458) (xy 358.509613 -137.585135)
			(xy 358.703723 -137.53039) (xy 358.899832 -137.483308) (xy 359.097639 -137.443962) (xy 359.296838 -137.412412)
			(xy 359.497122 -137.388707) (xy 359.698182 -137.372883) (xy 359.899709 -137.364965) (xy 360.101391 -137.364965)
			(xy 360.302918 -137.372883) (xy 360.503978 -137.388707) (xy 360.704262 -137.412412) (xy 360.903461 -137.443962)
			(xy 361.101268 -137.483308) (xy 361.297377 -137.53039) (xy 361.491487 -137.585135) (xy 361.683298 -137.647458)
			(xy 361.872515 -137.717263) (xy 362.058844 -137.794444) (xy 362.242001 -137.87888) (xy 362.421701 -137.970442)
			(xy 362.597667 -138.068988) (xy 362.76963 -138.174366) (xy 362.937322 -138.286415) (xy 363.100486 -138.404961)
			(xy 363.258871 -138.529821) (xy 363.412231 -138.660803) (xy 363.560331 -138.797705) (xy 363.702941 -138.940315)
			(xy 363.839843 -139.088415) (xy 363.970825 -139.241775) (xy 364.095685 -139.40016) (xy 364.214231 -139.563324)
			(xy 364.305556 -139.7) (xy 377.061486 -139.7) (xy 377.065468 -139.610072) (xy 377.077382 -139.520848)
			(xy 377.097135 -139.433026) (xy 377.124572 -139.347293) (xy 377.159479 -139.264321) (xy 377.201583 -139.184758)
			(xy 377.250553 -139.109228) (xy 377.306008 -139.038322) (xy 377.367512 -138.972594) (xy 377.434584 -138.912559)
			(xy 377.5067 -138.858687) (xy 377.583295 -138.811399) (xy 377.663769 -138.771066) (xy 377.747493 -138.738003)
			(xy 377.833812 -138.712469) (xy 377.92205 -138.694664) (xy 378.011515 -138.684726) (xy 378.10151 -138.682735)
			(xy 378.191327 -138.688705) (xy 378.280266 -138.70259) (xy 378.36763 -138.724281) (xy 378.452735 -138.753608)
			(xy 378.534914 -138.790342) (xy 378.613526 -138.834196) (xy 378.687954 -138.884825) (xy 378.757616 -138.941835)
			(xy 378.821967 -139.004778) (xy 378.880504 -139.073162) (xy 378.932767 -139.146452) (xy 378.978349 -139.224074)
			(xy 379.016892 -139.305421) (xy 379.048095 -139.389856) (xy 379.071713 -139.476718) (xy 379.087562 -139.565328)
			(xy 379.095518 -139.654992) (xy 379.096016 -139.7) (xy 396.619486 -139.7) (xy 396.623468 -139.610072)
			(xy 396.635382 -139.520848) (xy 396.655135 -139.433026) (xy 396.682572 -139.347293) (xy 396.717479 -139.264321)
			(xy 396.759583 -139.184758) (xy 396.808553 -139.109228) (xy 396.864008 -139.038322) (xy 396.925512 -138.972594)
			(xy 396.992584 -138.912559) (xy 397.0647 -138.858687) (xy 397.141295 -138.811399) (xy 397.221769 -138.771066)
			(xy 397.305493 -138.738003) (xy 397.391812 -138.712469) (xy 397.48005 -138.694664) (xy 397.569515 -138.684726)
			(xy 397.65951 -138.682735) (xy 397.749327 -138.688705) (xy 397.838266 -138.70259) (xy 397.92563 -138.724281)
			(xy 398.010735 -138.753608) (xy 398.092914 -138.790342) (xy 398.171526 -138.834196) (xy 398.245954 -138.884825)
			(xy 398.315616 -138.941835) (xy 398.379967 -139.004778) (xy 398.438504 -139.073162) (xy 398.490767 -139.146452)
			(xy 398.536349 -139.224074) (xy 398.574892 -139.305421) (xy 398.606095 -139.389856) (xy 398.629713 -139.476718)
			(xy 398.645562 -139.565328) (xy 398.653518 -139.654992) (xy 398.654016 -139.7) (xy 398.653518 -139.745008)
			(xy 398.645562 -139.834672) (xy 398.629713 -139.923282) (xy 398.606095 -140.010144) (xy 398.574892 -140.094579)
			(xy 398.536349 -140.175926) (xy 398.490767 -140.253548) (xy 398.438504 -140.326838) (xy 398.379967 -140.395222)
			(xy 398.315616 -140.458165) (xy 398.245954 -140.515175) (xy 398.171526 -140.565804) (xy 398.092914 -140.609658)
			(xy 398.010735 -140.646392) (xy 397.92563 -140.675719) (xy 397.838266 -140.69741) (xy 397.749327 -140.711295)
			(xy 397.65951 -140.717265) (xy 397.569515 -140.715274) (xy 397.48005 -140.705336) (xy 397.391812 -140.687531)
			(xy 397.305493 -140.661997) (xy 397.221769 -140.628934) (xy 397.141295 -140.588601) (xy 397.0647 -140.541313)
			(xy 396.992584 -140.487441) (xy 396.925512 -140.427406) (xy 396.864008 -140.361678) (xy 396.808553 -140.290772)
			(xy 396.759583 -140.215242) (xy 396.717479 -140.135679) (xy 396.682572 -140.052707) (xy 396.655135 -139.966974)
			(xy 396.635382 -139.879152) (xy 396.623468 -139.789928) (xy 396.619486 -139.7) (xy 379.096016 -139.7)
			(xy 379.095518 -139.745008) (xy 379.087562 -139.834672) (xy 379.071713 -139.923282) (xy 379.048095 -140.010144)
			(xy 379.016892 -140.094579) (xy 378.978349 -140.175926) (xy 378.932767 -140.253548) (xy 378.880504 -140.326838)
			(xy 378.821967 -140.395222) (xy 378.757616 -140.458165) (xy 378.687954 -140.515175) (xy 378.613526 -140.565804)
			(xy 378.534914 -140.609658) (xy 378.452735 -140.646392) (xy 378.36763 -140.675719) (xy 378.280266 -140.69741)
			(xy 378.191327 -140.711295) (xy 378.10151 -140.717265) (xy 378.011515 -140.715274) (xy 377.92205 -140.705336)
			(xy 377.833812 -140.687531) (xy 377.747493 -140.661997) (xy 377.663769 -140.628934) (xy 377.583295 -140.588601)
			(xy 377.5067 -140.541313) (xy 377.434584 -140.487441) (xy 377.367512 -140.427406) (xy 377.306008 -140.361678)
			(xy 377.250553 -140.290772) (xy 377.201583 -140.215242) (xy 377.159479 -140.135679) (xy 377.124572 -140.052707)
			(xy 377.097135 -139.966974) (xy 377.077382 -139.879152) (xy 377.065468 -139.789928) (xy 377.061486 -139.7)
			(xy 364.305556 -139.7) (xy 364.32628 -139.731016) (xy 364.431658 -139.902979) (xy 364.530204 -140.078945)
			(xy 364.621766 -140.258645) (xy 364.706202 -140.441802) (xy 364.783383 -140.628131) (xy 364.853188 -140.817348)
			(xy 364.915511 -141.009159) (xy 364.970256 -141.203269) (xy 365.017338 -141.399378) (xy 365.056684 -141.597185)
			(xy 365.088234 -141.796384) (xy 365.111939 -141.996668) (xy 365.127763 -142.197728) (xy 365.135681 -142.399255)
			(xy 365.136176 -142.500096) (xy 365.136176 -147.500086) (xy 365.135681 -147.600927) (xy 365.127763 -147.802454)
			(xy 365.111939 -148.003514) (xy 365.088234 -148.203798) (xy 365.056684 -148.402997) (xy 365.017338 -148.600804)
			(xy 364.970256 -148.796913) (xy 364.915511 -148.991023) (xy 364.853188 -149.182834) (xy 364.783383 -149.372051)
			(xy 364.706202 -149.55838) (xy 364.621766 -149.741537) (xy 364.530204 -149.921237) (xy 364.431658 -150.097203)
			(xy 364.32628 -150.269166) (xy 364.214231 -150.436858) (xy 364.095685 -150.600022) (xy 363.970825 -150.758407)
			(xy 363.839843 -150.911767) (xy 363.702941 -151.059867) (xy 363.560331 -151.202477) (xy 363.412231 -151.339379)
			(xy 363.258871 -151.470361) (xy 363.100486 -151.595221) (xy 362.937322 -151.713767) (xy 362.76963 -151.825816)
			(xy 362.597667 -151.931194) (xy 362.421701 -152.02974) (xy 362.242001 -152.121302) (xy 362.058844 -152.205738)
			(xy 361.872515 -152.282919) (xy 361.683298 -152.352724) (xy 361.491487 -152.415047) (xy 361.297377 -152.469792)
			(xy 361.101268 -152.516874) (xy 360.903461 -152.55622) (xy 360.704262 -152.58777) (xy 360.503978 -152.611475)
			(xy 360.302918 -152.627299) (xy 360.101391 -152.635217) (xy 359.899709 -152.635217) (xy 359.698182 -152.627299)
			(xy 359.497122 -152.611475) (xy 359.296838 -152.58777) (xy 359.097639 -152.55622) (xy 358.899832 -152.516874)
			(xy 358.703723 -152.469792) (xy 358.509613 -152.415047) (xy 358.317802 -152.352724) (xy 358.128585 -152.282919)
			(xy 357.942256 -152.205738) (xy 357.759099 -152.121302) (xy 357.579399 -152.02974) (xy 357.403433 -151.931194)
			(xy 357.23147 -151.825816) (xy 357.063778 -151.713767) (xy 356.900614 -151.595221) (xy 356.742229 -151.470361)
			(xy 356.588869 -151.339379) (xy 356.440769 -151.202477) (xy 356.298159 -151.059867) (xy 356.161257 -150.911767)
			(xy 356.030275 -150.758407) (xy 355.905415 -150.600022) (xy 355.786869 -150.436858) (xy 355.67482 -150.269166)
			(xy 355.569442 -150.097203) (xy 355.470896 -149.921237) (xy 355.379334 -149.741537) (xy 355.294898 -149.55838)
			(xy 355.217717 -149.372051) (xy 355.147912 -149.182834) (xy 355.085589 -148.991023) (xy 355.030844 -148.796913)
			(xy 354.983762 -148.600804) (xy 354.944416 -148.402997) (xy 354.912866 -148.203798) (xy 354.889161 -148.003514)
			(xy 354.873337 -147.802454) (xy 354.865419 -147.600927) (xy 354.864924 -147.500086) (xy 352.515932 -147.500086)
			(xy 352.515932 -150.121366) (xy 352.516448 -150.131942) (xy 352.524971 -150.151297) (xy 352.540609 -150.165534)
			(xy 352.550476 -150.169372) (xy 352.590802 -150.183408) (xy 352.668804 -150.218159) (xy 352.743117 -150.260224)
			(xy 352.813057 -150.309217) (xy 352.87798 -150.364686) (xy 352.93729 -150.426121) (xy 352.990439 -150.492958)
			(xy 353.036938 -150.564579) (xy 353.076361 -150.640327) (xy 353.108343 -150.719504) (xy 353.132591 -150.801382)
			(xy 353.148881 -150.885206) (xy 353.157064 -150.970206) (xy 353.157064 -151.055598) (xy 353.148881 -151.140598)
			(xy 353.13259 -151.224422) (xy 353.108342 -151.306299) (xy 353.076359 -151.385476) (xy 353.036936 -151.461224)
			(xy 352.990436 -151.532846) (xy 352.937287 -151.599681) (xy 352.877978 -151.661117) (xy 352.813054 -151.716586)
			(xy 352.743114 -151.765578) (xy 352.668801 -151.807643) (xy 352.590799 -151.842393) (xy 352.550476 -151.85644)
			(xy 352.534982 -151.861774) (xy 352.515932 -151.88819) (xy 352.515932 -153.299922) (xy 352.516443 -153.390713)
			(xy 352.524716 -153.572106) (xy 352.541243 -153.752934) (xy 352.56599 -153.932822) (xy 352.598906 -154.111396)
			(xy 352.639923 -154.288284) (xy 352.688955 -154.463121) (xy 352.7459 -154.635542) (xy 352.777806 -154.720544)
			(xy 352.7825 -154.731157) (xy 352.799467 -154.746955) (xy 352.821633 -154.753745) (xy 352.833178 -154.752548)
			(xy 352.866749 -154.747691) (xy 352.934387 -154.742476) (xy 352.968306 -154.742134) (xy 352.969322 -154.742134)
			(xy 353.010424 -154.742595) (xy 353.092277 -154.750182) (xy 353.17308 -154.765289) (xy 353.252145 -154.787788)
			(xy 353.328797 -154.817485) (xy 353.402381 -154.854129) (xy 353.472271 -154.897406) (xy 353.537869 -154.946947)
			(xy 353.598616 -155.002329) (xy 353.653994 -155.06308) (xy 353.70353 -155.128682) (xy 353.746802 -155.198575)
			(xy 353.783441 -155.272162) (xy 353.813133 -155.348816) (xy 353.835625 -155.427882) (xy 353.850727 -155.508687)
			(xy 353.858308 -155.59054) (xy 353.85883 -155.631642) (xy 353.858362 -155.672957) (xy 353.850699 -155.755231)
			(xy 353.835433 -155.836439) (xy 353.812698 -155.915879) (xy 353.782688 -155.992867) (xy 353.745663 -156.066738)
			(xy 353.72421 -156.10205) (xy 353.71659 -156.128974) (xy 353.717062 -156.139216) (xy 353.725064 -156.158075)
			(xy 353.732084 -156.16555) (xy 353.794273 -156.224978) (xy 353.923053 -156.339046) (xy 354.056638 -156.447448)
			(xy 354.194778 -156.549982) (xy 354.337215 -156.646457) (xy 354.483684 -156.736693) (xy 354.633912 -156.820522)
			(xy 354.787619 -156.897789) (xy 354.944518 -156.968347) (xy 355.104317 -157.032067) (xy 355.266717 -157.08883)
			(xy 355.431416 -157.138528) (xy 355.514656 -157.160214) (xy 355.526067 -157.162509) (xy 355.548824 -157.157736)
			(xy 355.56719 -157.143476) (xy 355.572822 -157.13329) (xy 355.591468 -157.096463) (xy 355.634624 -157.026091)
			(xy 355.684114 -156.96002) (xy 355.739513 -156.898817) (xy 355.800344 -156.843011) (xy 355.866083 -156.79308)
			(xy 355.936165 -156.749455) (xy 356.009988 -156.71251) (xy 356.086915 -156.682563) (xy 356.166287 -156.659872)
			(xy 356.247419 -156.644631) (xy 356.329614 -156.636973) (xy 356.37089 -156.636466) (xy 356.414138 -156.636976)
			(xy 356.500225 -156.645364) (xy 356.585091 -156.662071) (xy 356.667935 -156.686939) (xy 356.747972 -156.719733)
			(xy 356.824447 -156.760143) (xy 356.896636 -156.807788) (xy 356.963859 -156.862218) (xy 357.025479 -156.922917)
			(xy 357.080914 -156.989312) (xy 357.129641 -157.060776) (xy 357.171199 -157.136634) (xy 357.205195 -157.216168)
			(xy 357.218742 -157.257242) (xy 357.222252 -157.266862) (xy 357.235506 -157.282449) (xy 357.253778 -157.291658)
			(xy 357.263954 -157.292802) (xy 357.350776 -157.298975) (xy 357.523824 -157.317909) (xy 357.695888 -157.344324)
			(xy 357.866646 -157.378171) (xy 358.035777 -157.419386) (xy 358.202963 -157.467892) (xy 358.36789 -157.523598)
			(xy 358.530247 -157.586399) (xy 358.689731 -157.656177) (xy 358.846041 -157.7328) (xy 358.998883 -157.816126)
			(xy 359.147971 -157.905997) (xy 359.22077 -157.95371) (xy 359.289013 -157.999499) (xy 359.422125 -158.095911)
			(xy 359.551179 -158.197693) (xy 359.675957 -158.304672) (xy 359.73639 -158.360364) (xy 359.804033 -158.424058)
			(xy 359.934042 -158.556823) (xy 360.057773 -158.695458) (xy 360.174962 -158.839665) (xy 360.285357 -158.989136)
			(xy 360.388724 -159.143553) (xy 360.48484 -159.302583) (xy 360.529632 -159.383984) (xy 360.55333 -159.427998)
			(xy 360.598801 -159.517035) (xy 360.620564 -159.562038) (xy 360.623104 -159.567372) (xy 360.652644 -159.63011)
			(xy 371.481871 -159.63011) (xy 371.485828 -159.520564) (xy 371.49768 -159.411589) (xy 371.517364 -159.303754)
			(xy 371.544778 -159.19762) (xy 371.579779 -159.09374) (xy 371.622185 -158.992657) (xy 371.671774 -158.894898)
			(xy 371.728287 -158.800971) (xy 371.791431 -158.711368) (xy 371.860876 -158.626554) (xy 371.93626 -158.546972)
			(xy 372.01719 -158.473037) (xy 372.103244 -158.405135) (xy 372.193973 -158.343619) (xy 372.288904 -158.288811)
			(xy 372.387543 -158.240995) (xy 372.489375 -158.200421) (xy 372.593869 -158.167301) (xy 372.700481 -158.141808)
			(xy 372.808654 -158.124074) (xy 372.917825 -158.114191) (xy 373.027425 -158.112212) (xy 373.136881 -158.118147)
			(xy 373.245625 -158.131964) (xy 373.353087 -158.153592) (xy 373.458709 -158.182918) (xy 373.561939 -158.219789)
			(xy 373.66224 -158.264012) (xy 373.759089 -158.315358) (xy 373.851979 -158.373558) (xy 373.940428 -158.438309)
			(xy 374.023975 -158.509274) (xy 374.102182 -158.586083) (xy 374.174644 -158.668334) (xy 374.240982 -158.7556)
			(xy 374.300849 -158.847424) (xy 374.353935 -158.94333) (xy 374.399962 -159.042816) (xy 374.438691 -159.145364)
			(xy 374.469919 -159.250439) (xy 374.493483 -159.357494) (xy 374.509262 -159.46597) (xy 374.517171 -159.575301)
			(xy 374.517666 -159.63011) (xy 374.517171 -159.684919) (xy 374.509262 -159.79425) (xy 374.493483 -159.902726)
			(xy 374.469919 -160.009781) (xy 374.438691 -160.114856) (xy 374.399962 -160.217404) (xy 374.353935 -160.31689)
			(xy 374.300849 -160.412796) (xy 374.240982 -160.50462) (xy 374.174644 -160.591886) (xy 374.102182 -160.674137)
			(xy 374.023975 -160.750946) (xy 373.940428 -160.821911) (xy 373.851979 -160.886662) (xy 373.759089 -160.944862)
			(xy 373.66224 -160.996208) (xy 373.561939 -161.040431) (xy 373.458709 -161.077302) (xy 373.353087 -161.106628)
			(xy 373.245625 -161.128256) (xy 373.136881 -161.142073) (xy 373.027425 -161.148008) (xy 372.917825 -161.146029)
			(xy 372.808654 -161.136146) (xy 372.700481 -161.118412) (xy 372.593869 -161.092919) (xy 372.489375 -161.059799)
			(xy 372.387543 -161.019225) (xy 372.288904 -160.971409) (xy 372.193973 -160.916601) (xy 372.103244 -160.855085)
			(xy 372.01719 -160.787183) (xy 371.93626 -160.713248) (xy 371.860876 -160.633666) (xy 371.791431 -160.548852)
			(xy 371.728287 -160.459249) (xy 371.671774 -160.365322) (xy 371.622185 -160.267563) (xy 371.579779 -160.16648)
			(xy 371.544778 -160.0626) (xy 371.517364 -159.956466) (xy 371.49768 -159.848631) (xy 371.485828 -159.739656)
			(xy 371.481871 -159.63011) (xy 360.652644 -159.63011) (xy 360.664407 -159.655093) (xy 360.739524 -159.833866)
			(xy 360.805921 -160.016057) (xy 360.863444 -160.201241) (xy 360.911958 -160.388987) (xy 360.932222 -160.483804)
			(xy 360.93461 -160.493151) (xy 360.945243 -160.509229) (xy 360.961045 -160.520268) (xy 360.970322 -160.52292)
			(xy 361.011571 -160.533226) (xy 361.092046 -160.560675) (xy 361.169536 -160.595675) (xy 361.243335 -160.637907)
			(xy 361.312768 -160.686986) (xy 361.377204 -160.742464) (xy 361.436053 -160.803836) (xy 361.48878 -160.870541)
			(xy 361.534904 -160.941971) (xy 361.574005 -161.017476) (xy 361.605724 -161.096366) (xy 361.629774 -161.177921)
			(xy 361.645935 -161.261399) (xy 361.65406 -161.346038) (xy 361.654598 -161.388552) (xy 361.654097 -161.431124)
			(xy 361.645958 -161.515877) (xy 361.629759 -161.599465) (xy 361.605649 -161.681124) (xy 361.573848 -161.760106)
			(xy 361.534647 -161.835688) (xy 361.488405 -161.90718) (xy 361.435544 -161.973926) (xy 361.376549 -162.035318)
			(xy 361.311958 -162.090793) (xy 361.242363 -162.139843) (xy 361.168401 -162.182021) (xy 361.090747 -162.216939)
			(xy 361.050586 -162.23107) (xy 361.040761 -162.234968) (xy 361.02518 -162.249218) (xy 361.016625 -162.268521)
			(xy 361.016219 -162.275866) (xy 385.708125 -162.275866) (xy 385.716065 -162.167119) (xy 385.731923 -162.059242)
			(xy 385.755612 -161.95281) (xy 385.787008 -161.848391) (xy 385.825942 -161.746543) (xy 385.872206 -161.647808)
			(xy 385.925554 -161.552714) (xy 385.985702 -161.461768) (xy 386.052327 -161.375455) (xy 386.125075 -161.294235)
			(xy 386.203558 -161.218542) (xy 386.287357 -161.14878) (xy 386.376024 -161.085322) (xy 386.469087 -161.028504)
			(xy 386.566049 -160.978632) (xy 386.666393 -160.93597) (xy 386.769583 -160.900747) (xy 386.87507 -160.87315)
			(xy 386.982289 -160.853327) (xy 387.090669 -160.841383) (xy 387.199632 -160.837382) (xy 387.308596 -160.841346)
			(xy 387.41698 -160.853253) (xy 387.524206 -160.873039) (xy 387.629702 -160.9006) (xy 387.732904 -160.935789)
			(xy 387.833263 -160.978416) (xy 387.930242 -161.028256) (xy 388.023324 -161.085041) (xy 388.112013 -161.14847)
			(xy 388.195836 -161.218203) (xy 388.274344 -161.293869) (xy 388.34712 -161.375064) (xy 388.413775 -161.461355)
			(xy 388.473953 -161.55228) (xy 388.527334 -161.647356) (xy 388.573632 -161.746075) (xy 388.6126 -161.84791)
			(xy 388.644031 -161.952318) (xy 388.667757 -162.058742) (xy 388.683651 -162.166614) (xy 388.691629 -162.275358)
			(xy 388.692136 -162.329876) (xy 388.691647 -162.384394) (xy 388.683707 -162.493141) (xy 388.667849 -162.601018)
			(xy 388.64416 -162.70745) (xy 388.612764 -162.811869) (xy 388.57383 -162.913717) (xy 388.527566 -163.012452)
			(xy 388.474218 -163.107546) (xy 388.41407 -163.198492) (xy 388.347445 -163.284805) (xy 388.274697 -163.366025)
			(xy 388.196214 -163.441718) (xy 388.112415 -163.51148) (xy 388.023748 -163.574938) (xy 387.930685 -163.631756)
			(xy 387.833723 -163.681628) (xy 387.733379 -163.72429) (xy 387.630189 -163.759513) (xy 387.524702 -163.78711)
			(xy 387.417483 -163.806933) (xy 387.309103 -163.818877) (xy 387.20014 -163.822878) (xy 387.091176 -163.818914)
			(xy 386.982792 -163.807007) (xy 386.875566 -163.787221) (xy 386.77007 -163.75966) (xy 386.666868 -163.724471)
			(xy 386.566509 -163.681844) (xy 386.46953 -163.632004) (xy 386.376448 -163.575219) (xy 386.287759 -163.51179)
			(xy 386.203936 -163.442057) (xy 386.125428 -163.366391) (xy 386.052652 -163.285196) (xy 385.985997 -163.198905)
			(xy 385.925819 -163.10798) (xy 385.872438 -163.012904) (xy 385.82614 -162.914185) (xy 385.787172 -162.81235)
			(xy 385.755741 -162.707942) (xy 385.732015 -162.601518) (xy 385.716121 -162.493646) (xy 385.708143 -162.384902)
			(xy 385.708125 -162.275866) (xy 361.016219 -162.275866) (xy 361.016042 -162.279076) (xy 361.016042 -165.578028)
			(xy 361.01657 -165.588595) (xy 361.025106 -165.607928) (xy 361.040744 -165.622143) (xy 361.050586 -165.626034)
			(xy 361.090748 -165.640167) (xy 361.168412 -165.675071) (xy 361.242386 -165.717238) (xy 361.31199 -165.766281)
			(xy 361.376589 -165.821751) (xy 361.435591 -165.883142) (xy 361.488456 -165.94989) (xy 361.534699 -166.021385)
			(xy 361.573898 -166.096973) (xy 361.605694 -166.17596) (xy 361.629795 -166.257625) (xy 361.645982 -166.34122)
			(xy 361.654105 -166.425978) (xy 361.654598 -166.468552) (xy 361.654065 -166.512125) (xy 361.645539 -166.598852)
			(xy 361.628575 -166.684331) (xy 361.603334 -166.767741) (xy 361.570059 -166.848284) (xy 361.529069 -166.925187)
			(xy 361.480756 -166.997715) (xy 361.425583 -167.06517) (xy 361.364079 -167.126909) (xy 361.296833 -167.182338)
			(xy 361.22449 -167.230927) (xy 361.147743 -167.272209) (xy 361.107736 -167.28948) (xy 361.076494 -167.33647)
			(xy 361.077256 -167.34536) (xy 361.09275 -167.428672) (xy 361.110489 -167.515171) (xy 361.152661 -167.686657)
			(xy 361.202391 -167.856105) (xy 361.259583 -168.023183) (xy 361.324123 -168.187561) (xy 361.395886 -168.348918)
			(xy 361.47473 -168.506935) (xy 361.5605 -168.661303) (xy 361.606338 -168.736772) (xy 361.612312 -168.745464)
			(xy 361.629635 -168.757454) (xy 361.650314 -168.761486) (xy 361.660694 -168.759632) (xy 361.75442 -168.73855)
			(xy 361.79379 -168.694608) (xy 361.799966 -168.644266) (xy 361.819647 -168.54476) (xy 361.847569 -168.447244)
			(xy 361.883535 -168.352401) (xy 361.927295 -168.260892) (xy 361.978544 -168.173357) (xy 362.036923 -168.090407)
			(xy 362.102024 -168.012621) (xy 362.173394 -167.940543) (xy 362.21162 -167.907208) (xy 362.219642 -167.899635)
			(xy 362.228862 -167.879619) (xy 362.2294 -167.8686) (xy 362.2294 -167.791384) (xy 362.228856 -167.780367)
			(xy 362.219633 -167.760357) (xy 362.21162 -167.752776) (xy 362.173997 -167.719952) (xy 362.103676 -167.649059)
			(xy 362.039418 -167.572629) (xy 361.981656 -167.491178) (xy 361.930781 -167.405257) (xy 361.887136 -167.315447)
			(xy 361.851018 -167.222355) (xy 361.822669 -167.12661) (xy 361.802282 -167.02886) (xy 361.789995 -166.929765)
			(xy 361.78589 -166.829996) (xy 361.789995 -166.730227) (xy 361.802283 -166.631133) (xy 361.822671 -166.533383)
			(xy 361.85102 -166.437638) (xy 361.887139 -166.344546) (xy 361.930784 -166.254736) (xy 361.98166 -166.168815)
			(xy 362.039423 -166.087365) (xy 362.103682 -166.010935) (xy 362.174002 -165.940043) (xy 362.21162 -165.907212)
			(xy 362.219643 -165.89964) (xy 362.228865 -165.879623) (xy 362.2294 -165.868604) (xy 362.2294 -165.791388)
			(xy 362.228857 -165.780371) (xy 362.219635 -165.760359) (xy 362.21162 -165.75278) (xy 362.175696 -165.721462)
			(xy 362.108321 -165.654045) (xy 362.046442 -165.581551) (xy 361.990439 -165.504427) (xy 361.940659 -165.423147)
			(xy 361.897406 -165.338214) (xy 361.86095 -165.250149) (xy 361.831512 -165.159497) (xy 361.809276 -165.066814)
			(xy 361.794378 -164.972674) (xy 361.78691 -164.877654) (xy 361.786424 -164.829998) (xy 361.786942 -164.77982)
			(xy 361.795228 -164.679807) (xy 361.811744 -164.58082) (xy 361.836377 -164.483534) (xy 361.868958 -164.388615)
			(xy 361.909266 -164.296709) (xy 361.957024 -164.208446) (xy 362.011906 -164.124427) (xy 362.073539 -164.045227)
			(xy 362.1415 -163.971386) (xy 362.215327 -163.903408) (xy 362.294514 -163.841759) (xy 362.378521 -163.786858)
			(xy 362.466774 -163.739081) (xy 362.55867 -163.698754) (xy 362.653583 -163.666152) (xy 362.750863 -163.641498)
			(xy 362.849847 -163.624961) (xy 362.949858 -163.616653) (xy 363.000036 -163.616132) (xy 363.047697 -163.616612)
			(xy 363.142723 -163.624113) (xy 363.236868 -163.639043) (xy 363.329552 -163.661309) (xy 363.420205 -163.690775)
			(xy 363.508268 -163.727259) (xy 363.593199 -163.770536) (xy 363.674475 -163.820339) (xy 363.751595 -163.876363)
			(xy 363.824085 -163.938262) (xy 363.891497 -164.005655) (xy 363.922818 -164.041582) (xy 363.93039 -164.049605)
			(xy 363.950407 -164.058822) (xy 363.961426 -164.059362) (xy 364.038642 -164.059362) (xy 364.049658 -164.058815)
			(xy 364.069668 -164.049593) (xy 364.07725 -164.041582) (xy 364.10856 -164.005644) (xy 364.175965 -163.938241)
			(xy 364.24845 -163.876333) (xy 364.325568 -163.820304) (xy 364.406845 -163.770496) (xy 364.491778 -163.727219)
			(xy 364.579845 -163.690738) (xy 364.670502 -163.661279) (xy 364.763191 -163.639023) (xy 364.857341 -163.624107)
			(xy 364.95237 -163.616623) (xy 365.000032 -163.616132) (xy 365.050198 -163.616651) (xy 365.150186 -163.624938)
			(xy 365.249149 -163.641453) (xy 365.346411 -163.666082) (xy 365.441307 -163.698658) (xy 365.533189 -163.738958)
			(xy 365.621429 -163.786708) (xy 365.705426 -163.84158) (xy 365.784605 -163.9032) (xy 365.858426 -163.971148)
			(xy 365.926385 -164.044959) (xy 365.988017 -164.124129) (xy 366.042901 -164.208118) (xy 366.090663 -164.296351)
			(xy 366.130977 -164.388227) (xy 366.163567 -164.483118) (xy 366.188211 -164.580376) (xy 366.20474 -164.679337)
			(xy 366.213041 -164.779324) (xy 366.213644 -164.82949) (xy 366.213644 -164.829998) (xy 366.213177 -164.877655)
			(xy 366.205703 -164.972675) (xy 366.190801 -165.066816) (xy 366.168562 -165.159499) (xy 366.139123 -165.250152)
			(xy 366.102666 -165.338218) (xy 366.059416 -165.423154) (xy 366.009638 -165.504436) (xy 365.953639 -165.581565)
			(xy 365.891765 -165.654065) (xy 365.824396 -165.721489) (xy 365.788448 -165.75278) (xy 365.780428 -165.760354)
			(xy 365.771209 -165.78037) (xy 365.770668 -165.791388) (xy 365.770668 -165.868604) (xy 365.771208 -165.879623)
			(xy 365.780424 -165.899641) (xy 365.788448 -165.907212) (xy 365.826878 -165.940716) (xy 365.898589 -166.013199)
			(xy 365.963965 -166.091445) (xy 366.022543 -166.174901) (xy 366.073912 -166.262978) (xy 366.096296 -166.308786)
			(xy 366.10136 -166.318177) (xy 366.117499 -166.332098) (xy 366.127538 -166.33571) (xy 366.199166 -166.3573)
			(xy 366.209432 -166.359843) (xy 366.230411 -166.357336) (xy 366.239806 -166.352474) (xy 366.285768 -166.325669)
			(xy 366.380871 -166.277934) (xy 366.479145 -166.237121) (xy 366.580085 -166.203441) (xy 366.683175 -166.177064)
			(xy 366.787887 -166.158126) (xy 366.893685 -166.146725) (xy 367.000028 -166.142918) (xy 367.106371 -166.146725)
			(xy 367.212169 -166.158126) (xy 367.316881 -166.177064) (xy 367.419971 -166.203441) (xy 367.520911 -166.237121)
			(xy 367.619185 -166.277934) (xy 367.714288 -166.325669) (xy 367.76025 -166.352474) (xy 367.769591 -166.3575)
			(xy 367.790635 -166.360005) (xy 367.80089 -166.3573) (xy 367.872518 -166.33571) (xy 367.882603 -166.332179)
			(xy 367.898768 -166.318234) (xy 367.90376 -166.308786) (xy 367.926137 -166.262975) (xy 367.977514 -166.174903)
			(xy 368.036098 -166.091451) (xy 368.101474 -166.013207) (xy 368.173183 -165.940722) (xy 368.211608 -165.907212)
			(xy 368.219633 -165.89964) (xy 368.228856 -165.879624) (xy 368.229388 -165.868604) (xy 368.229388 -165.791388)
			(xy 368.228845 -165.780371) (xy 368.219621 -165.760361) (xy 368.211608 -165.75278) (xy 368.175684 -165.721462)
			(xy 368.10831 -165.654045) (xy 368.046431 -165.58155) (xy 367.990429 -165.504426) (xy 367.940649 -165.423146)
			(xy 367.897398 -165.338213) (xy 367.860941 -165.250149) (xy 367.831504 -165.159496) (xy 367.809268 -165.066814)
			(xy 367.79437 -164.972673) (xy 367.786903 -164.877654) (xy 367.786412 -164.829998) (xy 367.78693 -164.77982)
			(xy 367.795216 -164.679807) (xy 367.811732 -164.580819) (xy 367.836365 -164.483533) (xy 367.868946 -164.388613)
			(xy 367.909253 -164.296707) (xy 367.957011 -164.208443) (xy 368.011894 -164.124424) (xy 368.073526 -164.045223)
			(xy 368.141488 -163.971381) (xy 368.215314 -163.903403) (xy 368.294501 -163.841753) (xy 368.378508 -163.786852)
			(xy 368.466761 -163.739074) (xy 368.558658 -163.698746) (xy 368.65357 -163.666143) (xy 368.750851 -163.641489)
			(xy 368.849835 -163.62495) (xy 368.949846 -163.616642) (xy 369.000024 -163.616132) (xy 369.047685 -163.616612)
			(xy 369.142711 -163.624112) (xy 369.236857 -163.639041) (xy 369.329542 -163.661306) (xy 369.420195 -163.690771)
			(xy 369.508259 -163.727254) (xy 369.593191 -163.770531) (xy 369.674468 -163.820334) (xy 369.751588 -163.876358)
			(xy 369.824079 -163.938256) (xy 369.891492 -164.005649) (xy 369.922806 -164.041582) (xy 369.930377 -164.049607)
			(xy 369.950394 -164.058829) (xy 369.961414 -164.059362) (xy 370.03863 -164.059362) (xy 370.049647 -164.058818)
			(xy 370.069661 -164.049599) (xy 370.077238 -164.041582) (xy 370.108548 -164.005644) (xy 370.175953 -163.93824)
			(xy 370.248438 -163.876332) (xy 370.325556 -163.820301) (xy 370.406832 -163.770493) (xy 370.491765 -163.727215)
			(xy 370.579832 -163.690733) (xy 370.67049 -163.661273) (xy 370.763179 -163.639016) (xy 370.857328 -163.624099)
			(xy 370.952358 -163.616615) (xy 371.00002 -163.616132) (xy 371.050186 -163.616651) (xy 371.150175 -163.624937)
			(xy 371.249139 -163.64145) (xy 371.346402 -163.666079) (xy 371.441298 -163.698655) (xy 371.533181 -163.738955)
			(xy 371.621423 -163.786704) (xy 371.70542 -163.841576) (xy 371.7846 -163.903196) (xy 371.858422 -163.971144)
			(xy 371.926381 -164.044955) (xy 371.988014 -164.124125) (xy 372.042899 -164.208114) (xy 372.090662 -164.296348)
			(xy 372.130976 -164.388225) (xy 372.163566 -164.483116) (xy 372.18821 -164.580375) (xy 372.20474 -164.679336)
			(xy 372.213041 -164.779324) (xy 372.213632 -164.82949) (xy 372.213632 -164.829998) (xy 372.213165 -164.877655)
			(xy 372.205691 -164.972675) (xy 372.190788 -165.066816) (xy 372.168549 -165.159498) (xy 372.13911 -165.250152)
			(xy 372.102653 -165.338217) (xy 372.059403 -165.423153) (xy 372.009624 -165.504435) (xy 371.953625 -165.581563)
			(xy 371.891751 -165.654062) (xy 371.824381 -165.721486) (xy 371.788436 -165.75278) (xy 371.780404 -165.760348)
			(xy 371.771169 -165.780366) (xy 371.770656 -165.791388) (xy 371.770656 -165.868604) (xy 371.771196 -165.879623)
			(xy 371.78041 -165.899643) (xy 371.788436 -165.907212) (xy 371.826061 -165.940035) (xy 371.896385 -166.010927)
			(xy 371.960646 -166.087357) (xy 372.018411 -166.168807) (xy 372.069289 -166.254728) (xy 372.112936 -166.344539)
			(xy 372.149057 -166.437632) (xy 372.177408 -166.533378) (xy 372.197796 -166.631129) (xy 372.210085 -166.730226)
			(xy 372.214191 -166.829996) (xy 372.210086 -166.929767) (xy 372.197798 -167.028863) (xy 372.17741 -167.126614)
			(xy 372.14906 -167.22236) (xy 372.112939 -167.315454) (xy 372.069293 -167.405265) (xy 372.018416 -167.491186)
			(xy 371.960651 -167.572637) (xy 371.89639 -167.649067) (xy 371.826067 -167.719959) (xy 371.788436 -167.752776)
			(xy 371.780404 -167.760344) (xy 371.771167 -167.780361) (xy 371.770656 -167.791384) (xy 371.770656 -167.8686)
			(xy 371.771195 -167.87962) (xy 371.780408 -167.899641) (xy 371.788436 -167.907208) (xy 371.824361 -167.938525)
			(xy 371.891739 -168.005941) (xy 371.953621 -168.078434) (xy 372.009627 -168.155558) (xy 372.05941 -168.236837)
			(xy 372.102665 -168.32177) (xy 372.139124 -168.409835) (xy 372.168563 -168.500488) (xy 372.190801 -168.593171)
			(xy 372.2057 -168.687313) (xy 372.21317 -168.782333) (xy 372.213632 -168.82999) (xy 372.213114 -168.880168)
			(xy 372.204829 -168.98018) (xy 372.188314 -169.079167) (xy 372.163681 -169.176452) (xy 372.1311 -169.271371)
			(xy 372.090793 -169.363275) (xy 372.043035 -169.451538) (xy 371.988152 -169.535556) (xy 371.926519 -169.614755)
			(xy 371.858557 -169.688594) (xy 371.78473 -169.75657) (xy 371.705543 -169.818218) (xy 371.621535 -169.873117)
			(xy 371.533282 -169.920892) (xy 371.441385 -169.961217) (xy 371.346472 -169.993816) (xy 371.249192 -170.018466)
			(xy 371.150208 -170.035) (xy 371.050197 -170.043305) (xy 371.00002 -170.043856) (xy 370.952359 -170.043378)
			(xy 370.857331 -170.035881) (xy 370.763183 -170.020955) (xy 370.670496 -169.998692) (xy 370.579841 -169.969229)
			(xy 370.491775 -169.932748) (xy 370.406841 -169.889473) (xy 370.325562 -169.839671) (xy 370.248439 -169.783648)
			(xy 370.175946 -169.72175) (xy 370.108531 -169.654358) (xy 370.077238 -169.618406) (xy 370.069669 -169.610375)
			(xy 370.049652 -169.601139) (xy 370.03863 -169.600626) (xy 369.961414 -169.600626) (xy 369.950395 -169.601164)
			(xy 369.930378 -169.610383) (xy 369.922806 -169.618406) (xy 369.891496 -169.654346) (xy 369.824093 -169.721753)
			(xy 369.751609 -169.783664) (xy 369.674491 -169.839698) (xy 369.593216 -169.88951) (xy 369.508283 -169.932791)
			(xy 369.420216 -169.969276) (xy 369.329558 -169.99874) (xy 369.236868 -170.021001) (xy 369.142718 -170.035921)
			(xy 369.047687 -170.043409) (xy 369.000024 -170.043856) (xy 368.950042 -170.043347) (xy 368.850416 -170.035126)
			(xy 368.751805 -170.018737) (xy 368.654876 -169.994292) (xy 368.560286 -169.961956) (xy 368.468677 -169.921949)
			(xy 368.380669 -169.874542) (xy 368.296859 -169.820056) (xy 368.217816 -169.75886) (xy 368.144074 -169.691369)
			(xy 368.076134 -169.618041) (xy 368.014457 -169.539373) (xy 367.95946 -169.455897) (xy 367.911516 -169.368181)
			(xy 367.87095 -169.276818) (xy 367.838037 -169.182427) (xy 367.813001 -169.085649) (xy 367.803938 -169.036492)
			(xy 367.801338 -169.024871) (xy 367.787292 -169.005679) (xy 367.777014 -168.999662) (xy 367.693702 -168.957244)
			(xy 367.669826 -168.957244) (xy 367.658904 -168.962578) (xy 367.611629 -168.985448) (xy 367.514429 -169.02524)
			(xy 367.414663 -169.058071) (xy 367.312828 -169.083778) (xy 367.209432 -169.102232) (xy 367.104992 -169.113342)
			(xy 367.000028 -169.117051) (xy 366.895064 -169.113342) (xy 366.790624 -169.102232) (xy 366.687228 -169.083778)
			(xy 366.585393 -169.058071) (xy 366.485627 -169.02524) (xy 366.388427 -168.985448) (xy 366.341152 -168.962578)
			(xy 366.33023 -168.957244) (xy 366.306354 -168.957244) (xy 366.223042 -168.999662) (xy 366.212731 -169.005639)
			(xy 366.198685 -169.024854) (xy 366.196118 -169.036492) (xy 366.18711 -169.085657) (xy 366.162054 -169.182427)
			(xy 366.129125 -169.276809) (xy 366.088546 -169.368163) (xy 366.040591 -169.455871) (xy 365.985586 -169.539338)
			(xy 365.923902 -169.617998) (xy 365.855959 -169.691318) (xy 365.782215 -169.758803) (xy 365.703172 -169.819995)
			(xy 365.619363 -169.874478) (xy 365.531358 -169.921885) (xy 365.439753 -169.961893) (xy 365.345167 -169.994232)
			(xy 365.248242 -170.018683) (xy 365.149634 -170.03508) (xy 365.050013 -170.043311) (xy 365.000032 -170.043856)
			(xy 364.95237 -170.043378) (xy 364.857342 -170.035882) (xy 364.763194 -170.020957) (xy 364.670507 -169.998695)
			(xy 364.57985 -169.969233) (xy 364.491784 -169.932752) (xy 364.406849 -169.889478) (xy 364.325569 -169.839676)
			(xy 364.248446 -169.783654) (xy 364.175952 -169.721756) (xy 364.108537 -169.654364) (xy 364.07725 -169.618406)
			(xy 364.069682 -169.610373) (xy 364.049665 -169.601132) (xy 364.038642 -169.600626) (xy 363.961426 -169.600626)
			(xy 363.950406 -169.601162) (xy 363.930385 -169.610378) (xy 363.922818 -169.618406) (xy 363.889364 -169.656744)
			(xy 363.816994 -169.728279) (xy 363.738877 -169.79349) (xy 363.69752 -169.82313) (xy 363.690104 -169.828832)
			(xy 363.679658 -169.84433) (xy 363.675474 -169.862546) (xy 363.678111 -169.881049) (xy 363.68228 -169.889424)
			(xy 363.703462 -169.928949) (xy 363.738682 -170.011422) (xy 363.765422 -170.097022) (xy 363.783409 -170.184878)
			(xy 363.792463 -170.274099) (xy 363.793024 -170.318938) (xy 363.792889 -170.340053) (xy 363.790854 -170.382235)
			(xy 363.78896 -170.403266) (xy 363.788421 -170.414903) (xy 363.796623 -170.436682) (xy 363.81357 -170.452631)
			(xy 363.82452 -170.456606) (xy 363.906061 -170.48131) (xy 364.070879 -170.524571) (xy 364.237395 -170.560745)
			(xy 364.405306 -170.589766) (xy 364.574304 -170.611582) (xy 364.74408 -170.626152) (xy 364.914324 -170.633449)
			(xy 364.999524 -170.633898)
		)
		(stroke
			(width 0)
			(type solid)
		)
		(fill yes)
		(layer "In5.Cu")
		(net "P52V_HS1")
	)
	(gr_poly
		(pts
			(xy 38.423596 -170.633898) (xy 38.434128 -170.633372) (xy 38.453415 -170.624903) (xy 38.467668 -170.609393)
			(xy 38.471602 -170.599608) (xy 38.471602 -170.599354) (xy 38.485985 -170.55869) (xy 38.521557 -170.480107)
			(xy 38.564563 -170.405333) (xy 38.6146 -170.33507) (xy 38.671199 -170.269976) (xy 38.733828 -170.210662)
			(xy 38.801901 -170.157683) (xy 38.87478 -170.111538) (xy 38.95178 -170.072658) (xy 38.991794 -170.056556)
			(xy 39.00551 -170.051222) (xy 39.023036 -170.027854) (xy 39.031672 -169.922444) (xy 39.032088 -169.912898)
			(xy 39.026626 -169.894603) (xy 39.014824 -169.879595) (xy 39.00678 -169.874438) (xy 38.965393 -169.849379)
			(xy 38.886327 -169.7936) (xy 38.811952 -169.731703) (xy 38.742742 -169.664083) (xy 38.679134 -169.591166)
			(xy 38.621533 -169.513418) (xy 38.570304 -169.431331) (xy 38.525773 -169.345426) (xy 38.488222 -169.256248)
			(xy 38.45789 -169.164364) (xy 38.434969 -169.070357) (xy 38.419604 -168.974824) (xy 38.411894 -168.87837)
			(xy 38.411404 -168.82999) (xy 38.411871 -168.782334) (xy 38.419347 -168.687315) (xy 38.43425 -168.593174)
			(xy 38.456491 -168.500493) (xy 38.485931 -168.409841) (xy 38.522389 -168.321776) (xy 38.565641 -168.236843)
			(xy 38.615421 -168.155562) (xy 38.671421 -168.078436) (xy 38.733298 -168.005939) (xy 38.800668 -167.938517)
			(xy 38.8366 -167.907208) (xy 38.844625 -167.899637) (xy 38.853848 -167.87962) (xy 38.85438 -167.8686)
			(xy 38.85438 -167.791384) (xy 38.853836 -167.780368) (xy 38.84461 -167.76036) (xy 38.8366 -167.752776)
			(xy 38.798977 -167.719952) (xy 38.728658 -167.649058) (xy 38.664401 -167.572628) (xy 38.60664 -167.491177)
			(xy 38.555765 -167.405256) (xy 38.512122 -167.315445) (xy 38.476004 -167.222353) (xy 38.447655 -167.126609)
			(xy 38.427269 -167.028859) (xy 38.414982 -166.929765) (xy 38.410877 -166.829996) (xy 38.414982 -166.730227)
			(xy 38.42727 -166.631133) (xy 38.447657 -166.533384) (xy 38.476006 -166.437639) (xy 38.512125 -166.344547)
			(xy 38.555769 -166.254738) (xy 38.606644 -166.168817) (xy 38.664405 -166.087366) (xy 38.728663 -166.010936)
			(xy 38.798983 -165.940043) (xy 38.8366 -165.907212) (xy 38.844626 -165.899641) (xy 38.853851 -165.879624)
			(xy 38.85438 -165.868604) (xy 38.85438 -165.791388) (xy 38.853837 -165.780371) (xy 38.844612 -165.760362)
			(xy 38.8366 -165.75278) (xy 38.798977 -165.719956) (xy 38.728658 -165.649062) (xy 38.6644 -165.572632)
			(xy 38.606638 -165.49118) (xy 38.555764 -165.405259) (xy 38.51212 -165.315449) (xy 38.476001 -165.222357)
			(xy 38.447653 -165.126612) (xy 38.427266 -165.028862) (xy 38.414979 -164.929768) (xy 38.410874 -164.829999)
			(xy 38.414979 -164.73023) (xy 38.427267 -164.631135) (xy 38.447654 -164.533385) (xy 38.476002 -164.437641)
			(xy 38.512121 -164.344549) (xy 38.555765 -164.254738) (xy 38.60664 -164.168817) (xy 38.664401 -164.087366)
			(xy 38.728659 -164.010936) (xy 38.798979 -163.940043) (xy 38.8366 -163.907216) (xy 38.844626 -163.899645)
			(xy 38.853853 -163.879628) (xy 38.85438 -163.868608) (xy 38.85438 -163.791392) (xy 38.853837 -163.780375)
			(xy 38.844614 -163.760364) (xy 38.8366 -163.752784) (xy 38.798977 -163.71996) (xy 38.728657 -163.649066)
			(xy 38.664399 -163.572636) (xy 38.606637 -163.491184) (xy 38.555762 -163.405263) (xy 38.512118 -163.315453)
			(xy 38.475999 -163.22236) (xy 38.447651 -163.126615) (xy 38.427264 -163.028865) (xy 38.414976 -162.92977)
			(xy 38.410871 -162.830001) (xy 38.414976 -162.730232) (xy 38.427263 -162.631137) (xy 38.44765 -162.533387)
			(xy 38.475999 -162.437642) (xy 38.512117 -162.34455) (xy 38.555761 -162.254739) (xy 38.606636 -162.168818)
			(xy 38.664397 -162.087366) (xy 38.728655 -162.010936) (xy 38.798975 -161.940042) (xy 38.8366 -161.90722)
			(xy 38.844627 -161.899649) (xy 38.853855 -161.879633) (xy 38.85438 -161.868612) (xy 38.85438 -161.791396)
			(xy 38.853838 -161.780379) (xy 38.844616 -161.760367) (xy 38.8366 -161.752788) (xy 38.798977 -161.719964)
			(xy 38.728657 -161.64907) (xy 38.664398 -161.57264) (xy 38.606636 -161.491188) (xy 38.555761 -161.405267)
			(xy 38.512116 -161.315456) (xy 38.475997 -161.222364) (xy 38.447648 -161.126619) (xy 38.427261 -161.028868)
			(xy 38.414973 -160.929773) (xy 38.410868 -160.830004) (xy 38.414973 -160.730234) (xy 38.42726 -160.63114)
			(xy 38.447647 -160.533389) (xy 38.475995 -160.437644) (xy 38.512113 -160.344551) (xy 38.555757 -160.25474)
			(xy 38.606632 -160.168818) (xy 38.664393 -160.087367) (xy 38.728651 -160.010935) (xy 38.798971 -159.940042)
			(xy 38.8366 -159.907224) (xy 38.844628 -159.899654) (xy 38.853857 -159.879637) (xy 38.85438 -159.868616)
			(xy 38.85438 -159.7914) (xy 38.853839 -159.780382) (xy 38.844618 -159.760369) (xy 38.8366 -159.752792)
			(xy 38.798976 -159.719968) (xy 38.728656 -159.649074) (xy 38.664397 -159.572643) (xy 38.606635 -159.491192)
			(xy 38.555759 -159.40527) (xy 38.512115 -159.31546) (xy 38.475995 -159.222367) (xy 38.447646 -159.126622)
			(xy 38.427259 -159.028871) (xy 38.41497 -158.929776) (xy 38.410865 -158.830007) (xy 38.414969 -158.730237)
			(xy 38.427256 -158.631142) (xy 38.447643 -158.533391) (xy 38.475991 -158.437645) (xy 38.512109 -158.344552)
			(xy 38.555753 -158.254741) (xy 38.606628 -158.168819) (xy 38.664389 -158.087367) (xy 38.728647 -158.010935)
			(xy 38.798967 -157.940041) (xy 38.8366 -157.907228) (xy 38.844629 -157.899658) (xy 38.85386 -157.879641)
			(xy 38.85438 -157.86862) (xy 38.85438 -157.791404) (xy 38.85384 -157.780386) (xy 38.844619 -157.760372)
			(xy 38.8366 -157.752796) (xy 38.798976 -157.719972) (xy 38.728656 -157.649078) (xy 38.664397 -157.572647)
			(xy 38.606634 -157.491196) (xy 38.555758 -157.405274) (xy 38.512113 -157.315463) (xy 38.475993 -157.222371)
			(xy 38.447644 -157.126625) (xy 38.427256 -157.028874) (xy 38.414968 -156.929779) (xy 38.410862 -156.830009)
			(xy 38.414966 -156.730239) (xy 38.427253 -156.631144) (xy 38.447639 -156.533393) (xy 38.475987 -156.437647)
			(xy 38.512106 -156.344553) (xy 38.555749 -156.254742) (xy 38.606624 -156.168819) (xy 38.664385 -156.087367)
			(xy 38.728643 -156.010935) (xy 38.798963 -155.940041) (xy 38.8366 -155.907232) (xy 38.844629 -155.899662)
			(xy 38.853862 -155.879645) (xy 38.85438 -155.868624) (xy 38.85438 -155.791408) (xy 38.853841 -155.780389)
			(xy 38.844621 -155.760374) (xy 38.8366 -155.7528) (xy 38.798976 -155.719976) (xy 38.728655 -155.649082)
			(xy 38.664396 -155.572651) (xy 38.606633 -155.4912) (xy 38.555757 -155.405278) (xy 38.512111 -155.315467)
			(xy 38.475991 -155.222374) (xy 38.447642 -155.126628) (xy 38.427253 -155.028877) (xy 38.414965 -154.929782)
			(xy 38.410859 -154.830012) (xy 38.414963 -154.730242) (xy 38.42725 -154.631146) (xy 38.447636 -154.533394)
			(xy 38.475984 -154.437648) (xy 38.512102 -154.344554) (xy 38.555745 -154.254743) (xy 38.60662 -154.16882)
			(xy 38.664381 -154.087367) (xy 38.728639 -154.010935) (xy 38.798959 -153.94004) (xy 38.8366 -153.907236)
			(xy 38.84463 -153.899666) (xy 38.853864 -153.87965) (xy 38.85438 -153.868628) (xy 38.85438 -153.791412)
			(xy 38.853841 -153.780393) (xy 38.844623 -153.760376) (xy 38.8366 -153.752804) (xy 38.800676 -153.721486)
			(xy 38.7333 -153.654069) (xy 38.67142 -153.581575) (xy 38.615417 -153.504451) (xy 38.565636 -153.423172)
			(xy 38.522383 -153.338238) (xy 38.485925 -153.250174) (xy 38.456486 -153.159521) (xy 38.434249 -153.066839)
			(xy 38.419349 -152.972698) (xy 38.41188 -152.877678) (xy 38.411404 -152.830022) (xy 38.411921 -152.779843)
			(xy 38.420206 -152.679828) (xy 38.43672 -152.580839) (xy 38.461351 -152.483551) (xy 38.493931 -152.388629)
			(xy 38.534238 -152.296721) (xy 38.581995 -152.208455) (xy 38.636877 -152.124434) (xy 38.698509 -152.045231)
			(xy 38.766471 -151.971387) (xy 38.840297 -151.903407) (xy 38.919485 -151.841755) (xy 39.003492 -151.786852)
			(xy 39.091746 -151.739072) (xy 39.183644 -151.698743) (xy 39.278557 -151.666139) (xy 39.375839 -151.641483)
			(xy 39.474824 -151.624944) (xy 39.574837 -151.616634) (xy 39.625016 -151.616156) (xy 39.672677 -151.616635)
			(xy 39.767703 -151.624135) (xy 39.861849 -151.639064) (xy 39.954534 -151.661329) (xy 40.045188 -151.690794)
			(xy 40.133251 -151.727277) (xy 40.218183 -151.770554) (xy 40.299459 -151.820358) (xy 40.37658 -151.876382)
			(xy 40.44907 -151.938281) (xy 40.516482 -152.005674) (xy 40.547798 -152.041606) (xy 40.55537 -152.049629)
			(xy 40.575387 -152.058849) (xy 40.586406 -152.059386) (xy 40.663622 -152.059386) (xy 40.674638 -152.058841)
			(xy 40.694645 -152.049615) (xy 40.70223 -152.041606) (xy 40.73354 -152.005667) (xy 40.800944 -151.938261)
			(xy 40.873428 -151.876352) (xy 40.950546 -151.820319) (xy 41.031822 -151.77051) (xy 41.116755 -151.72723)
			(xy 41.204822 -151.690747) (xy 41.29548 -151.661286) (xy 41.388169 -151.639028) (xy 41.482319 -151.62411)
			(xy 41.57735 -151.616624) (xy 41.625012 -151.616156) (xy 41.675179 -151.616674) (xy 41.775172 -151.62496)
			(xy 41.874138 -151.641473) (xy 41.971404 -151.666101) (xy 42.066303 -151.698675) (xy 42.158189 -151.738974)
			(xy 42.246435 -151.786722) (xy 42.330436 -151.841594) (xy 42.40962 -151.903213) (xy 42.483446 -151.97116)
			(xy 42.55141 -152.044971) (xy 42.613047 -152.124141) (xy 42.667937 -152.20813) (xy 42.715705 -152.296364)
			(xy 42.756025 -152.388241) (xy 42.788621 -152.483134) (xy 42.813271 -152.580393) (xy 42.829806 -152.679356)
			(xy 42.838114 -152.779347) (xy 42.838624 -152.829514) (xy 42.838624 -152.830022) (xy 42.838156 -152.877678)
			(xy 42.83068 -152.972697) (xy 42.815776 -153.066837) (xy 42.793535 -153.159519) (xy 42.764095 -153.250171)
			(xy 42.727637 -153.338235) (xy 42.684385 -153.423168) (xy 42.634605 -153.504449) (xy 42.578605 -153.581575)
			(xy 42.51673 -153.654073) (xy 42.44936 -153.721495) (xy 42.413428 -153.752804) (xy 42.405401 -153.760374)
			(xy 42.396178 -153.780392) (xy 42.395648 -153.791412) (xy 42.395648 -153.868628) (xy 42.396192 -153.879645)
			(xy 42.405412 -153.899658) (xy 42.413428 -153.907236) (xy 42.451052 -153.940059) (xy 42.521374 -154.01095)
			(xy 42.585634 -154.08738) (xy 42.643398 -154.16883) (xy 42.694274 -154.25475) (xy 42.73792 -154.34456)
			(xy 42.774039 -154.437652) (xy 42.802388 -154.533397) (xy 42.822776 -154.631148) (xy 42.835063 -154.730242)
			(xy 42.839167 -154.830012) (xy 42.835061 -154.929781) (xy 42.822772 -155.028875) (xy 42.802383 -155.126625)
			(xy 42.774032 -155.22237) (xy 42.737911 -155.315461) (xy 42.694263 -155.40527) (xy 42.643385 -155.49119)
			(xy 42.58562 -155.572639) (xy 42.521359 -155.649067) (xy 42.451035 -155.719957) (xy 42.413428 -155.7528)
			(xy 42.4054 -155.76037) (xy 42.396175 -155.780387) (xy 42.395648 -155.791408) (xy 42.395648 -155.868624)
			(xy 42.396191 -155.879642) (xy 42.40541 -155.899656) (xy 42.413428 -155.907232) (xy 42.451053 -155.940055)
			(xy 42.521375 -156.010946) (xy 42.585635 -156.087376) (xy 42.643399 -156.168826) (xy 42.694276 -156.254747)
			(xy 42.737922 -156.344557) (xy 42.774041 -156.437649) (xy 42.802391 -156.533394) (xy 42.822778 -156.631145)
			(xy 42.835066 -156.73024) (xy 42.83917 -156.830009) (xy 42.835064 -156.929779) (xy 42.822775 -157.028873)
			(xy 42.802386 -157.126624) (xy 42.774036 -157.222368) (xy 42.737914 -157.31546) (xy 42.694267 -157.405269)
			(xy 42.643389 -157.491189) (xy 42.585624 -157.572639) (xy 42.521363 -157.649067) (xy 42.451039 -157.719957)
			(xy 42.413428 -157.752796) (xy 42.4054 -157.760366) (xy 42.396173 -157.780383) (xy 42.395648 -157.791404)
			(xy 42.395648 -157.86862) (xy 42.396191 -157.879638) (xy 42.405408 -157.899654) (xy 42.413428 -157.907228)
			(xy 42.451053 -157.940051) (xy 42.521375 -158.010942) (xy 42.585636 -158.087372) (xy 42.6434 -158.168822)
			(xy 42.694277 -158.254743) (xy 42.737923 -158.344553) (xy 42.774043 -158.437645) (xy 42.802393 -158.533391)
			(xy 42.822781 -158.631141) (xy 42.835068 -158.730237) (xy 42.839173 -158.830006) (xy 42.835067 -158.929776)
			(xy 42.822779 -159.028871) (xy 42.80239 -159.126622) (xy 42.774039 -159.222367) (xy 42.737918 -159.315459)
			(xy 42.694271 -159.405269) (xy 42.643393 -159.491189) (xy 42.585628 -159.572639) (xy 42.537306 -159.63011)
			(xy 71.481963 -159.63011) (xy 71.48592 -159.520564) (xy 71.497772 -159.411589) (xy 71.517456 -159.303754)
			(xy 71.54487 -159.19762) (xy 71.579871 -159.09374) (xy 71.622277 -158.992657) (xy 71.671866 -158.894898)
			(xy 71.728379 -158.800971) (xy 71.791523 -158.711368) (xy 71.860968 -158.626554) (xy 71.936352 -158.546972)
			(xy 72.017282 -158.473037) (xy 72.103336 -158.405135) (xy 72.194065 -158.343619) (xy 72.288996 -158.288811)
			(xy 72.387635 -158.240995) (xy 72.489467 -158.200421) (xy 72.593961 -158.167301) (xy 72.700573 -158.141808)
			(xy 72.808746 -158.124074) (xy 72.917917 -158.114191) (xy 73.027517 -158.112212) (xy 73.136973 -158.118147)
			(xy 73.245717 -158.131964) (xy 73.353179 -158.153592) (xy 73.458801 -158.182918) (xy 73.562031 -158.219789)
			(xy 73.662332 -158.264012) (xy 73.759181 -158.315358) (xy 73.852071 -158.373558) (xy 73.94052 -158.438309)
			(xy 74.024067 -158.509274) (xy 74.102274 -158.586083) (xy 74.174736 -158.668334) (xy 74.241074 -158.7556)
			(xy 74.300941 -158.847424) (xy 74.354027 -158.94333) (xy 74.400054 -159.042816) (xy 74.438783 -159.145364)
			(xy 74.470011 -159.250439) (xy 74.493575 -159.357494) (xy 74.509354 -159.46597) (xy 74.517263 -159.575301)
			(xy 74.517758 -159.63011) (xy 74.517263 -159.684919) (xy 74.509354 -159.79425) (xy 74.493575 -159.902726)
			(xy 74.470011 -160.009781) (xy 74.438783 -160.114856) (xy 74.400054 -160.217404) (xy 74.354027 -160.31689)
			(xy 74.300941 -160.412796) (xy 74.241074 -160.50462) (xy 74.174736 -160.591886) (xy 74.102274 -160.674137)
			(xy 74.024067 -160.750946) (xy 73.94052 -160.821911) (xy 73.852071 -160.886662) (xy 73.759181 -160.944862)
			(xy 73.662332 -160.996208) (xy 73.562031 -161.040431) (xy 73.458801 -161.077302) (xy 73.353179 -161.106628)
			(xy 73.245717 -161.128256) (xy 73.136973 -161.142073) (xy 73.027517 -161.148008) (xy 72.917917 -161.146029)
			(xy 72.808746 -161.136146) (xy 72.700573 -161.118412) (xy 72.593961 -161.092919) (xy 72.489467 -161.059799)
			(xy 72.387635 -161.019225) (xy 72.288996 -160.971409) (xy 72.194065 -160.916601) (xy 72.103336 -160.855085)
			(xy 72.017282 -160.787183) (xy 71.936352 -160.713248) (xy 71.860968 -160.633666) (xy 71.791523 -160.548852)
			(xy 71.728379 -160.459249) (xy 71.671866 -160.365322) (xy 71.622277 -160.267563) (xy 71.579871 -160.16648)
			(xy 71.54487 -160.0626) (xy 71.517456 -159.956466) (xy 71.497772 -159.848631) (xy 71.48592 -159.739656)
			(xy 71.481963 -159.63011) (xy 42.537306 -159.63011) (xy 42.521367 -159.649067) (xy 42.451043 -159.719958)
			(xy 42.413428 -159.752792) (xy 42.405399 -159.760361) (xy 42.396171 -159.780379) (xy 42.395648 -159.7914)
			(xy 42.395648 -159.868616) (xy 42.39619 -159.879634) (xy 42.405406 -159.899651) (xy 42.413428 -159.907224)
			(xy 42.451053 -159.940047) (xy 42.521376 -160.010939) (xy 42.585637 -160.087368) (xy 42.643401 -160.168818)
			(xy 42.694279 -160.254739) (xy 42.737925 -160.344549) (xy 42.774045 -160.437642) (xy 42.802395 -160.533387)
			(xy 42.822783 -160.631138) (xy 42.835071 -160.730234) (xy 42.839176 -160.830004) (xy 42.835071 -160.929774)
			(xy 42.822782 -161.028869) (xy 42.802393 -161.12662) (xy 42.774043 -161.222365) (xy 42.737922 -161.315458)
			(xy 42.694275 -161.405268) (xy 42.643397 -161.491188) (xy 42.585632 -161.572638) (xy 42.521371 -161.649067)
			(xy 42.451047 -161.719958) (xy 42.413428 -161.752788) (xy 42.405398 -161.760357) (xy 42.396168 -161.780375)
			(xy 42.395648 -161.791396) (xy 42.395648 -161.868612) (xy 42.396189 -161.879631) (xy 42.405405 -161.899649)
			(xy 42.413428 -161.90722) (xy 42.451053 -161.940043) (xy 42.521376 -162.010935) (xy 42.585638 -162.087364)
			(xy 42.643402 -162.168814) (xy 42.69428 -162.254735) (xy 42.704549 -162.275866) (xy 51.308235 -162.275866)
			(xy 51.316175 -162.167119) (xy 51.332033 -162.059242) (xy 51.355722 -161.95281) (xy 51.387118 -161.848391)
			(xy 51.426052 -161.746543) (xy 51.472316 -161.647808) (xy 51.525664 -161.552714) (xy 51.585812 -161.461768)
			(xy 51.652437 -161.375455) (xy 51.725185 -161.294235) (xy 51.803668 -161.218542) (xy 51.887467 -161.14878)
			(xy 51.976134 -161.085322) (xy 52.069197 -161.028504) (xy 52.166159 -160.978632) (xy 52.266503 -160.93597)
			(xy 52.369693 -160.900747) (xy 52.47518 -160.87315) (xy 52.582399 -160.853327) (xy 52.690779 -160.841383)
			(xy 52.799742 -160.837382) (xy 52.908706 -160.841346) (xy 53.01709 -160.853253) (xy 53.124316 -160.873039)
			(xy 53.229812 -160.9006) (xy 53.333014 -160.935789) (xy 53.433373 -160.978416) (xy 53.530352 -161.028256)
			(xy 53.623434 -161.085041) (xy 53.712123 -161.14847) (xy 53.795946 -161.218203) (xy 53.874454 -161.293869)
			(xy 53.94723 -161.375064) (xy 54.013885 -161.461355) (xy 54.074063 -161.55228) (xy 54.127444 -161.647356)
			(xy 54.173742 -161.746075) (xy 54.21271 -161.84791) (xy 54.244141 -161.952318) (xy 54.267867 -162.058742)
			(xy 54.283761 -162.166614) (xy 54.291739 -162.275358) (xy 54.292246 -162.329876) (xy 54.291757 -162.384394)
			(xy 54.283817 -162.493141) (xy 54.267959 -162.601018) (xy 54.24427 -162.70745) (xy 54.212874 -162.811869)
			(xy 54.17394 -162.913717) (xy 54.127676 -163.012452) (xy 54.074328 -163.107546) (xy 54.01418 -163.198492)
			(xy 53.947555 -163.284805) (xy 53.874807 -163.366025) (xy 53.796324 -163.441718) (xy 53.712525 -163.51148)
			(xy 53.623858 -163.574938) (xy 53.530795 -163.631756) (xy 53.433833 -163.681628) (xy 53.333489 -163.72429)
			(xy 53.230299 -163.759513) (xy 53.124812 -163.78711) (xy 53.017593 -163.806933) (xy 52.909213 -163.818877)
			(xy 52.80025 -163.822878) (xy 52.691286 -163.818914) (xy 52.582902 -163.807007) (xy 52.475676 -163.787221)
			(xy 52.37018 -163.75966) (xy 52.266978 -163.724471) (xy 52.166619 -163.681844) (xy 52.06964 -163.632004)
			(xy 51.976558 -163.575219) (xy 51.887869 -163.51179) (xy 51.804046 -163.442057) (xy 51.725538 -163.366391)
			(xy 51.652762 -163.285196) (xy 51.586107 -163.198905) (xy 51.525929 -163.10798) (xy 51.472548 -163.012904)
			(xy 51.42625 -162.914185) (xy 51.387282 -162.81235) (xy 51.355851 -162.707942) (xy 51.332125 -162.601518)
			(xy 51.316231 -162.493646) (xy 51.308253 -162.384902) (xy 51.308235 -162.275866) (xy 42.704549 -162.275866)
			(xy 42.737927 -162.344546) (xy 42.774048 -162.437639) (xy 42.802398 -162.533384) (xy 42.822786 -162.631135)
			(xy 42.835074 -162.730231) (xy 42.839179 -162.830001) (xy 42.835074 -162.929772) (xy 42.822785 -163.028867)
			(xy 42.802397 -163.126618) (xy 42.774047 -163.222364) (xy 42.737926 -163.315457) (xy 42.694279 -163.405267)
			(xy 42.643401 -163.491188) (xy 42.585636 -163.572638) (xy 42.521375 -163.649067) (xy 42.451051 -163.719959)
			(xy 42.413428 -163.752784) (xy 42.405398 -163.760353) (xy 42.396166 -163.78037) (xy 42.395648 -163.791392)
			(xy 42.395648 -163.868608) (xy 42.396188 -163.879627) (xy 42.405403 -163.899647) (xy 42.413428 -163.907216)
			(xy 42.451053 -163.940039) (xy 42.521377 -164.010931) (xy 42.585638 -164.08736) (xy 42.643404 -164.168811)
			(xy 42.694282 -164.254732) (xy 42.737929 -164.344542) (xy 42.77405 -164.437635) (xy 42.8024 -164.533381)
			(xy 42.822788 -164.631132) (xy 42.835077 -164.730228) (xy 42.839182 -164.829999) (xy 42.835077 -164.929769)
			(xy 42.822789 -165.028865) (xy 42.802401 -165.126617) (xy 42.77405 -165.222362) (xy 42.73793 -165.315455)
			(xy 42.694283 -165.405266) (xy 42.643405 -165.491187) (xy 42.58564 -165.572638) (xy 42.521379 -165.649068)
			(xy 42.451055 -165.719959) (xy 42.413428 -165.75278) (xy 42.405397 -165.760349) (xy 42.396164 -165.780366)
			(xy 42.395648 -165.791388) (xy 42.395648 -165.868604) (xy 42.396187 -165.879623) (xy 42.405401 -165.899644)
			(xy 42.413428 -165.907212) (xy 42.451053 -165.940035) (xy 42.521377 -166.010927) (xy 42.585639 -166.087356)
			(xy 42.643405 -166.168807) (xy 42.694283 -166.254728) (xy 42.73793 -166.344539) (xy 42.774052 -166.437632)
			(xy 42.802402 -166.533378) (xy 42.822791 -166.631129) (xy 42.83508 -166.730225) (xy 42.839185 -166.829996)
			(xy 42.83508 -166.929767) (xy 42.822792 -167.028863) (xy 42.802404 -167.126615) (xy 42.774054 -167.222361)
			(xy 42.737934 -167.315454) (xy 42.694287 -167.405265) (xy 42.643409 -167.491187) (xy 42.585644 -167.572638)
			(xy 42.521383 -167.649068) (xy 42.451059 -167.71996) (xy 42.413428 -167.752776) (xy 42.405397 -167.760345)
			(xy 42.396162 -167.780362) (xy 42.395648 -167.791384) (xy 42.395648 -167.8686) (xy 42.396187 -167.87962)
			(xy 42.405399 -167.899642) (xy 42.413428 -167.907208) (xy 42.449354 -167.938525) (xy 42.516732 -168.00594)
			(xy 42.578614 -168.078433) (xy 42.63462 -168.155557) (xy 42.684404 -168.236836) (xy 42.727659 -168.32177)
			(xy 42.764118 -168.409834) (xy 42.793558 -168.500488) (xy 42.815796 -168.593171) (xy 42.830695 -168.687313)
			(xy 42.838164 -168.782333) (xy 42.838624 -168.82999) (xy 42.838106 -168.880167) (xy 42.829821 -168.98018)
			(xy 42.813305 -169.079166) (xy 42.788673 -169.176451) (xy 42.756092 -169.271369) (xy 42.715785 -169.363274)
			(xy 42.668027 -169.451536) (xy 42.613144 -169.535553) (xy 42.551511 -169.614752) (xy 42.483549 -169.688592)
			(xy 42.409722 -169.756567) (xy 42.330534 -169.818215) (xy 42.246527 -169.873113) (xy 42.158273 -169.920887)
			(xy 42.066376 -169.961211) (xy 41.971464 -169.99381) (xy 41.874183 -170.01846) (xy 41.7752 -170.034993)
			(xy 41.675189 -170.043297) (xy 41.625012 -170.043856) (xy 41.577351 -170.043378) (xy 41.482323 -170.03588)
			(xy 41.388176 -170.020954) (xy 41.29549 -169.99869) (xy 41.204834 -169.969227) (xy 41.116769 -169.932745)
			(xy 41.031835 -169.88947) (xy 40.950557 -169.839667) (xy 40.873434 -169.783645) (xy 40.800942 -169.721747)
			(xy 40.733528 -169.654354) (xy 40.70223 -169.618406) (xy 40.69466 -169.610377) (xy 40.674644 -169.601144)
			(xy 40.663622 -169.600626) (xy 40.586406 -169.600626) (xy 40.575388 -169.601166) (xy 40.555374 -169.610387)
			(xy 40.547798 -169.618406) (xy 40.516411 -169.654461) (xy 40.448809 -169.72206) (xy 40.376095 -169.784126)
			(xy 40.29872 -169.840276) (xy 40.217164 -169.890159) (xy 40.131935 -169.933467) (xy 40.043561 -169.969931)
			(xy 39.95259 -169.999324) (xy 39.906194 -170.010836) (xy 39.868348 -170.04919) (xy 39.848536 -170.138344)
			(xy 39.84689 -170.147707) (xy 39.849849 -170.166473) (xy 39.859407 -170.182891) (xy 39.86657 -170.189144)
			(xy 39.899481 -170.215886) (xy 39.960592 -170.274688) (xy 40.015823 -170.339045) (xy 40.064671 -170.40837)
			(xy 40.106693 -170.482034) (xy 40.141507 -170.559366) (xy 40.155622 -170.599354) (xy 40.155622 -170.599608)
			(xy 40.159551 -170.609388) (xy 40.173823 -170.624867) (xy 40.193102 -170.63333) (xy 40.203628 -170.633898)
			(xy 43.503596 -170.633898) (xy 43.514128 -170.633372) (xy 43.533415 -170.624903) (xy 43.547668 -170.609393)
			(xy 43.551602 -170.599608) (xy 43.551602 -170.599354) (xy 43.565762 -170.559248) (xy 43.600703 -170.481699)
			(xy 43.64289 -170.407841) (xy 43.691935 -170.338347) (xy 43.747391 -170.273854) (xy 43.808752 -170.21495)
			(xy 43.875456 -170.162173) (xy 43.946894 -170.116007) (xy 44.022414 -170.076872) (xy 44.101326 -170.045126)
			(xy 44.182907 -170.021059) (xy 44.266414 -170.004891) (xy 44.351083 -169.99677) (xy 44.436141 -169.99677)
			(xy 44.52081 -170.004891) (xy 44.604317 -170.021059) (xy 44.685898 -170.045126) (xy 44.76481 -170.076872)
			(xy 44.84033 -170.116007) (xy 44.911768 -170.162173) (xy 44.978472 -170.21495) (xy 45.039833 -170.273854)
			(xy 45.095289 -170.338347) (xy 45.144334 -170.407841) (xy 45.186521 -170.481699) (xy 45.221462 -170.559248)
			(xy 45.235622 -170.599354) (xy 45.235622 -170.599608) (xy 45.239551 -170.609388) (xy 45.253823 -170.624867)
			(xy 45.273102 -170.63333) (xy 45.283628 -170.633898) (xy 48.583596 -170.633898) (xy 48.594128 -170.633372)
			(xy 48.613415 -170.624903) (xy 48.627668 -170.609393) (xy 48.631602 -170.599608) (xy 48.631602 -170.599354)
			(xy 48.646941 -170.556083) (xy 48.68532 -170.472677) (xy 48.732077 -170.393664) (xy 48.786716 -170.31988)
			(xy 48.848656 -170.25211) (xy 48.882554 -170.221148) (xy 48.894492 -170.21048) (xy 48.901858 -170.179746)
			(xy 48.861726 -170.076114) (xy 48.857533 -170.066559) (xy 48.842951 -170.051663) (xy 48.823642 -170.04381)
			(xy 48.813212 -170.043602) (xy 48.812958 -170.043602) (xy 48.800258 -170.043856) (xy 48.79975 -170.043856)
			(xy 48.749589 -170.043328) (xy 48.64961 -170.035025) (xy 48.550658 -170.018497) (xy 48.453409 -169.993856)
			(xy 48.358526 -169.961271) (xy 48.266656 -169.920964) (xy 48.178428 -169.87321) (xy 48.094444 -169.818335)
			(xy 48.015276 -169.756714) (xy 47.941466 -169.688768) (xy 47.873517 -169.614961) (xy 47.811893 -169.535795)
			(xy 47.757015 -169.451813) (xy 47.709257 -169.363587) (xy 47.668947 -169.271719) (xy 47.636358 -169.176837)
			(xy 47.611713 -169.079589) (xy 47.595181 -168.980637) (xy 47.586874 -168.880659) (xy 47.586392 -168.830498)
			(xy 47.586392 -168.82999) (xy 47.586859 -168.782334) (xy 47.594335 -168.687314) (xy 47.609238 -168.593174)
			(xy 47.631478 -168.500492) (xy 47.660918 -168.40984) (xy 47.697376 -168.321776) (xy 47.740628 -168.236841)
			(xy 47.790408 -168.155561) (xy 47.846408 -168.078434) (xy 47.908283 -168.005936) (xy 47.975654 -167.938514)
			(xy 48.011588 -167.907208) (xy 48.019615 -167.899637) (xy 48.02884 -167.87962) (xy 48.029368 -167.8686)
			(xy 48.029368 -167.791384) (xy 48.028824 -167.780368) (xy 48.019597 -167.760361) (xy 48.011588 -167.752776)
			(xy 47.973965 -167.719951) (xy 47.903647 -167.649058) (xy 47.83939 -167.572627) (xy 47.78163 -167.491176)
			(xy 47.730756 -167.405255) (xy 47.687113 -167.315445) (xy 47.650995 -167.222353) (xy 47.622647 -167.126608)
			(xy 47.602261 -167.028859) (xy 47.589974 -166.929765) (xy 47.585869 -166.829996) (xy 47.589974 -166.730228)
			(xy 47.602262 -166.631134) (xy 47.622649 -166.533384) (xy 47.650998 -166.43764) (xy 47.687116 -166.344548)
			(xy 47.73076 -166.254738) (xy 47.781634 -166.168818) (xy 47.839395 -166.087367) (xy 47.903652 -166.010936)
			(xy 47.973971 -165.940043) (xy 48.011588 -165.907212) (xy 48.019615 -165.899642) (xy 48.028842 -165.879625)
			(xy 48.029368 -165.868604) (xy 48.029368 -165.791388) (xy 48.028824 -165.780372) (xy 48.019598 -165.760364)
			(xy 48.011588 -165.75278) (xy 47.975665 -165.721462) (xy 47.908292 -165.654044) (xy 47.846414 -165.581549)
			(xy 47.790413 -165.504424) (xy 47.740633 -165.423145) (xy 47.697383 -165.338211) (xy 47.660927 -165.250147)
			(xy 47.63149 -165.159495) (xy 47.609255 -165.066813) (xy 47.594357 -164.972673) (xy 47.58689 -164.877654)
			(xy 47.586392 -164.829998) (xy 47.58691 -164.77982) (xy 47.595196 -164.679806) (xy 47.611712 -164.580817)
			(xy 47.636345 -164.483531) (xy 47.668926 -164.38861) (xy 47.709233 -164.296704) (xy 47.756991 -164.208439)
			(xy 47.811873 -164.124419) (xy 47.873505 -164.045217) (xy 47.941466 -163.971374) (xy 48.015293 -163.903395)
			(xy 48.094479 -163.841744) (xy 48.178486 -163.786841) (xy 48.266739 -163.739062) (xy 48.358636 -163.698733)
			(xy 48.453549 -163.666129) (xy 48.55083 -163.641473) (xy 48.649814 -163.624933) (xy 48.749826 -163.616622)
			(xy 48.800004 -163.616132) (xy 48.847665 -163.616611) (xy 48.942692 -163.62411) (xy 49.036839 -163.639037)
			(xy 49.129525 -163.661301) (xy 49.220179 -163.690765) (xy 49.308244 -163.727248) (xy 49.393177 -163.770523)
			(xy 49.474455 -163.820326) (xy 49.551577 -163.876349) (xy 49.624068 -163.938247) (xy 49.691483 -164.005639)
			(xy 49.722786 -164.041582) (xy 49.730356 -164.04961) (xy 49.750373 -164.058839) (xy 49.761394 -164.059362)
			(xy 49.83861 -164.059362) (xy 49.849629 -164.058822) (xy 49.869649 -164.049608) (xy 49.877218 -164.041582)
			(xy 49.908528 -164.005643) (xy 49.975932 -163.938238) (xy 50.048417 -163.876329) (xy 50.125535 -163.820297)
			(xy 50.206811 -163.770488) (xy 50.291744 -163.727208) (xy 50.379811 -163.690725) (xy 50.470468 -163.661263)
			(xy 50.563158 -163.639005) (xy 50.657308 -163.624086) (xy 50.752338 -163.6166) (xy 50.8 -163.616132)
			(xy 50.850167 -163.61665) (xy 50.950157 -163.624934) (xy 51.049122 -163.641447) (xy 51.146386 -163.666075)
			(xy 51.241284 -163.698649) (xy 51.333168 -163.738948) (xy 51.421411 -163.786697) (xy 51.50541 -163.841569)
			(xy 51.584592 -163.903189) (xy 51.658415 -163.971137) (xy 51.726375 -164.044948) (xy 51.788009 -164.124119)
			(xy 51.842895 -164.208108) (xy 51.890659 -164.296343) (xy 51.930974 -164.38822) (xy 51.963565 -164.483113)
			(xy 51.98821 -164.580372) (xy 52.00474 -164.679334) (xy 52.013041 -164.779324) (xy 52.013612 -164.82949)
			(xy 52.013612 -164.829998) (xy 52.013145 -164.877655) (xy 52.005671 -164.972674) (xy 51.990768 -165.066815)
			(xy 51.968529 -165.159498) (xy 51.93909 -165.250151) (xy 51.902632 -165.338216) (xy 51.859381 -165.423151)
			(xy 51.809602 -165.504432) (xy 51.753602 -165.58156) (xy 51.691727 -165.654058) (xy 51.624357 -165.721481)
			(xy 51.588416 -165.75278) (xy 51.580387 -165.76035) (xy 51.571156 -165.780367) (xy 51.570636 -165.791388)
			(xy 51.570636 -165.868604) (xy 51.571179 -165.879621) (xy 51.580403 -165.899631) (xy 51.588416 -165.907212)
			(xy 51.626039 -165.940037) (xy 51.696358 -166.01093) (xy 51.760616 -166.087361) (xy 51.818377 -166.168813)
			(xy 51.869252 -166.254734) (xy 51.912896 -166.344545) (xy 51.949014 -166.437637) (xy 51.977362 -166.533382)
			(xy 51.99775 -166.631132) (xy 52.010037 -166.730227) (xy 52.014143 -166.829996) (xy 52.010038 -166.929765)
			(xy 51.997751 -167.02886) (xy 51.977364 -167.12661) (xy 51.949016 -167.222355) (xy 51.912899 -167.315448)
			(xy 51.869255 -167.405259) (xy 51.818381 -167.49118) (xy 51.76062 -167.572632) (xy 51.696363 -167.649064)
			(xy 51.626045 -167.719958) (xy 51.588416 -167.752776) (xy 51.580386 -167.760345) (xy 51.571154 -167.780362)
			(xy 51.570636 -167.791384) (xy 51.570636 -167.8686) (xy 51.571178 -167.879617) (xy 51.580401 -167.899628)
			(xy 51.588416 -167.907208) (xy 51.62434 -167.938526) (xy 51.691713 -168.005944) (xy 51.753592 -168.078438)
			(xy 51.809593 -168.155563) (xy 51.859373 -168.236842) (xy 51.902625 -168.321776) (xy 51.939082 -168.40984)
			(xy 51.968519 -168.500492) (xy 51.990755 -168.593174) (xy 52.005654 -168.687315) (xy 52.013122 -168.782334)
			(xy 52.013612 -168.82999) (xy 52.013094 -168.880169) (xy 52.004809 -168.980184) (xy 51.988294 -169.079173)
			(xy 51.963662 -169.17646) (xy 51.931082 -169.271382) (xy 51.890775 -169.36329) (xy 51.843018 -169.451555)
			(xy 51.788135 -169.535576) (xy 51.726503 -169.614779) (xy 51.658542 -169.688623) (xy 51.584716 -169.756603)
			(xy 51.505529 -169.818255) (xy 51.421522 -169.873159) (xy 51.333268 -169.920939) (xy 51.241371 -169.961269)
			(xy 51.146458 -169.993874) (xy 51.049176 -170.01853) (xy 50.950191 -170.035071) (xy 50.850179 -170.043381)
			(xy 50.8 -170.043856) (xy 50.752339 -170.043377) (xy 50.657312 -170.035879) (xy 50.563165 -170.020951)
			(xy 50.470479 -169.998687) (xy 50.379825 -169.969223) (xy 50.29176 -169.932741) (xy 50.206827 -169.889465)
			(xy 50.125549 -169.839662) (xy 50.048427 -169.783639) (xy 49.975936 -169.721741) (xy 49.908522 -169.654348)
			(xy 49.877218 -169.618406) (xy 49.869648 -169.610378) (xy 49.849631 -169.60115) (xy 49.83861 -169.600626)
			(xy 49.761394 -169.600626) (xy 49.750377 -169.601168) (xy 49.730366 -169.610392) (xy 49.722786 -169.618406)
			(xy 49.690645 -169.655306) (xy 49.621304 -169.724367) (xy 49.546622 -169.787615) (xy 49.50714 -169.816526)
			(xy 49.499004 -169.822911) (xy 49.488269 -169.840567) (xy 49.485384 -169.861027) (xy 49.487582 -169.871136)
			(xy 49.516538 -169.978324) (xy 49.540922 -169.998644) (xy 49.55667 -170.000168) (xy 49.599046 -170.004639)
			(xy 49.682741 -170.020663) (xy 49.764519 -170.044621) (xy 49.84363 -170.076294) (xy 49.919347 -170.11539)
			(xy 49.990976 -170.161552) (xy 50.05786 -170.214356) (xy 50.119385 -170.273316) (xy 50.174987 -170.337893)
			(xy 50.224155 -170.407493) (xy 50.266438 -170.481479) (xy 50.301448 -170.55917) (xy 50.315622 -170.599354)
			(xy 50.315622 -170.599608) (xy 50.319551 -170.609388) (xy 50.333823 -170.624867) (xy 50.353102 -170.63333)
			(xy 50.363628 -170.633898) (xy 53.663596 -170.633898) (xy 53.674128 -170.633372) (xy 53.693415 -170.624903)
			(xy 53.707668 -170.609393) (xy 53.711602 -170.599608) (xy 53.711602 -170.599354) (xy 53.725254 -170.560595)
			(xy 53.758755 -170.485553) (xy 53.799038 -170.413923) (xy 53.84576 -170.346316) (xy 53.898522 -170.283309)
			(xy 53.956873 -170.225441) (xy 54.020316 -170.173204) (xy 54.088309 -170.127046) (xy 54.160272 -170.08736)
			(xy 54.197758 -170.070526) (xy 54.198012 -170.070526) (xy 54.206454 -170.066314) (xy 54.219769 -170.052973)
			(xy 54.227371 -170.035725) (xy 54.228238 -170.02633) (xy 54.233572 -169.921174) (xy 54.219348 -169.895774)
			(xy 54.206902 -169.888916) (xy 54.163968 -169.864281) (xy 54.081835 -169.809018) (xy 54.004476 -169.747248)
			(xy 53.932404 -169.679383) (xy 53.8661 -169.605873) (xy 53.806003 -169.527207) (xy 53.752513 -169.443908)
			(xy 53.705985 -169.35653) (xy 53.666729 -169.265652) (xy 53.635004 -169.171878) (xy 53.611023 -169.075832)
			(xy 53.594943 -168.978152) (xy 53.586873 -168.879487) (xy 53.58638 -168.82999) (xy 53.586847 -168.782334)
			(xy 53.594322 -168.687314) (xy 53.609226 -168.593174) (xy 53.631466 -168.500492) (xy 53.660906 -168.409839)
			(xy 53.697364 -168.321775) (xy 53.740615 -168.23684) (xy 53.790394 -168.155559) (xy 53.846394 -168.078432)
			(xy 53.908269 -168.005934) (xy 53.975639 -167.938511) (xy 54.011576 -167.907208) (xy 54.019604 -167.899638)
			(xy 54.028832 -167.879621) (xy 54.029356 -167.8686) (xy 54.029356 -167.791384) (xy 54.028814 -167.780366)
			(xy 54.019598 -167.760348) (xy 54.011576 -167.752776) (xy 53.973951 -167.719953) (xy 53.903628 -167.649062)
			(xy 53.839367 -167.572632) (xy 53.781602 -167.491182) (xy 53.730724 -167.405261) (xy 53.687078 -167.315451)
			(xy 53.650957 -167.222358) (xy 53.622607 -167.126613) (xy 53.602219 -167.028862) (xy 53.589931 -166.929766)
			(xy 53.585826 -166.829996) (xy 53.589932 -166.730226) (xy 53.602221 -166.631131) (xy 53.622609 -166.53338)
			(xy 53.65096 -166.437634) (xy 53.687081 -166.344542) (xy 53.730728 -166.254732) (xy 53.781606 -166.168811)
			(xy 53.839371 -166.087361) (xy 53.903633 -166.010933) (xy 53.973957 -165.940042) (xy 54.011576 -165.907212)
			(xy 54.019605 -165.899642) (xy 54.028834 -165.879625) (xy 54.029356 -165.868604) (xy 54.029356 -165.791388)
			(xy 54.028815 -165.780369) (xy 54.0196 -165.760351) (xy 54.011576 -165.75278) (xy 53.975651 -165.721463)
			(xy 53.908273 -165.654047) (xy 53.846391 -165.581554) (xy 53.790386 -165.504431) (xy 53.740603 -165.423151)
			(xy 53.697348 -165.338218) (xy 53.66089 -165.250153) (xy 53.631451 -165.1595) (xy 53.609214 -165.066817)
			(xy 53.594315 -164.972675) (xy 53.586847 -164.877655) (xy 53.58638 -164.829998) (xy 53.586898 -164.779821)
			(xy 53.595185 -164.67981) (xy 53.611701 -164.580824) (xy 53.636334 -164.48354) (xy 53.668915 -164.388623)
			(xy 53.709223 -164.296719) (xy 53.756982 -164.208458) (xy 53.811865 -164.124442) (xy 53.873498 -164.045244)
			(xy 53.94146 -163.971406) (xy 54.015287 -163.903431) (xy 54.094474 -163.841784) (xy 54.178481 -163.786887)
			(xy 54.266734 -163.739113) (xy 54.358631 -163.69879) (xy 54.453543 -163.666192) (xy 54.550822 -163.641543)
			(xy 54.649805 -163.62501) (xy 54.749815 -163.616707) (xy 54.799992 -163.616132) (xy 54.847653 -163.61661)
			(xy 54.942681 -163.624108) (xy 55.036828 -163.639035) (xy 55.129514 -163.661299) (xy 55.22017 -163.690762)
			(xy 55.308235 -163.727243) (xy 55.393169 -163.770519) (xy 55.474447 -163.820321) (xy 55.55157 -163.876343)
			(xy 55.624062 -163.938241) (xy 55.691477 -164.005633) (xy 55.722774 -164.041582) (xy 55.730343 -164.049612)
			(xy 55.75036 -164.058846) (xy 55.761382 -164.059362) (xy 55.838598 -164.059362) (xy 55.849618 -164.058824)
			(xy 55.869642 -164.049613) (xy 55.877206 -164.041582) (xy 55.908516 -164.005643) (xy 55.97592 -163.938237)
			(xy 56.048404 -163.876327) (xy 56.125522 -163.820294) (xy 56.206798 -163.770484) (xy 56.291731 -163.727204)
			(xy 56.379798 -163.69072) (xy 56.470456 -163.661257) (xy 56.563145 -163.638998) (xy 56.657295 -163.624079)
			(xy 56.752326 -163.616592) (xy 56.799988 -163.616132) (xy 56.850155 -163.616649) (xy 56.950146 -163.624933)
			(xy 57.049112 -163.641445) (xy 57.146377 -163.666072) (xy 57.241275 -163.698646) (xy 57.333161 -163.738945)
			(xy 57.421404 -163.786693) (xy 57.505404 -163.841564) (xy 57.584587 -163.903185) (xy 57.658411 -163.971132)
			(xy 57.726372 -164.044944) (xy 57.788007 -164.124115) (xy 57.842893 -164.208105) (xy 57.890658 -164.29634)
			(xy 57.930973 -164.388218) (xy 57.963565 -164.483111) (xy 57.98821 -164.580371) (xy 58.004739 -164.679333)
			(xy 58.013041 -164.779323) (xy 58.0136 -164.82949) (xy 58.0136 -164.829998) (xy 58.013133 -164.877655)
			(xy 58.005659 -164.972674) (xy 57.990756 -165.066815) (xy 57.968516 -165.159497) (xy 57.939077 -165.25015)
			(xy 57.902619 -165.338215) (xy 57.859368 -165.423149) (xy 57.809589 -165.504431) (xy 57.753589 -165.581558)
			(xy 57.691713 -165.654056) (xy 57.624342 -165.721479) (xy 57.588404 -165.75278) (xy 57.580376 -165.76035)
			(xy 57.571148 -165.780367) (xy 57.570624 -165.791388) (xy 57.570624 -165.868604) (xy 57.571166 -165.879621)
			(xy 57.580389 -165.899633) (xy 57.588404 -165.907212) (xy 57.626027 -165.940036) (xy 57.696347 -166.01093)
			(xy 57.760605 -166.087361) (xy 57.818367 -166.168812) (xy 57.869242 -166.254734) (xy 57.912887 -166.344544)
			(xy 57.949005 -166.437637) (xy 57.977354 -166.533382) (xy 57.997742 -166.631132) (xy 58.010029 -166.730227)
			(xy 58.014135 -166.829996) (xy 58.01003 -166.929765) (xy 57.997743 -167.02886) (xy 57.977356 -167.126611)
			(xy 57.949008 -167.222356) (xy 57.91289 -167.315449) (xy 57.869246 -167.40526) (xy 57.818371 -167.491181)
			(xy 57.76061 -167.572633) (xy 57.696352 -167.649064) (xy 57.626033 -167.719958) (xy 57.588404 -167.752776)
			(xy 57.580376 -167.760346) (xy 57.571146 -167.780363) (xy 57.570624 -167.791384) (xy 57.570624 -167.8686)
			(xy 57.571165 -167.879618) (xy 57.580387 -167.89963) (xy 57.588404 -167.907208) (xy 57.624328 -167.938526)
			(xy 57.691702 -168.005943) (xy 57.753581 -168.078438) (xy 57.809584 -168.155562) (xy 57.859364 -168.236842)
			(xy 57.902616 -168.321775) (xy 57.939073 -168.409839) (xy 57.968511 -168.500492) (xy 57.990747 -168.593174)
			(xy 58.005646 -168.687315) (xy 58.013114 -168.782334) (xy 58.0136 -168.82999) (xy 58.013082 -168.880169)
			(xy 58.004797 -168.980183) (xy 57.988282 -169.079172) (xy 57.96365 -169.176459) (xy 57.931069 -169.27138)
			(xy 57.890763 -169.363287) (xy 57.843005 -169.451553) (xy 57.788123 -169.535573) (xy 57.726491 -169.614775)
			(xy 57.658529 -169.688618) (xy 57.584703 -169.756598) (xy 57.505516 -169.81825) (xy 57.421509 -169.873153)
			(xy 57.333255 -169.920932) (xy 57.241358 -169.961261) (xy 57.146445 -169.993865) (xy 57.049164 -170.018521)
			(xy 56.950179 -170.03506) (xy 56.850166 -170.04337) (xy 56.799988 -170.043856) (xy 56.752327 -170.043377)
			(xy 56.6573 -170.035877) (xy 56.563154 -170.020949) (xy 56.470469 -169.998684) (xy 56.379815 -169.96922)
			(xy 56.291751 -169.932737) (xy 56.206819 -169.889461) (xy 56.125542 -169.839657) (xy 56.04842 -169.783634)
			(xy 55.97593 -169.721735) (xy 55.908517 -169.654343) (xy 55.877206 -169.618406) (xy 55.869635 -169.61038)
			(xy 55.849618 -169.601157) (xy 55.838598 -169.600626) (xy 55.761382 -169.600626) (xy 55.750366 -169.601171)
			(xy 55.730359 -169.610397) (xy 55.722774 -169.618406) (xy 55.689033 -169.657063) (xy 55.616023 -169.72917)
			(xy 55.537189 -169.79486) (xy 55.453094 -169.853664) (xy 55.364338 -169.905164) (xy 55.271553 -169.948992)
			(xy 55.175401 -169.984835) (xy 55.126128 -169.999152) (xy 55.112412 -170.002962) (xy 55.0926 -170.024298)
			(xy 55.070248 -170.1419) (xy 55.080408 -170.168824) (xy 55.092092 -170.177714) (xy 55.12674 -170.204749)
			(xy 55.19109 -170.26461) (xy 55.249223 -170.330526) (xy 55.300572 -170.401853) (xy 55.344636 -170.477897)
			(xy 55.380987 -170.557915) (xy 55.395622 -170.599354) (xy 55.395622 -170.599608) (xy 55.399551 -170.609388)
			(xy 55.413823 -170.624867) (xy 55.433102 -170.63333) (xy 55.443628 -170.633898) (xy 58.743596 -170.633898)
			(xy 58.754128 -170.633372) (xy 58.773415 -170.624903) (xy 58.787668 -170.609393) (xy 58.791602 -170.599608)
			(xy 58.791602 -170.599354) (xy 58.805762 -170.559248) (xy 58.840703 -170.481699) (xy 58.88289 -170.407841)
			(xy 58.931935 -170.338347) (xy 58.987391 -170.273854) (xy 59.048752 -170.21495) (xy 59.115456 -170.162173)
			(xy 59.186894 -170.116007) (xy 59.262414 -170.076872) (xy 59.341326 -170.045126) (xy 59.422907 -170.021059)
			(xy 59.506414 -170.004891) (xy 59.591083 -169.99677) (xy 59.676141 -169.99677) (xy 59.76081 -170.004891)
			(xy 59.844317 -170.021059) (xy 59.925898 -170.045126) (xy 60.00481 -170.076872) (xy 60.08033 -170.116007)
			(xy 60.151768 -170.162173) (xy 60.218472 -170.21495) (xy 60.279833 -170.273854) (xy 60.335289 -170.338347)
			(xy 60.384334 -170.407841) (xy 60.426521 -170.481699) (xy 60.461462 -170.559248) (xy 60.475622 -170.599354)
			(xy 60.475622 -170.599608) (xy 60.479551 -170.609388) (xy 60.493823 -170.624867) (xy 60.513102 -170.63333)
			(xy 60.523628 -170.633898) (xy 63.823596 -170.633898) (xy 63.834128 -170.633372) (xy 63.853415 -170.624903)
			(xy 63.867668 -170.609393) (xy 63.871602 -170.599608) (xy 63.871602 -170.599354) (xy 63.885678 -170.55943)
			(xy 63.920404 -170.482219) (xy 63.962314 -170.408661) (xy 64.011029 -170.339421) (xy 64.066107 -170.275126)
			(xy 64.127049 -170.216361) (xy 64.193303 -170.163656) (xy 64.264268 -170.11749) (xy 64.339301 -170.078281)
			(xy 64.378332 -170.06189) (xy 64.387018 -170.057964) (xy 64.400874 -170.044894) (xy 64.409017 -170.027675)
			(xy 64.410082 -170.018202) (xy 64.416178 -169.927524) (xy 64.416507 -169.918065) (xy 64.41098 -169.899976)
			(xy 64.399254 -169.885135) (xy 64.391286 -169.880026) (xy 64.391032 -169.880026) (xy 64.346929 -169.853796)
			(xy 64.262852 -169.794957) (xy 64.184041 -169.729231) (xy 64.111059 -169.657087) (xy 64.077342 -169.618406)
			(xy 64.069773 -169.610374) (xy 64.049756 -169.601137) (xy 64.038734 -169.600626) (xy 63.961518 -169.600626)
			(xy 63.950499 -169.601163) (xy 63.930481 -169.610381) (xy 63.92291 -169.618406) (xy 63.8916 -169.654346)
			(xy 63.824197 -169.721753) (xy 63.751713 -169.783665) (xy 63.674596 -169.839699) (xy 63.59332 -169.889511)
			(xy 63.508387 -169.932793) (xy 63.42032 -169.969278) (xy 63.329662 -169.998742) (xy 63.236972 -170.021003)
			(xy 63.142822 -170.035924) (xy 63.047791 -170.043412) (xy 63.000128 -170.043856) (xy 62.949959 -170.043339)
			(xy 62.849964 -170.035057) (xy 62.750995 -170.018547) (xy 62.653726 -169.993921) (xy 62.558823 -169.961348)
			(xy 62.466934 -169.921051) (xy 62.378685 -169.873303) (xy 62.294681 -169.818433) (xy 62.215493 -169.756814)
			(xy 62.141664 -169.688867) (xy 62.073697 -169.615056) (xy 62.012057 -169.535885) (xy 61.957163 -169.451895)
			(xy 61.909393 -169.363659) (xy 61.869071 -169.27178) (xy 61.836472 -169.176886) (xy 61.81182 -169.079624)
			(xy 61.795283 -168.980659) (xy 61.786974 -168.880667) (xy 61.786516 -168.830498) (xy 61.786516 -168.82999)
			(xy 61.786983 -168.782334) (xy 61.794459 -168.687315) (xy 61.809362 -168.593175) (xy 61.831603 -168.500493)
			(xy 61.861043 -168.409841) (xy 61.897502 -168.321777) (xy 61.940754 -168.236844) (xy 61.990534 -168.155564)
			(xy 62.046535 -168.078438) (xy 62.108412 -168.005941) (xy 62.175783 -167.93852) (xy 62.211712 -167.907208)
			(xy 62.219736 -167.899636) (xy 62.228956 -167.879619) (xy 62.229492 -167.8686) (xy 62.229492 -167.791384)
			(xy 62.228948 -167.780368) (xy 62.219724 -167.760358) (xy 62.211712 -167.752776) (xy 62.174089 -167.719952)
			(xy 62.103769 -167.649059) (xy 62.039511 -167.572629) (xy 61.981749 -167.491177) (xy 61.930875 -167.405256)
			(xy 61.88723 -167.315446) (xy 61.851112 -167.222354) (xy 61.822764 -167.126609) (xy 61.802377 -167.028859)
			(xy 61.790089 -166.929765) (xy 61.785985 -166.829996) (xy 61.79009 -166.730227) (xy 61.802378 -166.631133)
			(xy 61.822766 -166.533383) (xy 61.851115 -166.437639) (xy 61.887234 -166.344547) (xy 61.930878 -166.254737)
			(xy 61.981754 -166.168816) (xy 62.039516 -166.087365) (xy 62.103774 -166.010935) (xy 62.174094 -165.940043)
			(xy 62.211712 -165.907212) (xy 62.219736 -165.89964) (xy 62.228959 -165.879623) (xy 62.229492 -165.868604)
			(xy 62.229492 -165.791388) (xy 62.228949 -165.780371) (xy 62.219726 -165.76036) (xy 62.211712 -165.75278)
			(xy 62.175788 -165.721462) (xy 62.108414 -165.654045) (xy 62.046535 -165.58155) (xy 61.990533 -165.504426)
			(xy 61.940752 -165.423147) (xy 61.897501 -165.338213) (xy 61.861044 -165.250149) (xy 61.831607 -165.159496)
			(xy 61.809371 -165.066814) (xy 61.794473 -164.972673) (xy 61.787005 -164.877654) (xy 61.786516 -164.829998)
			(xy 61.787034 -164.77982) (xy 61.79532 -164.679807) (xy 61.811836 -164.580819) (xy 61.836469 -164.483533)
			(xy 61.86905 -164.388613) (xy 61.909357 -164.296708) (xy 61.957115 -164.208444) (xy 62.011998 -164.124425)
			(xy 62.07363 -164.045224) (xy 62.141592 -163.971383) (xy 62.215418 -163.903405) (xy 62.294605 -163.841755)
			(xy 62.378612 -163.786854) (xy 62.466865 -163.739076) (xy 62.558762 -163.698748) (xy 62.653674 -163.666146)
			(xy 62.750955 -163.641492) (xy 62.849939 -163.624954) (xy 62.94995 -163.616645) (xy 63.000128 -163.616132)
			(xy 63.047789 -163.616612) (xy 63.142815 -163.624112) (xy 63.23696 -163.639041) (xy 63.329645 -163.661307)
			(xy 63.420299 -163.690773) (xy 63.508362 -163.727256) (xy 63.593294 -163.770532) (xy 63.67457 -163.820336)
			(xy 63.751691 -163.87636) (xy 63.824181 -163.938258) (xy 63.891593 -164.005651) (xy 63.92291 -164.041582)
			(xy 63.930481 -164.049606) (xy 63.950499 -164.058826) (xy 63.961518 -164.059362) (xy 64.038734 -164.059362)
			(xy 64.049751 -164.058817) (xy 64.069763 -164.049597) (xy 64.077342 -164.041582) (xy 64.108652 -164.005644)
			(xy 64.176057 -163.93824) (xy 64.248542 -163.876332) (xy 64.32566 -163.820302) (xy 64.406936 -163.770494)
			(xy 64.49187 -163.727216) (xy 64.579936 -163.690735) (xy 64.670594 -163.661275) (xy 64.763283 -163.639018)
			(xy 64.857432 -163.624102) (xy 64.952462 -163.616617) (xy 65.000124 -163.616132) (xy 65.05029 -163.616651)
			(xy 65.150279 -163.624937) (xy 65.249243 -163.641451) (xy 65.346505 -163.66608) (xy 65.441401 -163.698656)
			(xy 65.533284 -163.738956) (xy 65.621525 -163.786705) (xy 65.705522 -163.841577) (xy 65.784702 -163.903197)
			(xy 65.858523 -163.971145) (xy 65.926482 -164.044956) (xy 65.988115 -164.124126) (xy 66.043 -164.208115)
			(xy 66.090762 -164.296349) (xy 66.131076 -164.388226) (xy 66.163667 -164.483117) (xy 66.188311 -164.580375)
			(xy 66.20484 -164.679336) (xy 66.213141 -164.779324) (xy 66.213736 -164.82949) (xy 66.213736 -164.829998)
			(xy 66.213269 -164.877655) (xy 66.205795 -164.972675) (xy 66.190892 -165.066816) (xy 66.168653 -165.159499)
			(xy 66.139215 -165.250152) (xy 66.102758 -165.338217) (xy 66.059507 -165.423153) (xy 66.009729 -165.504435)
			(xy 65.95373 -165.581564) (xy 65.891855 -165.654063) (xy 65.824486 -165.721487) (xy 65.78854 -165.75278)
			(xy 65.780521 -165.760355) (xy 65.771304 -165.78037) (xy 65.77076 -165.791388) (xy 65.77076 -165.868604)
			(xy 65.7713 -165.879623) (xy 65.780515 -165.899642) (xy 65.78854 -165.907212) (xy 65.82697 -165.940715)
			(xy 65.898682 -166.013199) (xy 65.964058 -166.091444) (xy 66.022637 -166.1749) (xy 66.074006 -166.262977)
			(xy 66.096388 -166.308786) (xy 66.101452 -166.318178) (xy 66.11759 -166.332102) (xy 66.12763 -166.33571)
			(xy 66.199258 -166.3573) (xy 66.209525 -166.359844) (xy 66.230505 -166.35734) (xy 66.239898 -166.352474)
			(xy 66.28586 -166.325669) (xy 66.380963 -166.277934) (xy 66.479237 -166.237121) (xy 66.580177 -166.203441)
			(xy 66.683267 -166.177064) (xy 66.787979 -166.158126) (xy 66.893777 -166.146725) (xy 67.00012 -166.142918)
			(xy 67.106463 -166.146725) (xy 67.212261 -166.158126) (xy 67.316973 -166.177064) (xy 67.420063 -166.203441)
			(xy 67.521003 -166.237121) (xy 67.619277 -166.277934) (xy 67.71438 -166.325669) (xy 67.760342 -166.352474)
			(xy 67.769682 -166.357501) (xy 67.790727 -166.36001) (xy 67.800982 -166.3573) (xy 67.87261 -166.33571)
			(xy 67.882696 -166.33218) (xy 67.898864 -166.318237) (xy 67.903852 -166.308786) (xy 67.926229 -166.262975)
			(xy 67.977606 -166.174903) (xy 68.036189 -166.091451) (xy 68.101565 -166.013206) (xy 68.173274 -165.94072)
			(xy 68.2117 -165.907212) (xy 68.219726 -165.899641) (xy 68.228951 -165.879624) (xy 68.22948 -165.868604)
			(xy 68.22948 -165.791388) (xy 68.228937 -165.780371) (xy 68.219712 -165.760362) (xy 68.2117 -165.75278)
			(xy 68.175777 -165.721462) (xy 68.108403 -165.654044) (xy 68.046524 -165.58155) (xy 67.990523 -165.504425)
			(xy 67.940743 -165.423146) (xy 67.897492 -165.338212) (xy 67.861035 -165.250148) (xy 67.831599 -165.159496)
			(xy 67.809363 -165.066814) (xy 67.794465 -164.972673) (xy 67.786997 -164.877654) (xy 67.786504 -164.829998)
			(xy 67.787022 -164.77982) (xy 67.795308 -164.679806) (xy 67.811824 -164.580818) (xy 67.836457 -164.483532)
			(xy 67.869038 -164.388612) (xy 67.909345 -164.296706) (xy 67.957103 -164.208441) (xy 68.011985 -164.124422)
			(xy 68.073618 -164.045221) (xy 68.141579 -163.971379) (xy 68.215405 -163.9034) (xy 68.294592 -163.841749)
			(xy 68.378599 -163.786847) (xy 68.466852 -163.739069) (xy 68.558749 -163.69874) (xy 68.653662 -163.666137)
			(xy 68.750942 -163.641482) (xy 68.849926 -163.624943) (xy 68.949938 -163.616634) (xy 69.000116 -163.616132)
			(xy 69.047777 -163.616611) (xy 69.142804 -163.624111) (xy 69.23695 -163.639039) (xy 69.329635 -163.661304)
			(xy 69.420289 -163.690769) (xy 69.508353 -163.727252) (xy 69.593285 -163.770528) (xy 69.674562 -163.820331)
			(xy 69.751684 -163.876354) (xy 69.824175 -163.938253) (xy 69.891588 -164.005645) (xy 69.922898 -164.041582)
			(xy 69.930468 -164.049609) (xy 69.950486 -164.058833) (xy 69.961506 -164.059362) (xy 70.038722 -164.059362)
			(xy 70.04974 -164.058819) (xy 70.069756 -164.049602) (xy 70.07733 -164.041582) (xy 70.10864 -164.005644)
			(xy 70.176045 -163.938239) (xy 70.248529 -163.876331) (xy 70.325647 -163.820299) (xy 70.406924 -163.770491)
			(xy 70.491857 -163.727212) (xy 70.579924 -163.69073) (xy 70.670581 -163.661269) (xy 70.76327 -163.639012)
			(xy 70.85742 -163.624094) (xy 70.95245 -163.616609) (xy 71.000112 -163.616132) (xy 71.050278 -163.61665)
			(xy 71.150268 -163.624936) (xy 71.249232 -163.641449) (xy 71.346495 -163.666077) (xy 71.441392 -163.698653)
			(xy 71.533276 -163.738952) (xy 71.621518 -163.786701) (xy 71.705516 -163.841573) (xy 71.784697 -163.903193)
			(xy 71.858519 -163.971141) (xy 71.926479 -164.044952) (xy 71.988112 -164.124123) (xy 72.042998 -164.208112)
			(xy 72.090761 -164.296346) (xy 72.131075 -164.388223) (xy 72.163666 -164.483115) (xy 72.18831 -164.580374)
			(xy 72.20484 -164.679335) (xy 72.213141 -164.779324) (xy 72.213724 -164.82949) (xy 72.213724 -164.829998)
			(xy 72.213257 -164.877655) (xy 72.205783 -164.972675) (xy 72.19088 -165.066816) (xy 72.168641 -165.159498)
			(xy 72.139202 -165.250151) (xy 72.102745 -165.338217) (xy 72.059494 -165.423152) (xy 72.009715 -165.504434)
			(xy 71.953716 -165.581562) (xy 71.891841 -165.654061) (xy 71.824471 -165.721484) (xy 71.788528 -165.75278)
			(xy 71.780497 -165.760349) (xy 71.771264 -165.780366) (xy 71.770748 -165.791388) (xy 71.770748 -165.868604)
			(xy 71.771287 -165.879623) (xy 71.780501 -165.899644) (xy 71.788528 -165.907212) (xy 71.826153 -165.940035)
			(xy 71.896477 -166.010927) (xy 71.960739 -166.087356) (xy 72.018505 -166.168807) (xy 72.069383 -166.254728)
			(xy 72.11303 -166.344539) (xy 72.149152 -166.437632) (xy 72.177502 -166.533378) (xy 72.197891 -166.631129)
			(xy 72.21018 -166.730225) (xy 72.214285 -166.829996) (xy 72.21018 -166.929767) (xy 72.197892 -167.028863)
			(xy 72.177504 -167.126615) (xy 72.149154 -167.222361) (xy 72.113034 -167.315454) (xy 72.069387 -167.405265)
			(xy 72.018509 -167.491187) (xy 71.960744 -167.572638) (xy 71.896483 -167.649068) (xy 71.826159 -167.71996)
			(xy 71.788528 -167.752776) (xy 71.780497 -167.760345) (xy 71.771262 -167.780362) (xy 71.770748 -167.791384)
			(xy 71.770748 -167.8686) (xy 71.771287 -167.87962) (xy 71.780499 -167.899642) (xy 71.788528 -167.907208)
			(xy 71.824454 -167.938525) (xy 71.891832 -168.00594) (xy 71.953714 -168.078433) (xy 72.00972 -168.155557)
			(xy 72.059504 -168.236836) (xy 72.102759 -168.32177) (xy 72.139218 -168.409834) (xy 72.168658 -168.500488)
			(xy 72.190896 -168.593171) (xy 72.205795 -168.687313) (xy 72.213264 -168.782333) (xy 72.213724 -168.82999)
			(xy 72.213206 -168.880167) (xy 72.204921 -168.98018) (xy 72.188405 -169.079166) (xy 72.163773 -169.176451)
			(xy 72.131192 -169.271369) (xy 72.090885 -169.363274) (xy 72.043127 -169.451536) (xy 71.988244 -169.535553)
			(xy 71.926611 -169.614752) (xy 71.858649 -169.688592) (xy 71.784822 -169.756567) (xy 71.705634 -169.818215)
			(xy 71.621627 -169.873113) (xy 71.533373 -169.920887) (xy 71.441476 -169.961211) (xy 71.346564 -169.99381)
			(xy 71.249283 -170.01846) (xy 71.1503 -170.034993) (xy 71.050289 -170.043297) (xy 71.000112 -170.043856)
			(xy 70.952451 -170.043378) (xy 70.857423 -170.03588) (xy 70.763276 -170.020954) (xy 70.67059 -169.99869)
			(xy 70.579934 -169.969227) (xy 70.491869 -169.932745) (xy 70.406935 -169.88947) (xy 70.325657 -169.839667)
			(xy 70.248534 -169.783645) (xy 70.176042 -169.721747) (xy 70.108628 -169.654354) (xy 70.07733 -169.618406)
			(xy 70.06976 -169.610377) (xy 70.049744 -169.601144) (xy 70.038722 -169.600626) (xy 69.961506 -169.600626)
			(xy 69.950488 -169.601166) (xy 69.930474 -169.610387) (xy 69.922898 -169.618406) (xy 69.891435 -169.654489)
			(xy 69.823682 -169.722135) (xy 69.750819 -169.784245) (xy 69.712332 -169.812716) (xy 69.69887 -169.822622)
			(xy 69.68871 -169.854118) (xy 69.730366 -169.97807) (xy 69.757544 -169.99712) (xy 69.774308 -169.996612)
			(xy 69.793612 -169.996358) (xy 69.836136 -169.99686) (xy 69.920794 -170.004989) (xy 70.004291 -170.021162)
			(xy 70.085862 -170.04523) (xy 70.164763 -170.076976) (xy 70.240273 -170.116108) (xy 70.311704 -170.162269)
			(xy 70.378402 -170.215037) (xy 70.439758 -170.273932) (xy 70.495213 -170.338414) (xy 70.544259 -170.407895)
			(xy 70.586449 -170.48174) (xy 70.621398 -170.559276) (xy 70.635622 -170.599354) (xy 70.635622 -170.599608)
			(xy 70.639551 -170.609388) (xy 70.653823 -170.624867) (xy 70.673102 -170.63333) (xy 70.683628 -170.633898)
			(xy 73.983596 -170.633898) (xy 73.994128 -170.633372) (xy 74.013415 -170.624903) (xy 74.027668 -170.609393)
			(xy 74.031602 -170.599608) (xy 74.031602 -170.599354) (xy 74.045706 -170.559465) (xy 74.080448 -170.482313)
			(xy 74.122357 -170.408807) (xy 74.171055 -170.339613) (xy 74.226102 -170.275354) (xy 74.287002 -170.216612)
			(xy 74.353203 -170.163917) (xy 74.424108 -170.117744) (xy 74.46137 -170.097704) (xy 74.474324 -170.090846)
			(xy 74.488548 -170.066716) (xy 74.487532 -169.96156) (xy 74.487013 -169.952266) (xy 74.480199 -169.93496)
			(xy 74.467689 -169.921195) (xy 74.459592 -169.916602) (xy 74.459338 -169.916602) (xy 74.41651 -169.894752)
			(xy 74.334095 -169.84522) (xy 74.255858 -169.789323) (xy 74.182287 -169.727412) (xy 74.113845 -169.659874)
			(xy 74.050961 -169.587133) (xy 73.994029 -169.509645) (xy 73.943406 -169.427896) (xy 73.899409 -169.342398)
			(xy 73.862314 -169.253688) (xy 73.832353 -169.16232) (xy 73.809715 -169.068869) (xy 73.794542 -168.973919)
			(xy 73.786927 -168.878067) (xy 73.786492 -168.82999) (xy 73.786959 -168.782334) (xy 73.794435 -168.687314)
			(xy 73.809338 -168.593174) (xy 73.831578 -168.500492) (xy 73.861018 -168.40984) (xy 73.897476 -168.321776)
			(xy 73.940728 -168.236841) (xy 73.990508 -168.155561) (xy 74.046508 -168.078434) (xy 74.108383 -168.005936)
			(xy 74.175754 -167.938514) (xy 74.211688 -167.907208) (xy 74.219715 -167.899637) (xy 74.22894 -167.87962)
			(xy 74.229468 -167.8686) (xy 74.229468 -167.791384) (xy 74.228924 -167.780368) (xy 74.219697 -167.760361)
			(xy 74.211688 -167.752776) (xy 74.174065 -167.719951) (xy 74.103747 -167.649058) (xy 74.03949 -167.572627)
			(xy 73.98173 -167.491176) (xy 73.930856 -167.405255) (xy 73.887213 -167.315445) (xy 73.851095 -167.222353)
			(xy 73.822747 -167.126608) (xy 73.802361 -167.028859) (xy 73.790074 -166.929765) (xy 73.785969 -166.829996)
			(xy 73.790074 -166.730228) (xy 73.802362 -166.631134) (xy 73.822749 -166.533384) (xy 73.851098 -166.43764)
			(xy 73.887216 -166.344548) (xy 73.93086 -166.254738) (xy 73.981734 -166.168818) (xy 74.039495 -166.087367)
			(xy 74.103752 -166.010936) (xy 74.174071 -165.940043) (xy 74.211688 -165.907212) (xy 74.219715 -165.899642)
			(xy 74.228942 -165.879625) (xy 74.229468 -165.868604) (xy 74.229468 -165.791388) (xy 74.228924 -165.780372)
			(xy 74.219698 -165.760364) (xy 74.211688 -165.75278) (xy 74.175765 -165.721462) (xy 74.108392 -165.654044)
			(xy 74.046514 -165.581549) (xy 73.990513 -165.504424) (xy 73.940733 -165.423145) (xy 73.897483 -165.338211)
			(xy 73.861027 -165.250147) (xy 73.83159 -165.159495) (xy 73.809355 -165.066813) (xy 73.794457 -164.972673)
			(xy 73.78699 -164.877654) (xy 73.786492 -164.829998) (xy 73.78701 -164.77982) (xy 73.795296 -164.679806)
			(xy 73.811812 -164.580817) (xy 73.836445 -164.483531) (xy 73.869026 -164.38861) (xy 73.909333 -164.296704)
			(xy 73.957091 -164.208439) (xy 74.011973 -164.124419) (xy 74.073605 -164.045217) (xy 74.141566 -163.971374)
			(xy 74.215393 -163.903395) (xy 74.294579 -163.841744) (xy 74.378586 -163.786841) (xy 74.466839 -163.739062)
			(xy 74.558736 -163.698733) (xy 74.653649 -163.666129) (xy 74.75093 -163.641473) (xy 74.849914 -163.624933)
			(xy 74.949926 -163.616622) (xy 75.000104 -163.616132) (xy 75.047765 -163.616611) (xy 75.142792 -163.62411)
			(xy 75.236939 -163.639037) (xy 75.329625 -163.661301) (xy 75.420279 -163.690765) (xy 75.508344 -163.727248)
			(xy 75.593277 -163.770523) (xy 75.674555 -163.820326) (xy 75.751677 -163.876349) (xy 75.824168 -163.938247)
			(xy 75.891583 -164.005639) (xy 75.922886 -164.041582) (xy 75.930456 -164.04961) (xy 75.950473 -164.058839)
			(xy 75.961494 -164.059362) (xy 76.03871 -164.059362) (xy 76.049729 -164.058822) (xy 76.069749 -164.049608)
			(xy 76.077318 -164.041582) (xy 76.108628 -164.005643) (xy 76.176032 -163.938238) (xy 76.248517 -163.876329)
			(xy 76.325635 -163.820297) (xy 76.406911 -163.770488) (xy 76.491844 -163.727208) (xy 76.579911 -163.690725)
			(xy 76.670568 -163.661263) (xy 76.763258 -163.639005) (xy 76.857408 -163.624086) (xy 76.952438 -163.6166)
			(xy 77.0001 -163.616132) (xy 77.050267 -163.61665) (xy 77.150257 -163.624934) (xy 77.249222 -163.641447)
			(xy 77.346486 -163.666075) (xy 77.441384 -163.698649) (xy 77.533268 -163.738948) (xy 77.621511 -163.786697)
			(xy 77.70551 -163.841569) (xy 77.784692 -163.903189) (xy 77.858515 -163.971137) (xy 77.926475 -164.044948)
			(xy 77.988109 -164.124119) (xy 78.042995 -164.208108) (xy 78.090759 -164.296343) (xy 78.131074 -164.38822)
			(xy 78.163665 -164.483113) (xy 78.18831 -164.580372) (xy 78.20484 -164.679334) (xy 78.213141 -164.779324)
			(xy 78.213712 -164.82949) (xy 78.213712 -164.829998) (xy 78.213245 -164.877655) (xy 78.205771 -164.972674)
			(xy 78.190868 -165.066815) (xy 78.168629 -165.159498) (xy 78.13919 -165.250151) (xy 78.102732 -165.338216)
			(xy 78.059481 -165.423151) (xy 78.009702 -165.504432) (xy 77.953702 -165.58156) (xy 77.891827 -165.654058)
			(xy 77.824457 -165.721481) (xy 77.788516 -165.75278) (xy 77.780487 -165.76035) (xy 77.771256 -165.780367)
			(xy 77.770736 -165.791388) (xy 77.770736 -165.868604) (xy 77.771279 -165.879621) (xy 77.780503 -165.899631)
			(xy 77.788516 -165.907212) (xy 77.826139 -165.940037) (xy 77.896458 -166.01093) (xy 77.960716 -166.087361)
			(xy 78.018477 -166.168813) (xy 78.069352 -166.254734) (xy 78.112996 -166.344545) (xy 78.149114 -166.437637)
			(xy 78.177462 -166.533382) (xy 78.19785 -166.631132) (xy 78.210137 -166.730227) (xy 78.214243 -166.829996)
			(xy 78.210138 -166.929765) (xy 78.197851 -167.02886) (xy 78.177464 -167.12661) (xy 78.149116 -167.222355)
			(xy 78.112999 -167.315448) (xy 78.069355 -167.405259) (xy 78.018481 -167.49118) (xy 77.96072 -167.572632)
			(xy 77.896463 -167.649064) (xy 77.826145 -167.719958) (xy 77.788516 -167.752776) (xy 77.780486 -167.760345)
			(xy 77.771254 -167.780362) (xy 77.770736 -167.791384) (xy 77.770736 -167.8686) (xy 77.771278 -167.879617)
			(xy 77.780501 -167.899628) (xy 77.788516 -167.907208) (xy 77.826739 -167.940564) (xy 77.898101 -168.012681)
			(xy 77.963195 -168.090502) (xy 78.021569 -168.173483) (xy 78.072814 -168.261046) (xy 78.116574 -168.35258)
			(xy 78.152543 -168.447446) (xy 78.18047 -168.544983) (xy 78.200161 -168.64451) (xy 78.206346 -168.694862)
			(xy 78.208011 -168.705286) (xy 78.218537 -168.723555) (xy 78.235531 -168.736036) (xy 78.245716 -168.738804)
			(xy 78.339696 -168.759632) (xy 78.350041 -168.76138) (xy 78.370603 -168.75733) (xy 78.387838 -168.745406)
			(xy 78.393798 -168.736772) (xy 78.441296 -168.658537) (xy 78.529916 -168.498373) (xy 78.611087 -168.334308)
			(xy 78.684636 -168.166689) (xy 78.75041 -167.995868) (xy 78.808269 -167.822206) (xy 78.858092 -167.646071)
			(xy 78.899772 -167.467833) (xy 78.933222 -167.287869) (xy 78.958372 -167.106559) (xy 78.975168 -166.924284)
			(xy 78.983576 -166.741431) (xy 78.984094 -166.649908) (xy 78.984094 -166.360094) (xy 78.965298 -166.333932)
			(xy 78.949804 -166.328598) (xy 78.909724 -166.314413) (xy 78.83223 -166.279428) (xy 78.758427 -166.237208)
			(xy 78.68899 -166.188139) (xy 78.624551 -166.132668) (xy 78.565699 -166.071302) (xy 78.512971 -166.004601)
			(xy 78.466848 -165.933172) (xy 78.427751 -165.857669) (xy 78.396036 -165.77878) (xy 78.371994 -165.697224)
			(xy 78.355842 -165.613747) (xy 78.34773 -165.529109) (xy 78.34773 -165.444083) (xy 78.355843 -165.359446)
			(xy 78.371995 -165.275968) (xy 78.396039 -165.194413) (xy 78.427754 -165.115524) (xy 78.466852 -165.040021)
			(xy 78.512976 -164.968593) (xy 78.565704 -164.901892) (xy 78.624557 -164.840526) (xy 78.688996 -164.785056)
			(xy 78.758434 -164.735988) (xy 78.832237 -164.693769) (xy 78.909732 -164.658784) (xy 78.949804 -164.644578)
			(xy 78.965298 -164.639244) (xy 78.984094 -164.613082) (xy 78.984094 -161.299906) (xy 78.9846 -161.209783)
			(xy 78.992686 -161.02972) (xy 79.008843 -160.8502) (xy 79.033037 -160.671586) (xy 79.065221 -160.494237)
			(xy 79.105329 -160.318511) (xy 79.153281 -160.144761) (xy 79.208979 -159.973337) (xy 79.272313 -159.804585)
			(xy 79.343153 -159.638844) (xy 79.421359 -159.476449) (xy 79.506771 -159.317726) (xy 79.599218 -159.162994)
			(xy 79.698514 -159.012566) (xy 79.80446 -158.866744) (xy 79.916841 -158.725822) (xy 80.035431 -158.590085)
			(xy 80.159991 -158.459804) (xy 80.290271 -158.335243) (xy 80.426009 -158.216652) (xy 80.56693 -158.104271)
			(xy 80.712751 -157.998325) (xy 80.863179 -157.899028) (xy 81.01791 -157.80658) (xy 81.176633 -157.721167)
			(xy 81.339028 -157.642961) (xy 81.504768 -157.572119) (xy 81.67352 -157.508785) (xy 81.844944 -157.453086)
			(xy 82.018693 -157.405134) (xy 82.194419 -157.365025) (xy 82.371768 -157.33284) (xy 82.550382 -157.308645)
			(xy 82.729902 -157.292487) (xy 82.909965 -157.2844) (xy 83.000088 -157.283912) (xy 83.256882 -157.283912)
			(xy 83.28406 -157.263084) (xy 83.288632 -157.246574) (xy 83.30005 -157.206781) (xy 83.329295 -157.129326)
			(xy 83.365612 -157.054924) (xy 83.408685 -156.984219) (xy 83.458141 -156.917822) (xy 83.513554 -156.856308)
			(xy 83.574443 -156.800209) (xy 83.640281 -156.750012) (xy 83.7105 -156.706149) (xy 83.78449 -156.669001)
			(xy 83.861612 -156.638889) (xy 83.941198 -156.616074) (xy 84.02256 -156.600753) (xy 84.104994 -156.593058)
			(xy 84.14639 -156.592524) (xy 84.190299 -156.593054) (xy 84.27769 -156.601708) (xy 84.363802 -156.618934)
			(xy 84.447797 -156.644562) (xy 84.528857 -156.678345) (xy 84.606193 -156.719952) (xy 84.679052 -156.768979)
			(xy 84.746724 -156.824948) (xy 84.80855 -156.887314) (xy 84.863928 -156.955471) (xy 84.888578 -156.991812)
			(xy 84.895425 -157.001196) (xy 84.915398 -157.013007) (xy 84.938531 -157.014831) (xy 84.949538 -157.011116)
			(xy 85.028187 -156.979904) (xy 85.183051 -156.91167) (xy 85.334879 -156.836923) (xy 85.483397 -156.755799)
			(xy 85.628337 -156.668442) (xy 85.769438 -156.575012) (xy 85.906446 -156.475676) (xy 86.039113 -156.370613)
			(xy 86.10346 -156.315664) (xy 86.111877 -156.307763) (xy 86.121106 -156.286628) (xy 86.12014 -156.263587)
			(xy 86.115144 -156.25318) (xy 86.094763 -156.214247) (xy 86.0609 -156.133149) (xy 86.035206 -156.049105)
			(xy 86.017931 -155.962935) (xy 86.009244 -155.875482) (xy 86.008718 -155.83154) (xy 86.009176 -155.790436)
			(xy 86.016758 -155.708579) (xy 86.031861 -155.62777) (xy 86.054356 -155.5487) (xy 86.08405 -155.472042)
			(xy 86.120692 -155.398452) (xy 86.163967 -155.328557) (xy 86.213508 -155.262953) (xy 86.26889 -155.2022)
			(xy 86.329642 -155.146817) (xy 86.395245 -155.097275) (xy 86.46514 -155.053999) (xy 86.53873 -155.017356)
			(xy 86.615386 -154.98766) (xy 86.694456 -154.965164) (xy 86.775265 -154.95006) (xy 86.857122 -154.942477)
			(xy 86.898226 -154.942032) (xy 86.89848 -154.942032) (xy 86.943632 -154.942586) (xy 87.03347 -154.951748)
			(xy 87.077804 -154.96032) (xy 87.088218 -154.961336) (xy 87.097967 -154.960907) (xy 87.116052 -154.953625)
			(xy 87.130086 -154.940093) (xy 87.134446 -154.931364) (xy 87.172195 -154.845944) (xy 87.240623 -154.672155)
			(xy 87.300833 -154.495351) (xy 87.352694 -154.315921) (xy 87.39609 -154.134257) (xy 87.430927 -153.950759)
			(xy 87.457128 -153.765831) (xy 87.474635 -153.579878) (xy 87.483411 -153.393309) (xy 87.48395 -153.299922)
			(xy 87.48395 -152.024842) (xy 87.483435 -152.014266) (xy 87.474913 -151.994911) (xy 87.459273 -151.980676)
			(xy 87.449406 -151.976836) (xy 87.409233 -151.962711) (xy 87.331545 -151.92782) (xy 87.257548 -151.885665)
			(xy 87.187919 -151.83663) (xy 87.123295 -151.781165) (xy 87.064268 -151.719777) (xy 87.011379 -151.653028)
			(xy 86.965111 -151.58153) (xy 86.925889 -151.505937) (xy 86.894071 -151.426941) (xy 86.869949 -151.345266)
			(xy 86.853744 -151.26166) (xy 86.845604 -151.176887) (xy 86.845603 -151.091724) (xy 86.853742 -151.006952)
			(xy 86.869946 -150.923345) (xy 86.894067 -150.84167) (xy 86.925884 -150.762674) (xy 86.965105 -150.68708)
			(xy 87.011372 -150.615582) (xy 87.06426 -150.548832) (xy 87.123286 -150.487443) (xy 87.18791 -150.431977)
			(xy 87.257538 -150.382941) (xy 87.331535 -150.340785) (xy 87.409222 -150.305894) (xy 87.449406 -150.2918)
			(xy 87.45924 -150.287907) (xy 87.474843 -150.273661) (xy 87.483425 -150.254355) (xy 87.48395 -150.243794)
			(xy 87.48395 -146.944842) (xy 87.483435 -146.934266) (xy 87.474913 -146.914911) (xy 87.459273 -146.900676)
			(xy 87.449406 -146.896836) (xy 87.409233 -146.882711) (xy 87.331545 -146.84782) (xy 87.257548 -146.805665)
			(xy 87.187919 -146.75663) (xy 87.123295 -146.701165) (xy 87.064268 -146.639777) (xy 87.011379 -146.573028)
			(xy 86.965111 -146.50153) (xy 86.925889 -146.425937) (xy 86.894071 -146.346941) (xy 86.869949 -146.265266)
			(xy 86.853744 -146.18166) (xy 86.845604 -146.096887) (xy 86.845603 -146.011724) (xy 86.853742 -145.926952)
			(xy 86.869946 -145.843345) (xy 86.894067 -145.76167) (xy 86.925884 -145.682674) (xy 86.965105 -145.60708)
			(xy 87.011372 -145.535582) (xy 87.06426 -145.468832) (xy 87.123286 -145.407443) (xy 87.18791 -145.351977)
			(xy 87.257538 -145.302941) (xy 87.331535 -145.260785) (xy 87.409222 -145.225894) (xy 87.449406 -145.2118)
			(xy 87.45924 -145.207907) (xy 87.474843 -145.193661) (xy 87.483425 -145.174355) (xy 87.48395 -145.163794)
			(xy 87.48395 -141.864842) (xy 87.483435 -141.854266) (xy 87.474913 -141.834911) (xy 87.459273 -141.820676)
			(xy 87.449406 -141.816836) (xy 87.409233 -141.802711) (xy 87.331545 -141.76782) (xy 87.257548 -141.725665)
			(xy 87.187919 -141.67663) (xy 87.123295 -141.621165) (xy 87.064268 -141.559777) (xy 87.011379 -141.493028)
			(xy 86.965111 -141.42153) (xy 86.925889 -141.345937) (xy 86.894071 -141.266941) (xy 86.869949 -141.185266)
			(xy 86.853744 -141.10166) (xy 86.845604 -141.016887) (xy 86.845603 -140.931724) (xy 86.853742 -140.846952)
			(xy 86.869946 -140.763345) (xy 86.894067 -140.68167) (xy 86.925884 -140.602674) (xy 86.965105 -140.52708)
			(xy 87.011372 -140.455582) (xy 87.06426 -140.388832) (xy 87.123286 -140.327443) (xy 87.18791 -140.271977)
			(xy 87.257538 -140.222941) (xy 87.331535 -140.180785) (xy 87.409222 -140.145894) (xy 87.449406 -140.1318)
			(xy 87.45924 -140.127907) (xy 87.474843 -140.113661) (xy 87.483425 -140.094355) (xy 87.48395 -140.083794)
			(xy 87.48395 -136.784842) (xy 87.483435 -136.774266) (xy 87.474913 -136.754911) (xy 87.459273 -136.740676)
			(xy 87.449406 -136.736836) (xy 87.409233 -136.722711) (xy 87.331545 -136.68782) (xy 87.257548 -136.645665)
			(xy 87.187919 -136.59663) (xy 87.123295 -136.541165) (xy 87.064268 -136.479777) (xy 87.011379 -136.413028)
			(xy 86.965111 -136.34153) (xy 86.925889 -136.265937) (xy 86.894071 -136.186941) (xy 86.869949 -136.105266)
			(xy 86.853744 -136.02166) (xy 86.845604 -135.936887) (xy 86.845603 -135.851724) (xy 86.853742 -135.766952)
			(xy 86.869946 -135.683345) (xy 86.894067 -135.60167) (xy 86.925884 -135.522674) (xy 86.965105 -135.44708)
			(xy 87.011372 -135.375582) (xy 87.06426 -135.308832) (xy 87.123286 -135.247443) (xy 87.18791 -135.191977)
			(xy 87.257538 -135.142941) (xy 87.331535 -135.100785) (xy 87.409222 -135.065894) (xy 87.449406 -135.0518)
			(xy 87.45924 -135.047907) (xy 87.474843 -135.033661) (xy 87.483425 -135.014355) (xy 87.48395 -135.003794)
			(xy 87.48395 -131.704842) (xy 87.483435 -131.694266) (xy 87.474913 -131.674911) (xy 87.459273 -131.660676)
			(xy 87.449406 -131.656836) (xy 87.409233 -131.642711) (xy 87.331545 -131.60782) (xy 87.257548 -131.565665)
			(xy 87.187919 -131.51663) (xy 87.123295 -131.461165) (xy 87.064268 -131.399777) (xy 87.011379 -131.333028)
			(xy 86.965111 -131.26153) (xy 86.925889 -131.185937) (xy 86.894071 -131.106941) (xy 86.869949 -131.025266)
			(xy 86.853744 -130.94166) (xy 86.845604 -130.856887) (xy 86.845603 -130.771724) (xy 86.853742 -130.686952)
			(xy 86.869946 -130.603345) (xy 86.894067 -130.52167) (xy 86.925884 -130.442674) (xy 86.965105 -130.36708)
			(xy 87.011372 -130.295582) (xy 87.06426 -130.228832) (xy 87.123286 -130.167443) (xy 87.18791 -130.111977)
			(xy 87.257538 -130.062941) (xy 87.331535 -130.020785) (xy 87.409222 -129.985894) (xy 87.449406 -129.9718)
			(xy 87.45924 -129.967907) (xy 87.474843 -129.953661) (xy 87.483425 -129.934355) (xy 87.48395 -129.923794)
			(xy 87.48395 -126.624842) (xy 87.483435 -126.614266) (xy 87.474913 -126.594911) (xy 87.459273 -126.580676)
			(xy 87.449406 -126.576836) (xy 87.409233 -126.562711) (xy 87.331545 -126.52782) (xy 87.257548 -126.485665)
			(xy 87.187919 -126.43663) (xy 87.123295 -126.381165) (xy 87.064268 -126.319777) (xy 87.011379 -126.253028)
			(xy 86.965111 -126.18153) (xy 86.925889 -126.105937) (xy 86.894071 -126.026941) (xy 86.869949 -125.945266)
			(xy 86.853744 -125.86166) (xy 86.845604 -125.776887) (xy 86.845603 -125.691724) (xy 86.853742 -125.606952)
			(xy 86.869946 -125.523345) (xy 86.894067 -125.44167) (xy 86.925884 -125.362674) (xy 86.965105 -125.28708)
			(xy 87.011372 -125.215582) (xy 87.06426 -125.148832) (xy 87.123286 -125.087443) (xy 87.18791 -125.031977)
			(xy 87.257538 -124.982941) (xy 87.331535 -124.940785) (xy 87.409222 -124.905894) (xy 87.449406 -124.8918)
			(xy 87.45924 -124.887907) (xy 87.474843 -124.873661) (xy 87.483425 -124.854355) (xy 87.48395 -124.843794)
			(xy 87.48395 -121.544842) (xy 87.483435 -121.534266) (xy 87.474913 -121.514911) (xy 87.459273 -121.500676)
			(xy 87.449406 -121.496836) (xy 87.409233 -121.482711) (xy 87.331545 -121.44782) (xy 87.257548 -121.405665)
			(xy 87.187919 -121.35663) (xy 87.123295 -121.301165) (xy 87.064268 -121.239777) (xy 87.011379 -121.173028)
			(xy 86.965111 -121.10153) (xy 86.925889 -121.025937) (xy 86.894071 -120.946941) (xy 86.869949 -120.865266)
			(xy 86.853744 -120.78166) (xy 86.845604 -120.696887) (xy 86.845603 -120.611724) (xy 86.853742 -120.526952)
			(xy 86.869946 -120.443345) (xy 86.894067 -120.36167) (xy 86.925884 -120.282674) (xy 86.965105 -120.20708)
			(xy 87.011372 -120.135582) (xy 87.06426 -120.068832) (xy 87.123286 -120.007443) (xy 87.18791 -119.951977)
			(xy 87.257538 -119.902941) (xy 87.331535 -119.860785) (xy 87.409222 -119.825894) (xy 87.449406 -119.8118)
			(xy 87.45924 -119.807907) (xy 87.474843 -119.793661) (xy 87.483425 -119.774355) (xy 87.48395 -119.763794)
			(xy 87.48395 -116.464842) (xy 87.483435 -116.454266) (xy 87.474913 -116.434911) (xy 87.459273 -116.420676)
			(xy 87.449406 -116.416836) (xy 87.409233 -116.402711) (xy 87.331545 -116.36782) (xy 87.257548 -116.325665)
			(xy 87.187919 -116.27663) (xy 87.123295 -116.221165) (xy 87.064268 -116.159777) (xy 87.011379 -116.093028)
			(xy 86.965111 -116.02153) (xy 86.925889 -115.945937) (xy 86.894071 -115.866941) (xy 86.869949 -115.785266)
			(xy 86.853744 -115.70166) (xy 86.845604 -115.616887) (xy 86.845603 -115.531724) (xy 86.853742 -115.446952)
			(xy 86.869946 -115.363345) (xy 86.894067 -115.28167) (xy 86.925884 -115.202674) (xy 86.965105 -115.12708)
			(xy 87.011372 -115.055582) (xy 87.06426 -114.988832) (xy 87.123286 -114.927443) (xy 87.18791 -114.871977)
			(xy 87.257538 -114.822941) (xy 87.331535 -114.780785) (xy 87.409222 -114.745894) (xy 87.449406 -114.7318)
			(xy 87.45924 -114.727907) (xy 87.474843 -114.713661) (xy 87.483425 -114.694355) (xy 87.48395 -114.683794)
			(xy 87.48395 -111.384842) (xy 87.483435 -111.374266) (xy 87.474913 -111.354911) (xy 87.459273 -111.340676)
			(xy 87.449406 -111.336836) (xy 87.409237 -111.322707) (xy 87.331557 -111.287812) (xy 87.257568 -111.245652)
			(xy 87.187947 -111.196615) (xy 87.123331 -111.141148) (xy 87.064311 -111.07976) (xy 87.011428 -111.013013)
			(xy 86.965167 -110.941517) (xy 86.925949 -110.865928) (xy 86.894135 -110.786936) (xy 86.870016 -110.705266)
			(xy 86.853812 -110.621664) (xy 86.845672 -110.536897) (xy 86.84514 -110.494318) (xy 86.845606 -110.453059)
			(xy 86.853247 -110.370897) (xy 86.868464 -110.289795) (xy 86.891126 -110.21045) (xy 86.921039 -110.133546)
			(xy 86.957946 -110.059742) (xy 87.001529 -109.989673) (xy 87.051414 -109.923942) (xy 87.107172 -109.863114)
			(xy 87.168324 -109.80771) (xy 87.234343 -109.758208) (xy 87.304664 -109.715033) (xy 87.378681 -109.678556)
			(xy 87.455758 -109.64909) (xy 87.49538 -109.637576) (xy 87.53221 -109.593888) (xy 87.540084 -109.523784)
			(xy 87.549189 -109.446216) (xy 87.569891 -109.291393) (xy 87.581486 -109.214158) (xy 87.607648 -109.053122)
			(xy 87.630302 -108.924668) (xy 87.682483 -108.669069) (xy 87.74247 -108.415189) (xy 87.810207 -108.163267)
			(xy 87.88563 -107.913537) (xy 87.926672 -107.789726) (xy 87.964065 -107.67963) (xy 88.044091 -107.461288)
			(xy 88.130051 -107.245214) (xy 88.221881 -107.031569) (xy 88.270334 -106.925872) (xy 88.274188 -106.916457)
			(xy 88.274876 -106.896143) (xy 88.267617 -106.877158) (xy 88.260936 -106.869484) (xy 88.232229 -106.838517)
			(xy 88.18016 -106.772033) (xy 88.134627 -106.700913) (xy 88.096041 -106.625797) (xy 88.064749 -106.547361)
			(xy 88.041033 -106.466313) (xy 88.025105 -106.383381) (xy 88.017111 -106.299314) (xy 88.016588 -106.25709)
			(xy 88.017063 -106.215988) (xy 88.024649 -106.134134) (xy 88.039755 -106.053329) (xy 88.062252 -105.974263)
			(xy 88.091948 -105.89761) (xy 88.12859 -105.824024) (xy 88.171866 -105.754132) (xy 88.221405 -105.688532)
			(xy 88.276786 -105.627782) (xy 88.337536 -105.572401) (xy 88.403137 -105.522862) (xy 88.473029 -105.479587)
			(xy 88.546615 -105.442945) (xy 88.623269 -105.41325) (xy 88.702335 -105.390753) (xy 88.78314 -105.375648)
			(xy 88.864994 -105.368063) (xy 88.906096 -105.367582) (xy 88.945644 -105.368024) (xy 89.024428 -105.375065)
			(xy 89.102276 -105.389064) (xy 89.140538 -105.399078) (xy 89.150464 -105.401342) (xy 89.170632 -105.398692)
			(xy 89.188181 -105.388406) (xy 89.19464 -105.380536) (xy 89.258187 -105.296581) (xy 89.388884 -105.131461)
			(xy 89.456006 -105.050336) (xy 89.521792 -104.972104) (xy 89.528904 -104.963976) (xy 89.534746 -104.957118)
			(xy 89.536524 -104.955086) (xy 89.536778 -104.954832) (xy 89.628933 -104.84827) (xy 89.819346 -104.640582)
			(xy 89.917524 -104.539542) (xy 89.995751 -104.460251) (xy 90.155792 -104.305292) (xy 90.237564 -104.229662)
			(xy 90.339389 -104.136831) (xy 90.548213 -103.957012) (xy 90.762744 -103.784041) (xy 90.982757 -103.6181)
			(xy 91.095068 -103.538274) (xy 91.116658 -103.496872) (xy 91.115134 -103.484934) (xy 91.103743 -103.434069)
			(xy 91.091517 -103.330551) (xy 91.09075 -103.278432) (xy 91.091223 -103.237328) (xy 91.098805 -103.15547)
			(xy 91.113908 -103.074661) (xy 91.136402 -102.99559) (xy 91.166097 -102.918932) (xy 91.202737 -102.845341)
			(xy 91.246011 -102.775444) (xy 91.29555 -102.709838) (xy 91.350931 -102.649083) (xy 91.411681 -102.593698)
			(xy 91.477283 -102.544153) (xy 91.547176 -102.500873) (xy 91.620764 -102.464226) (xy 91.69742 -102.434526)
			(xy 91.776489 -102.412025) (xy 91.857297 -102.396916) (xy 91.939154 -102.389327) (xy 91.980258 -102.388924)
			(xy 92.024167 -102.389457) (xy 92.111557 -102.398114) (xy 92.19767 -102.415338) (xy 92.281667 -102.440962)
			(xy 92.36273 -102.474737) (xy 92.440072 -102.516333) (xy 92.51294 -102.565346) (xy 92.580625 -102.621299)
			(xy 92.611956 -102.652068) (xy 92.619388 -102.65896) (xy 92.638078 -102.666758) (xy 92.658329 -102.666756)
			(xy 92.667836 -102.663244) (xy 92.812362 -102.603046) (xy 92.81287 -102.603046) (xy 92.81541 -102.601776)
			(xy 92.815918 -102.601776) (xy 92.978224 -102.538022) (xy 93.112336 -102.488492) (xy 93.23578 -102.445058)
			(xy 93.239336 -102.443788) (xy 93.250004 -102.440232) (xy 93.252036 -102.43947) (xy 93.316572 -102.417607)
			(xy 93.446246 -102.375694) (xy 93.51137 -102.35565) (xy 93.566864 -102.338793) (xy 93.678247 -102.306406)
			(xy 93.734128 -102.29088) (xy 93.851535 -102.258927) (xy 94.087874 -102.200919) (xy 94.325774 -102.149685)
			(xy 94.445328 -102.12705) (xy 94.571788 -102.104076) (xy 94.825831 -102.064825) (xy 94.953328 -102.048564)
			(xy 95.10148 -102.030862) (xy 95.398729 -102.004567) (xy 95.547688 -101.995986) (xy 95.557881 -101.995026)
			(xy 95.576306 -101.986138) (xy 95.589806 -101.970769) (xy 95.593408 -101.961188) (xy 95.60723 -101.920536)
			(xy 95.641637 -101.84186) (xy 95.683468 -101.766868) (xy 95.732333 -101.696257) (xy 95.787777 -101.630686)
			(xy 95.849283 -101.570765) (xy 95.91628 -101.517051) (xy 95.988142 -101.470046) (xy 96.0642 -101.430187)
			(xy 96.143747 -101.397845) (xy 96.22604 -101.373322) (xy 96.310315 -101.356846) (xy 96.395785 -101.348571)
			(xy 96.43872 -101.348032) (xy 96.481198 -101.348532) (xy 96.565766 -101.356641) (xy 96.649177 -101.372774)
			(xy 96.73067 -101.396784) (xy 96.809503 -101.428452) (xy 96.884959 -101.46749) (xy 96.95635 -101.513543)
			(xy 97.023026 -101.566191) (xy 97.084381 -101.624955) (xy 97.139855 -101.689299) (xy 97.188944 -101.758637)
			(xy 97.2312 -101.83234) (xy 97.266238 -101.909734) (xy 97.280476 -101.949758) (xy 97.28581 -101.965252)
			(xy 97.311972 -101.984048) (xy 100.645468 -101.984048) (xy 100.67163 -101.965252) (xy 100.676964 -101.949758)
			(xy 100.691175 -101.90972) (xy 100.726201 -101.832311) (xy 100.768448 -101.758595) (xy 100.817531 -101.689242)
			(xy 100.873003 -101.624885) (xy 100.934358 -101.56611) (xy 101.001038 -101.513453) (xy 101.072434 -101.467393)
			(xy 101.147897 -101.428351) (xy 101.226739 -101.396681) (xy 101.308241 -101.372673) (xy 101.39166 -101.356545)
			(xy 101.476238 -101.348444) (xy 101.561202 -101.348444) (xy 101.64578 -101.356545) (xy 101.729199 -101.372673)
			(xy 101.810701 -101.396681) (xy 101.889543 -101.428351) (xy 101.965006 -101.467393) (xy 102.036402 -101.513453)
			(xy 102.103082 -101.56611) (xy 102.164437 -101.624885) (xy 102.219909 -101.689242) (xy 102.268992 -101.758595)
			(xy 102.311239 -101.832311) (xy 102.346265 -101.90972) (xy 102.360476 -101.949758) (xy 102.36581 -101.965252)
			(xy 102.391972 -101.984048) (xy 105.725468 -101.984048) (xy 105.75163 -101.965252) (xy 105.756964 -101.949758)
			(xy 105.771175 -101.90972) (xy 105.806201 -101.832311) (xy 105.848448 -101.758595) (xy 105.897531 -101.689242)
			(xy 105.953003 -101.624885) (xy 106.014358 -101.56611) (xy 106.081038 -101.513453) (xy 106.152434 -101.467393)
			(xy 106.227897 -101.428351) (xy 106.306739 -101.396681) (xy 106.388241 -101.372673) (xy 106.47166 -101.356545)
			(xy 106.556238 -101.348444) (xy 106.641202 -101.348444) (xy 106.72578 -101.356545) (xy 106.809199 -101.372673)
			(xy 106.890701 -101.396681) (xy 106.969543 -101.428351) (xy 107.045006 -101.467393) (xy 107.116402 -101.513453)
			(xy 107.183082 -101.56611) (xy 107.244437 -101.624885) (xy 107.299909 -101.689242) (xy 107.348992 -101.758595)
			(xy 107.391239 -101.832311) (xy 107.426265 -101.90972) (xy 107.440476 -101.949758) (xy 107.44581 -101.965252)
			(xy 107.471972 -101.984048) (xy 110.805468 -101.984048) (xy 110.83163 -101.965252) (xy 110.836964 -101.949758)
			(xy 110.851175 -101.90972) (xy 110.886201 -101.832311) (xy 110.928448 -101.758595) (xy 110.977531 -101.689242)
			(xy 111.033003 -101.624885) (xy 111.094358 -101.56611) (xy 111.161038 -101.513453) (xy 111.232434 -101.467393)
			(xy 111.307897 -101.428351) (xy 111.386739 -101.396681) (xy 111.468241 -101.372673) (xy 111.55166 -101.356545)
			(xy 111.636238 -101.348444) (xy 111.721202 -101.348444) (xy 111.80578 -101.356545) (xy 111.889199 -101.372673)
			(xy 111.970701 -101.396681) (xy 112.049543 -101.428351) (xy 112.125006 -101.467393) (xy 112.196402 -101.513453)
			(xy 112.263082 -101.56611) (xy 112.324437 -101.624885) (xy 112.379909 -101.689242) (xy 112.428992 -101.758595)
			(xy 112.471239 -101.832311) (xy 112.506265 -101.90972) (xy 112.520476 -101.949758) (xy 112.52581 -101.965252)
			(xy 112.551972 -101.984048) (xy 114.146584 -101.984048) (xy 114.156597 -101.983563) (xy 114.175103 -101.975908)
			(xy 114.189272 -101.961757) (xy 114.196951 -101.943261) (xy 114.197384 -101.933248) (xy 114.197384 -83.630262)
			(xy 114.196954 -83.620195) (xy 114.189228 -83.601602) (xy 114.182398 -83.594194) (xy 110.809278 -80.221074)
			(xy 110.78612 -80.197195) (xy 110.745609 -80.144433) (xy 110.712334 -80.086832) (xy 110.686866 -80.02538)
			(xy 110.66964 -79.961129) (xy 110.660952 -79.895178) (xy 110.660434 -79.861918) (xy 110.660434 -75.179174)
			(xy 110.660957 -75.145914) (xy 110.669646 -75.079965) (xy 110.686873 -75.015714) (xy 110.712341 -74.954264)
			(xy 110.745616 -74.896665) (xy 110.786127 -74.843904) (xy 110.809278 -74.820018) (xy 111.337852 -74.291444)
			(xy 111.361732 -74.268288) (xy 111.414496 -74.227783) (xy 111.472097 -74.194514) (xy 111.533549 -74.16905)
			(xy 111.5978 -74.151829) (xy 111.663749 -74.143144) (xy 111.697008 -74.1426) (xy 117.991636 -74.1426)
			(xy 118.001703 -74.14217) (xy 118.020298 -74.134447) (xy 118.027704 -74.127614) (xy 118.691914 -73.463404)
			(xy 118.69877 -73.45601) (xy 118.70652 -73.437411) (xy 118.7069 -73.427336) (xy 118.7069 -69.667882)
			(xy 118.706473 -69.657813) (xy 118.698754 -69.639214) (xy 118.691914 -69.631814) (xy 117.771672 -68.711572)
			(xy 117.764275 -68.704722) (xy 117.745677 -68.696987) (xy 117.735604 -68.696586) (xy 112.208818 -68.696586)
			(xy 112.175558 -68.696066) (xy 112.109606 -68.68738) (xy 112.045354 -68.670156) (xy 111.983902 -68.644688)
			(xy 111.926302 -68.611413) (xy 111.873542 -68.5709) (xy 111.849662 -68.547742) (xy 111.049816 -67.747896)
			(xy 111.026655 -67.724018) (xy 110.986139 -67.671258) (xy 110.952859 -67.613658) (xy 110.927387 -67.552206)
			(xy 110.910157 -67.487953) (xy 110.901465 -67.422001) (xy 110.900972 -67.38874) (xy 110.900972 -64.34963)
			(xy 110.901491 -64.316369) (xy 110.910175 -64.250416) (xy 110.927397 -64.186163) (xy 110.952862 -64.124708)
			(xy 110.986135 -64.067105) (xy 111.026645 -64.014341) (xy 111.049816 -63.990474) (xy 111.689642 -63.350648)
			(xy 111.713522 -63.327492) (xy 111.766285 -63.286985) (xy 111.823886 -63.253714) (xy 111.885338 -63.228249)
			(xy 111.949589 -63.211027) (xy 112.015538 -63.202341) (xy 112.048798 -63.201804) (xy 117.80012 -63.201804)
			(xy 117.810189 -63.201377) (xy 117.828788 -63.193658) (xy 117.836188 -63.186818) (xy 118.596156 -62.42685)
			(xy 118.602999 -62.419451) (xy 118.610722 -62.400852) (xy 118.611142 -62.390782) (xy 118.611142 -58.342784)
			(xy 118.610714 -58.332716) (xy 118.602989 -58.314122) (xy 118.596156 -58.306716) (xy 117.964204 -57.674764)
			(xy 117.956809 -57.66791) (xy 117.93821 -57.660164) (xy 117.928136 -57.659778) (xy 111.985044 -57.659778)
			(xy 111.951782 -57.65926) (xy 111.885828 -57.650579) (xy 111.821572 -57.63336) (xy 111.760115 -57.607897)
			(xy 111.702509 -57.574628) (xy 111.64974 -57.534121) (xy 111.625888 -57.510934) (xy 111.05007 -56.935116)
			(xy 111.026915 -56.911236) (xy 110.986411 -56.858472) (xy 110.953143 -56.800871) (xy 110.927683 -56.739419)
			(xy 110.910464 -56.675168) (xy 110.901783 -56.609219) (xy 110.901226 -56.57596) (xy 110.901226 -55.736744)
			(xy 110.901647 -55.706997) (xy 110.908592 -55.647911) (xy 110.922391 -55.590041) (xy 110.942856 -55.534178)
			(xy 110.969706 -55.481089) (xy 110.985808 -55.456074) (xy 110.992158 -55.446676) (xy 110.99546 -55.424324)
			(xy 110.969044 -55.338218) (xy 110.965153 -55.327549) (xy 110.949851 -55.310808) (xy 110.93958 -55.30596)
			(xy 110.899273 -55.288833) (xy 110.821924 -55.24775) (xy 110.748984 -55.199267) (xy 110.68116 -55.143854)
			(xy 110.619107 -55.082046) (xy 110.563426 -55.014441) (xy 110.514656 -54.941693) (xy 110.473268 -54.864506)
			(xy 110.439662 -54.783627) (xy 110.414165 -54.699838) (xy 110.397021 -54.613949) (xy 110.388398 -54.526791)
			(xy 110.387892 -54.483) (xy 110.388396 -54.440652) (xy 110.396447 -54.356338) (xy 110.412476 -54.273172)
			(xy 110.436337 -54.191905) (xy 110.467816 -54.113275) (xy 110.506627 -54.037994) (xy 110.552417 -53.966742)
			(xy 110.604773 -53.900166) (xy 110.663221 -53.838868) (xy 110.727231 -53.783403) (xy 110.796223 -53.734274)
			(xy 110.869573 -53.691925) (xy 110.946616 -53.656741) (xy 111.026655 -53.629039) (xy 111.108964 -53.609071)
			(xy 111.192799 -53.597018) (xy 111.2774 -53.592988) (xy 111.362001 -53.597018) (xy 111.445836 -53.609071)
			(xy 111.528145 -53.629039) (xy 111.608184 -53.656741) (xy 111.685227 -53.691925) (xy 111.758577 -53.734274)
			(xy 111.827569 -53.783403) (xy 111.891579 -53.838868) (xy 111.950027 -53.900166) (xy 112.002383 -53.966742)
			(xy 112.048173 -54.037994) (xy 112.086984 -54.113275) (xy 112.118463 -54.191905) (xy 112.142324 -54.273172)
			(xy 112.158353 -54.356338) (xy 112.166404 -54.440652) (xy 112.166908 -54.483) (xy 112.166908 -54.489604)
			(xy 112.167328 -54.499624) (xy 112.174999 -54.518138) (xy 112.189172 -54.532308) (xy 112.207688 -54.539974)
			(xy 112.217708 -54.540404) (xy 122.2756 -54.540404) (xy 122.285608 -54.539916) (xy 122.3041 -54.532256)
			(xy 122.318254 -54.518104) (xy 122.325915 -54.499612) (xy 122.3264 -54.489604) (xy 122.3264 -46.4058)
			(xy 122.325912 -46.395792) (xy 122.318252 -46.377301) (xy 122.304099 -46.363148) (xy 122.285608 -46.355488)
			(xy 122.2756 -46.355) (xy 112.028478 -46.355) (xy 111.995219 -46.354477) (xy 111.92927 -46.345787)
			(xy 111.865021 -46.32856) (xy 111.803571 -46.303089) (xy 111.745975 -46.269811) (xy 111.693217 -46.229297)
			(xy 111.669322 -46.206156) (xy 111.133128 -45.669962) (xy 111.109968 -45.646084) (xy 111.069455 -45.593323)
			(xy 111.036178 -45.535723) (xy 111.010709 -45.47427) (xy 110.993483 -45.410018) (xy 110.984795 -45.344067)
			(xy 110.984284 -45.310806) (xy 110.984284 -44.15917) (xy 110.984574 -44.136243) (xy 110.988774 -44.09058)
			(xy 110.992666 -44.067984) (xy 110.993894 -44.059209) (xy 110.990967 -44.041749) (xy 110.982257 -44.026336)
			(xy 110.968811 -44.01482) (xy 110.960662 -44.011342) (xy 110.922243 -43.996191) (xy 110.84813 -43.95974)
			(xy 110.777713 -43.916577) (xy 110.7116 -43.867076) (xy 110.650357 -43.811661) (xy 110.594514 -43.750809)
			(xy 110.544549 -43.685044) (xy 110.500894 -43.614932) (xy 110.463924 -43.541077) (xy 110.433956 -43.464113)
			(xy 110.41125 -43.384704) (xy 110.396 -43.303532) (xy 110.388337 -43.221296) (xy 110.387892 -43.18)
			(xy 110.388367 -43.138898) (xy 110.395952 -43.057043) (xy 110.411057 -42.976238) (xy 110.433553 -42.897171)
			(xy 110.463249 -42.820517) (xy 110.499891 -42.74693) (xy 110.543166 -42.677038) (xy 110.592706 -42.611437)
			(xy 110.648087 -42.550687) (xy 110.708837 -42.495306) (xy 110.774438 -42.445766) (xy 110.84433 -42.402491)
			(xy 110.917917 -42.365849) (xy 110.994571 -42.336153) (xy 111.073638 -42.313657) (xy 111.154443 -42.298552)
			(xy 111.236298 -42.290967) (xy 111.2774 -42.290492) (xy 111.318708 -42.290961) (xy 111.40097 -42.298621)
			(xy 111.482166 -42.313873) (xy 111.561599 -42.336587) (xy 111.638585 -42.366568) (xy 111.712459 -42.403556)
			(xy 111.782586 -42.447234) (xy 111.848362 -42.497225) (xy 111.90922 -42.553099) (xy 111.964636 -42.614374)
			(xy 112.014132 -42.680523) (xy 112.057283 -42.750975) (xy 112.093717 -42.825125) (xy 112.123119 -42.902332)
			(xy 112.13465 -42.942002) (xy 112.13465 -42.942256) (xy 112.138129 -42.952724) (xy 112.1524 -42.969512)
			(xy 112.172401 -42.978756) (xy 112.183418 -42.97934) (xy 117.914928 -42.97934) (xy 117.924995 -42.97891)
			(xy 117.943586 -42.971182) (xy 117.950996 -42.964354) (xy 118.999 -41.91635) (xy 119.005839 -41.908949)
			(xy 119.013555 -41.890351) (xy 119.013986 -41.880282) (xy 119.013986 -36.200842) (xy 119.013552 -36.190777)
			(xy 119.005821 -36.172189) (xy 118.999 -36.164774) (xy 118.622826 -35.7886) (xy 118.615423 -35.781765)
			(xy 118.596825 -35.774058) (xy 118.586758 -35.773614) (xy 112.131856 -35.773614) (xy 112.098597 -35.77309)
			(xy 112.032649 -35.764398) (xy 111.968402 -35.747168) (xy 111.906954 -35.721696) (xy 111.849359 -35.688418)
			(xy 111.796603 -35.647903) (xy 111.7727 -35.62477) (xy 111.101124 -34.953194) (xy 111.077963 -34.929316)
			(xy 111.037446 -34.876556) (xy 111.004167 -34.818956) (xy 110.978694 -34.757504) (xy 110.961464 -34.693252)
			(xy 110.952772 -34.627299) (xy 110.95228 -34.594038) (xy 110.95228 -30.659324) (xy 110.9528 -30.626063)
			(xy 110.961484 -30.560111) (xy 110.978707 -30.495858) (xy 111.004173 -30.434404) (xy 111.037446 -30.376802)
			(xy 111.077957 -30.324039) (xy 111.101124 -30.300168) (xy 111.773208 -29.628084) (xy 111.797087 -29.604925)
			(xy 111.849848 -29.564411) (xy 111.907448 -29.531134) (xy 111.9689 -29.505664) (xy 112.033152 -29.488435)
			(xy 112.099103 -29.479745) (xy 112.132364 -29.47924) (xy 118.683278 -29.47924) (xy 118.693341 -29.478801)
			(xy 118.711919 -29.47106) (xy 118.719346 -29.464254) (xy 118.871492 -29.312108) (xy 118.878341 -29.30471)
			(xy 118.886079 -29.286112) (xy 118.886478 -29.27604) (xy 118.886478 -24.812244) (xy 118.886044 -24.802179)
			(xy 118.878313 -24.783591) (xy 118.871492 -24.776176) (xy 118.59133 -24.496014) (xy 118.583928 -24.489177)
			(xy 118.56533 -24.481466) (xy 118.555262 -24.481028) (xy 112.036606 -24.481028) (xy 112.003346 -24.480507)
			(xy 111.937395 -24.471821) (xy 111.873143 -24.454597) (xy 111.81169 -24.429129) (xy 111.75409 -24.395855)
			(xy 111.701328 -24.355344) (xy 111.67745 -24.332184) (xy 111.165386 -23.82012) (xy 111.14223 -23.79624)
			(xy 111.101724 -23.743477) (xy 111.068455 -23.685876) (xy 111.042993 -23.624424) (xy 111.025774 -23.560173)
			(xy 111.017092 -23.494223) (xy 111.016542 -23.460964) (xy 111.016542 -19.302476) (xy 111.017065 -19.269216)
			(xy 111.025754 -19.203267) (xy 111.042981 -19.139016) (xy 111.068449 -19.077566) (xy 111.101724 -19.019967)
			(xy 111.142235 -18.967206) (xy 111.165386 -18.94332) (xy 111.741458 -18.367248) (xy 111.765338 -18.344092)
			(xy 111.818102 -18.303587) (xy 111.875703 -18.270318) (xy 111.937155 -18.244856) (xy 112.001406 -18.227635)
			(xy 112.067355 -18.218951) (xy 112.100614 -18.218404) (xy 122.2756 -18.218404) (xy 122.285608 -18.217916)
			(xy 122.3041 -18.210256) (xy 122.318254 -18.196104) (xy 122.325915 -18.177612) (xy 122.3264 -18.167604)
			(xy 122.3264 -9.304782) (xy 122.325909 -9.294777) (xy 122.318246 -9.276291) (xy 122.304094 -9.262144)
			(xy 122.285605 -9.254488) (xy 122.2756 -9.253982) (xy 98.521012 -9.253982) (xy 98.51094 -9.254402)
			(xy 98.492331 -9.262112) (xy 98.484944 -9.268968) (xy 95.805301 -11.948611) (xy 99.749606 -11.948611)
			(xy 99.749606 -11.863889) (xy 99.757659 -11.779552) (xy 99.773693 -11.696362) (xy 99.797561 -11.615072)
			(xy 99.829049 -11.53642) (xy 99.867871 -11.461117) (xy 99.913674 -11.389845) (xy 99.966045 -11.323249)
			(xy 100.02451 -11.261934) (xy 100.088538 -11.206453) (xy 100.15755 -11.15731) (xy 100.23092 -11.11495)
			(xy 100.307985 -11.079755) (xy 100.388047 -11.052046) (xy 100.47038 -11.032072) (xy 100.554239 -11.020015)
			(xy 100.638864 -11.015984) (xy 100.723489 -11.020015) (xy 100.807348 -11.032072) (xy 100.889681 -11.052046)
			(xy 100.969743 -11.079755) (xy 101.046808 -11.11495) (xy 101.120178 -11.15731) (xy 101.18919 -11.206453)
			(xy 101.253218 -11.261934) (xy 101.311683 -11.323249) (xy 101.364054 -11.389845) (xy 101.409857 -11.461117)
			(xy 101.448679 -11.53642) (xy 101.480167 -11.615072) (xy 101.504035 -11.696362) (xy 101.520069 -11.779552)
			(xy 101.528122 -11.863889) (xy 101.528626 -11.90625) (xy 101.528122 -11.948611) (xy 101.520069 -12.032948)
			(xy 101.504035 -12.116138) (xy 101.480167 -12.197428) (xy 101.448679 -12.27608) (xy 101.409857 -12.351383)
			(xy 101.364054 -12.422655) (xy 101.311683 -12.489251) (xy 101.253218 -12.550566) (xy 101.18919 -12.606047)
			(xy 101.120178 -12.65519) (xy 101.046808 -12.69755) (xy 100.969743 -12.732745) (xy 100.889681 -12.760454)
			(xy 100.807348 -12.780428) (xy 100.723489 -12.792485) (xy 100.638864 -12.796517) (xy 100.554239 -12.792485)
			(xy 100.47038 -12.780428) (xy 100.388047 -12.760454) (xy 100.307985 -12.732745) (xy 100.23092 -12.69755)
			(xy 100.15755 -12.65519) (xy 100.088538 -12.606047) (xy 100.02451 -12.550566) (xy 99.966045 -12.489251)
			(xy 99.913674 -12.422655) (xy 99.867871 -12.351383) (xy 99.829049 -12.27608) (xy 99.797561 -12.197428)
			(xy 99.773693 -12.116138) (xy 99.757659 -12.032948) (xy 99.749606 -11.948611) (xy 95.805301 -11.948611)
			(xy 73.866756 -33.887156) (xy 73.842876 -33.910312) (xy 73.790112 -33.950818) (xy 73.732511 -33.984089)
			(xy 73.67106 -34.009553) (xy 73.606809 -34.026775) (xy 73.540859 -34.035461) (xy 73.5076 -34.036)
			(xy 35.127184 -34.036) (xy 35.117582 -34.036464) (xy 35.099752 -34.043614) (xy 35.085783 -34.056801)
			(xy 35.077618 -34.07419) (xy 35.076638 -34.083752) (xy 35.076638 -34.084006) (xy 35.073868 -34.12609)
			(xy 35.061364 -34.209502) (xy 35.041021 -34.291356) (xy 35.013021 -34.370917) (xy 34.977615 -34.447471)
			(xy 34.935123 -34.520329) (xy 34.885924 -34.588838) (xy 34.830461 -34.652382) (xy 34.769233 -34.71039)
			(xy 34.702788 -34.762343) (xy 34.631724 -34.807772) (xy 34.556679 -34.846271) (xy 34.478327 -34.877494)
			(xy 34.39737 -34.901159) (xy 34.314538 -34.917055) (xy 34.230572 -34.925039) (xy 34.1884 -34.925508)
			(xy 34.188146 -34.925508) (xy 34.144679 -34.924958) (xy 34.058164 -34.916436) (xy 34.015426 -34.90849)
			(xy 34.014918 -34.90849) (xy 34.002554 -34.906748) (xy 33.978722 -34.914092) (xy 33.969452 -34.92246)
			(xy 30.749551 -38.142361) (xy 33.299142 -38.142361) (xy 33.299142 -38.057639) (xy 33.307195 -37.973302)
			(xy 33.323229 -37.890112) (xy 33.347097 -37.808822) (xy 33.378585 -37.73017) (xy 33.417407 -37.654867)
			(xy 33.46321 -37.583595) (xy 33.515581 -37.516999) (xy 33.574046 -37.455684) (xy 33.638074 -37.400203)
			(xy 33.707086 -37.35106) (xy 33.780456 -37.3087) (xy 33.857521 -37.273505) (xy 33.937583 -37.245796)
			(xy 34.019916 -37.225822) (xy 34.103775 -37.213765) (xy 34.1884 -37.209734) (xy 34.273025 -37.213765)
			(xy 34.356884 -37.225822) (xy 34.439217 -37.245796) (xy 34.519279 -37.273505) (xy 34.596344 -37.3087)
			(xy 34.669714 -37.35106) (xy 34.738726 -37.400203) (xy 34.802754 -37.455684) (xy 34.861219 -37.516999)
			(xy 34.91359 -37.583595) (xy 34.959393 -37.654867) (xy 34.998215 -37.73017) (xy 35.029703 -37.808822)
			(xy 35.053571 -37.890112) (xy 35.069605 -37.973302) (xy 35.077658 -38.057639) (xy 35.078162 -38.1)
			(xy 35.077658 -38.142361) (xy 35.069605 -38.226698) (xy 35.053571 -38.309888) (xy 35.029703 -38.391178)
			(xy 34.998215 -38.46983) (xy 34.959393 -38.545133) (xy 34.91359 -38.616405) (xy 34.861219 -38.683001)
			(xy 34.802754 -38.744316) (xy 34.738726 -38.799797) (xy 34.669714 -38.84894) (xy 34.596344 -38.8913)
			(xy 34.519279 -38.926495) (xy 34.439217 -38.954204) (xy 34.356884 -38.974178) (xy 34.273025 -38.986235)
			(xy 34.1884 -38.990267) (xy 34.103775 -38.986235) (xy 34.019916 -38.974178) (xy 33.937583 -38.954204)
			(xy 33.857521 -38.926495) (xy 33.780456 -38.8913) (xy 33.707086 -38.84894) (xy 33.638074 -38.799797)
			(xy 33.574046 -38.744316) (xy 33.515581 -38.683001) (xy 33.46321 -38.616405) (xy 33.417407 -38.545133)
			(xy 33.378585 -38.46983) (xy 33.347097 -38.391178) (xy 33.323229 -38.309888) (xy 33.307195 -38.226698)
			(xy 33.299142 -38.142361) (xy 30.749551 -38.142361) (xy 26.417327 -42.474585) (xy 107.8931 -42.474585)
			(xy 107.8931 -42.389863) (xy 107.901153 -42.305526) (xy 107.917187 -42.222336) (xy 107.941055 -42.141046)
			(xy 107.972543 -42.062394) (xy 108.011365 -41.987091) (xy 108.057168 -41.915819) (xy 108.109539 -41.849223)
			(xy 108.168004 -41.787908) (xy 108.232032 -41.732427) (xy 108.301044 -41.683284) (xy 108.374414 -41.640924)
			(xy 108.451479 -41.605729) (xy 108.531541 -41.57802) (xy 108.613874 -41.558046) (xy 108.697733 -41.545989)
			(xy 108.782358 -41.541958) (xy 108.866983 -41.545989) (xy 108.950842 -41.558046) (xy 109.033175 -41.57802)
			(xy 109.113237 -41.605729) (xy 109.190302 -41.640924) (xy 109.263672 -41.683284) (xy 109.332684 -41.732427)
			(xy 109.396712 -41.787908) (xy 109.455177 -41.849223) (xy 109.507548 -41.915819) (xy 109.553351 -41.987091)
			(xy 109.592173 -42.062394) (xy 109.623661 -42.141046) (xy 109.647529 -42.222336) (xy 109.663563 -42.305526)
			(xy 109.671616 -42.389863) (xy 109.67212 -42.432224) (xy 109.671616 -42.474585) (xy 109.663563 -42.558922)
			(xy 109.647529 -42.642112) (xy 109.623661 -42.723402) (xy 109.592173 -42.802054) (xy 109.553351 -42.877357)
			(xy 109.507548 -42.948629) (xy 109.455177 -43.015225) (xy 109.396712 -43.07654) (xy 109.332684 -43.132021)
			(xy 109.263672 -43.181164) (xy 109.190302 -43.223524) (xy 109.113237 -43.258719) (xy 109.033175 -43.286428)
			(xy 108.950842 -43.306402) (xy 108.866983 -43.318459) (xy 108.782358 -43.322491) (xy 108.697733 -43.318459)
			(xy 108.613874 -43.306402) (xy 108.531541 -43.286428) (xy 108.451479 -43.258719) (xy 108.374414 -43.223524)
			(xy 108.301044 -43.181164) (xy 108.232032 -43.132021) (xy 108.168004 -43.07654) (xy 108.109539 -43.015225)
			(xy 108.057168 -42.948629) (xy 108.011365 -42.877357) (xy 107.972543 -42.802054) (xy 107.941055 -42.723402)
			(xy 107.917187 -42.642112) (xy 107.901153 -42.558922) (xy 107.8931 -42.474585) (xy 26.417327 -42.474585)
			(xy 23.735538 -45.156374) (xy 23.728699 -45.163775) (xy 23.720986 -45.182373) (xy 23.720552 -45.192442)
			(xy 23.720552 -45.787761) (xy 102.768142 -45.787761) (xy 102.768142 -45.703039) (xy 102.776195 -45.618702)
			(xy 102.792229 -45.535512) (xy 102.816097 -45.454222) (xy 102.847585 -45.37557) (xy 102.886407 -45.300267)
			(xy 102.93221 -45.228995) (xy 102.984581 -45.162399) (xy 103.043046 -45.101084) (xy 103.107074 -45.045603)
			(xy 103.176086 -44.99646) (xy 103.249456 -44.9541) (xy 103.326521 -44.918905) (xy 103.406583 -44.891196)
			(xy 103.488916 -44.871222) (xy 103.572775 -44.859165) (xy 103.6574 -44.855134) (xy 103.742025 -44.859165)
			(xy 103.825884 -44.871222) (xy 103.908217 -44.891196) (xy 103.988279 -44.918905) (xy 104.065344 -44.9541)
			(xy 104.138714 -44.99646) (xy 104.207726 -45.045603) (xy 104.271754 -45.101084) (xy 104.330219 -45.162399)
			(xy 104.38259 -45.228995) (xy 104.428393 -45.300267) (xy 104.467215 -45.37557) (xy 104.498703 -45.454222)
			(xy 104.522571 -45.535512) (xy 104.538605 -45.618702) (xy 104.546658 -45.703039) (xy 104.547162 -45.7454)
			(xy 104.546658 -45.787761) (xy 104.538605 -45.872098) (xy 104.522571 -45.955288) (xy 104.498703 -46.036578)
			(xy 104.467215 -46.11523) (xy 104.428393 -46.190533) (xy 104.38259 -46.261805) (xy 104.330219 -46.328401)
			(xy 104.271754 -46.389716) (xy 104.207726 -46.445197) (xy 104.138714 -46.49434) (xy 104.065344 -46.5367)
			(xy 103.988279 -46.571895) (xy 103.908217 -46.599604) (xy 103.825884 -46.619578) (xy 103.742025 -46.631635)
			(xy 103.6574 -46.635667) (xy 103.572775 -46.631635) (xy 103.488916 -46.619578) (xy 103.406583 -46.599604)
			(xy 103.326521 -46.571895) (xy 103.249456 -46.5367) (xy 103.176086 -46.49434) (xy 103.107074 -46.445197)
			(xy 103.043046 -46.389716) (xy 102.984581 -46.328401) (xy 102.93221 -46.261805) (xy 102.886407 -46.190533)
			(xy 102.847585 -46.11523) (xy 102.816097 -46.036578) (xy 102.792229 -45.955288) (xy 102.776195 -45.872098)
			(xy 102.768142 -45.787761) (xy 23.720552 -45.787761) (xy 23.720552 -50.919888) (xy 40.838131 -50.919888)
			(xy 40.842106 -50.809829) (xy 40.854014 -50.700343) (xy 40.87379 -50.592002) (xy 40.901333 -50.485371)
			(xy 40.936498 -50.381005) (xy 40.979102 -50.279448) (xy 41.028923 -50.181231) (xy 41.085702 -50.086864)
			(xy 41.149141 -49.99684) (xy 41.218912 -49.911629) (xy 41.294649 -49.831674) (xy 41.375958 -49.757393)
			(xy 41.462415 -49.689173) (xy 41.553569 -49.627368) (xy 41.648946 -49.572303) (xy 41.748047 -49.524263)
			(xy 41.850356 -49.483499) (xy 41.95534 -49.450224) (xy 42.062451 -49.424611) (xy 42.171131 -49.406794)
			(xy 42.280814 -49.396865) (xy 42.390927 -49.394877) (xy 42.500897 -49.400839) (xy 42.61015 -49.414721)
			(xy 42.718116 -49.436451) (xy 42.824233 -49.465914) (xy 42.927947 -49.502957) (xy 43.028718 -49.547388)
			(xy 43.12602 -49.598975) (xy 43.219346 -49.657447) (xy 43.308209 -49.722502) (xy 43.392147 -49.7938)
			(xy 43.470722 -49.870968) (xy 43.543523 -49.953605) (xy 43.610171 -50.041279) (xy 43.67032 -50.133535)
			(xy 43.723654 -50.22989) (xy 43.769897 -50.329842) (xy 43.808807 -50.43287) (xy 43.840181 -50.538438)
			(xy 43.863856 -50.645994) (xy 43.879708 -50.754978) (xy 43.887655 -50.864822) (xy 43.888152 -50.919888)
			(xy 60.396131 -50.919888) (xy 60.400106 -50.809829) (xy 60.412014 -50.700343) (xy 60.43179 -50.592002)
			(xy 60.459333 -50.485371) (xy 60.494498 -50.381005) (xy 60.537102 -50.279448) (xy 60.586923 -50.181231)
			(xy 60.643702 -50.086864) (xy 60.707141 -49.99684) (xy 60.776912 -49.911629) (xy 60.852649 -49.831674)
			(xy 60.933958 -49.757393) (xy 61.020415 -49.689173) (xy 61.111569 -49.627368) (xy 61.206946 -49.572303)
			(xy 61.306047 -49.524263) (xy 61.408356 -49.483499) (xy 61.51334 -49.450224) (xy 61.620451 -49.424611)
			(xy 61.729131 -49.406794) (xy 61.838814 -49.396865) (xy 61.948927 -49.394877) (xy 62.058897 -49.400839)
			(xy 62.16815 -49.414721) (xy 62.276116 -49.436451) (xy 62.382233 -49.465914) (xy 62.485947 -49.502957)
			(xy 62.586718 -49.547388) (xy 62.68402 -49.598975) (xy 62.777346 -49.657447) (xy 62.866209 -49.722502)
			(xy 62.950147 -49.7938) (xy 63.028722 -49.870968) (xy 63.101523 -49.953605) (xy 63.168171 -50.041279)
			(xy 63.22832 -50.133535) (xy 63.281654 -50.22989) (xy 63.327897 -50.329842) (xy 63.366807 -50.43287)
			(xy 63.398181 -50.538438) (xy 63.421856 -50.645994) (xy 63.437708 -50.754978) (xy 63.445655 -50.864822)
			(xy 63.446152 -50.919888) (xy 63.445655 -50.974954) (xy 63.437708 -51.084798) (xy 63.421856 -51.193782)
			(xy 63.398181 -51.301338) (xy 63.366807 -51.406906) (xy 63.327897 -51.509934) (xy 63.281654 -51.609886)
			(xy 63.22832 -51.706241) (xy 63.168171 -51.798497) (xy 63.101523 -51.886171) (xy 63.028722 -51.968808)
			(xy 62.950147 -52.045976) (xy 62.866209 -52.117274) (xy 62.777346 -52.182329) (xy 62.68402 -52.240801)
			(xy 62.586718 -52.292388) (xy 62.485947 -52.336819) (xy 62.382233 -52.373862) (xy 62.276116 -52.403325)
			(xy 62.16815 -52.425055) (xy 62.058897 -52.438937) (xy 61.948927 -52.444899) (xy 61.838814 -52.442911)
			(xy 61.729131 -52.432982) (xy 61.620451 -52.415165) (xy 61.51334 -52.389552) (xy 61.408356 -52.356277)
			(xy 61.306047 -52.315513) (xy 61.206946 -52.267473) (xy 61.111569 -52.212408) (xy 61.020415 -52.150603)
			(xy 60.933958 -52.082383) (xy 60.852649 -52.008102) (xy 60.776912 -51.928147) (xy 60.707141 -51.842936)
			(xy 60.643702 -51.752912) (xy 60.586923 -51.658545) (xy 60.537102 -51.560328) (xy 60.494498 -51.458771)
			(xy 60.459333 -51.354405) (xy 60.43179 -51.247774) (xy 60.412014 -51.139433) (xy 60.400106 -51.029947)
			(xy 60.396131 -50.919888) (xy 43.888152 -50.919888) (xy 43.887655 -50.974954) (xy 43.879708 -51.084798)
			(xy 43.863856 -51.193782) (xy 43.840181 -51.301338) (xy 43.808807 -51.406906) (xy 43.769897 -51.509934)
			(xy 43.723654 -51.609886) (xy 43.67032 -51.706241) (xy 43.610171 -51.798497) (xy 43.543523 -51.886171)
			(xy 43.470722 -51.968808) (xy 43.392147 -52.045976) (xy 43.308209 -52.117274) (xy 43.219346 -52.182329)
			(xy 43.12602 -52.240801) (xy 43.028718 -52.292388) (xy 42.927947 -52.336819) (xy 42.824233 -52.373862)
			(xy 42.718116 -52.403325) (xy 42.61015 -52.425055) (xy 42.500897 -52.438937) (xy 42.390927 -52.444899)
			(xy 42.280814 -52.442911) (xy 42.171131 -52.432982) (xy 42.062451 -52.415165) (xy 41.95534 -52.389552)
			(xy 41.850356 -52.356277) (xy 41.748047 -52.315513) (xy 41.648946 -52.267473) (xy 41.553569 -52.212408)
			(xy 41.462415 -52.150603) (xy 41.375958 -52.082383) (xy 41.294649 -52.008102) (xy 41.218912 -51.928147)
			(xy 41.149141 -51.842936) (xy 41.085702 -51.752912) (xy 41.028923 -51.658545) (xy 40.979102 -51.560328)
			(xy 40.936498 -51.458771) (xy 40.901333 -51.354405) (xy 40.87379 -51.247774) (xy 40.854014 -51.139433)
			(xy 40.842106 -51.029947) (xy 40.838131 -50.919888) (xy 23.720552 -50.919888) (xy 23.720552 -53.735167)
			(xy 108.485174 -53.735167) (xy 108.485174 -53.650445) (xy 108.493227 -53.566108) (xy 108.509261 -53.482918)
			(xy 108.533129 -53.401628) (xy 108.564617 -53.322976) (xy 108.603439 -53.247673) (xy 108.649242 -53.176401)
			(xy 108.701613 -53.109805) (xy 108.760078 -53.04849) (xy 108.824106 -52.993009) (xy 108.893118 -52.943866)
			(xy 108.966488 -52.901506) (xy 109.043553 -52.866311) (xy 109.123615 -52.838602) (xy 109.205948 -52.818628)
			(xy 109.289807 -52.806571) (xy 109.374432 -52.80254) (xy 109.459057 -52.806571) (xy 109.542916 -52.818628)
			(xy 109.625249 -52.838602) (xy 109.705311 -52.866311) (xy 109.782376 -52.901506) (xy 109.855746 -52.943866)
			(xy 109.924758 -52.993009) (xy 109.988786 -53.04849) (xy 110.047251 -53.109805) (xy 110.099622 -53.176401)
			(xy 110.145425 -53.247673) (xy 110.184247 -53.322976) (xy 110.215735 -53.401628) (xy 110.239603 -53.482918)
			(xy 110.255637 -53.566108) (xy 110.26369 -53.650445) (xy 110.264194 -53.692806) (xy 110.26369 -53.735167)
			(xy 110.255637 -53.819504) (xy 110.239603 -53.902694) (xy 110.215735 -53.983984) (xy 110.184247 -54.062636)
			(xy 110.145425 -54.137939) (xy 110.099622 -54.209211) (xy 110.047251 -54.275807) (xy 109.988786 -54.337122)
			(xy 109.924758 -54.392603) (xy 109.855746 -54.441746) (xy 109.782376 -54.484106) (xy 109.705311 -54.519301)
			(xy 109.625249 -54.54701) (xy 109.542916 -54.566984) (xy 109.459057 -54.579041) (xy 109.374432 -54.583073)
			(xy 109.289807 -54.579041) (xy 109.205948 -54.566984) (xy 109.123615 -54.54701) (xy 109.043553 -54.519301)
			(xy 108.966488 -54.484106) (xy 108.893118 -54.441746) (xy 108.824106 -54.392603) (xy 108.760078 -54.337122)
			(xy 108.701613 -54.275807) (xy 108.649242 -54.209211) (xy 108.603439 -54.137939) (xy 108.564617 -54.062636)
			(xy 108.533129 -53.983984) (xy 108.509261 -53.902694) (xy 108.493227 -53.819504) (xy 108.485174 -53.735167)
			(xy 23.720552 -53.735167) (xy 23.720552 -57.065361) (xy 102.768142 -57.065361) (xy 102.768142 -56.980639)
			(xy 102.776195 -56.896302) (xy 102.792229 -56.813112) (xy 102.816097 -56.731822) (xy 102.847585 -56.65317)
			(xy 102.886407 -56.577867) (xy 102.93221 -56.506595) (xy 102.984581 -56.439999) (xy 103.043046 -56.378684)
			(xy 103.107074 -56.323203) (xy 103.176086 -56.27406) (xy 103.249456 -56.2317) (xy 103.326521 -56.196505)
			(xy 103.406583 -56.168796) (xy 103.488916 -56.148822) (xy 103.572775 -56.136765) (xy 103.6574 -56.132734)
			(xy 103.742025 -56.136765) (xy 103.825884 -56.148822) (xy 103.908217 -56.168796) (xy 103.988279 -56.196505)
			(xy 104.065344 -56.2317) (xy 104.138714 -56.27406) (xy 104.207726 -56.323203) (xy 104.271754 -56.378684)
			(xy 104.330219 -56.439999) (xy 104.38259 -56.506595) (xy 104.428393 -56.577867) (xy 104.467215 -56.65317)
			(xy 104.498703 -56.731822) (xy 104.522571 -56.813112) (xy 104.538605 -56.896302) (xy 104.546658 -56.980639)
			(xy 104.547162 -57.023) (xy 104.546658 -57.065361) (xy 104.538605 -57.149698) (xy 104.522571 -57.232888)
			(xy 104.498703 -57.314178) (xy 104.467215 -57.39283) (xy 104.428393 -57.468133) (xy 104.38259 -57.539405)
			(xy 104.330219 -57.606001) (xy 104.271754 -57.667316) (xy 104.207726 -57.722797) (xy 104.138714 -57.77194)
			(xy 104.065344 -57.8143) (xy 103.988279 -57.849495) (xy 103.908217 -57.877204) (xy 103.825884 -57.897178)
			(xy 103.742025 -57.909235) (xy 103.6574 -57.913267) (xy 103.572775 -57.909235) (xy 103.488916 -57.897178)
			(xy 103.406583 -57.877204) (xy 103.326521 -57.849495) (xy 103.249456 -57.8143) (xy 103.176086 -57.77194)
			(xy 103.107074 -57.722797) (xy 103.043046 -57.667316) (xy 102.984581 -57.606001) (xy 102.93221 -57.539405)
			(xy 102.886407 -57.468133) (xy 102.847585 -57.39283) (xy 102.816097 -57.314178) (xy 102.792229 -57.232888)
			(xy 102.776195 -57.149698) (xy 102.768142 -57.065361) (xy 23.720552 -57.065361) (xy 23.720552 -58.42)
			(xy 41.345876 -58.42) (xy 41.349858 -58.330072) (xy 41.361772 -58.240848) (xy 41.381525 -58.153026)
			(xy 41.408962 -58.067293) (xy 41.443869 -57.984321) (xy 41.485973 -57.904758) (xy 41.534943 -57.829228)
			(xy 41.590398 -57.758322) (xy 41.651902 -57.692594) (xy 41.718974 -57.632559) (xy 41.79109 -57.578687)
			(xy 41.867685 -57.531399) (xy 41.948159 -57.491066) (xy 42.031883 -57.458003) (xy 42.118202 -57.432469)
			(xy 42.20644 -57.414664) (xy 42.295905 -57.404726) (xy 42.3859 -57.402735) (xy 42.475717 -57.408705)
			(xy 42.564656 -57.42259) (xy 42.65202 -57.444281) (xy 42.737125 -57.473608) (xy 42.819304 -57.510342)
			(xy 42.897916 -57.554196) (xy 42.972344 -57.604825) (xy 43.042006 -57.661835) (xy 43.106357 -57.724778)
			(xy 43.164894 -57.793162) (xy 43.217157 -57.866452) (xy 43.262739 -57.944074) (xy 43.301282 -58.025421)
			(xy 43.332485 -58.109856) (xy 43.356103 -58.196718) (xy 43.371952 -58.285328) (xy 43.379908 -58.374992)
			(xy 43.380406 -58.42) (xy 60.903876 -58.42) (xy 60.907858 -58.330072) (xy 60.919772 -58.240848) (xy 60.939525 -58.153026)
			(xy 60.966962 -58.067293) (xy 61.001869 -57.984321) (xy 61.043973 -57.904758) (xy 61.092943 -57.829228)
			(xy 61.148398 -57.758322) (xy 61.209902 -57.692594) (xy 61.276974 -57.632559) (xy 61.34909 -57.578687)
			(xy 61.425685 -57.531399) (xy 61.506159 -57.491066) (xy 61.589883 -57.458003) (xy 61.676202 -57.432469)
			(xy 61.76444 -57.414664) (xy 61.853905 -57.404726) (xy 61.9439 -57.402735) (xy 62.033717 -57.408705)
			(xy 62.122656 -57.42259) (xy 62.21002 -57.444281) (xy 62.295125 -57.473608) (xy 62.377304 -57.510342)
			(xy 62.455916 -57.554196) (xy 62.530344 -57.604825) (xy 62.600006 -57.661835) (xy 62.664357 -57.724778)
			(xy 62.722894 -57.793162) (xy 62.775157 -57.866452) (xy 62.820739 -57.944074) (xy 62.859282 -58.025421)
			(xy 62.890485 -58.109856) (xy 62.914103 -58.196718) (xy 62.929952 -58.285328) (xy 62.937908 -58.374992)
			(xy 62.938406 -58.42) (xy 62.937908 -58.465008) (xy 62.929952 -58.554672) (xy 62.914103 -58.643282)
			(xy 62.890485 -58.730144) (xy 62.859282 -58.814579) (xy 62.820739 -58.895926) (xy 62.775157 -58.973548)
			(xy 62.722894 -59.046838) (xy 62.664357 -59.115222) (xy 62.600006 -59.178165) (xy 62.530344 -59.235175)
			(xy 62.455916 -59.285804) (xy 62.377304 -59.329658) (xy 62.295125 -59.366392) (xy 62.21002 -59.395719)
			(xy 62.122656 -59.41741) (xy 62.033717 -59.431295) (xy 61.9439 -59.437265) (xy 61.853905 -59.435274)
			(xy 61.76444 -59.425336) (xy 61.676202 -59.407531) (xy 61.589883 -59.381997) (xy 61.506159 -59.348934)
			(xy 61.425685 -59.308601) (xy 61.34909 -59.261313) (xy 61.276974 -59.207441) (xy 61.209902 -59.147406)
			(xy 61.148398 -59.081678) (xy 61.092943 -59.010772) (xy 61.043973 -58.935242) (xy 61.001869 -58.855679)
			(xy 60.966962 -58.772707) (xy 60.939525 -58.686974) (xy 60.919772 -58.599152) (xy 60.907858 -58.509928)
			(xy 60.903876 -58.42) (xy 43.380406 -58.42) (xy 43.379908 -58.465008) (xy 43.371952 -58.554672) (xy 43.356103 -58.643282)
			(xy 43.332485 -58.730144) (xy 43.301282 -58.814579) (xy 43.262739 -58.895926) (xy 43.217157 -58.973548)
			(xy 43.164894 -59.046838) (xy 43.106357 -59.115222) (xy 43.042006 -59.178165) (xy 42.972344 -59.235175)
			(xy 42.897916 -59.285804) (xy 42.819304 -59.329658) (xy 42.737125 -59.366392) (xy 42.65202 -59.395719)
			(xy 42.564656 -59.41741) (xy 42.475717 -59.431295) (xy 42.3859 -59.437265) (xy 42.295905 -59.435274)
			(xy 42.20644 -59.425336) (xy 42.118202 -59.407531) (xy 42.031883 -59.381997) (xy 41.948159 -59.348934)
			(xy 41.867685 -59.308601) (xy 41.79109 -59.261313) (xy 41.718974 -59.207441) (xy 41.651902 -59.147406)
			(xy 41.590398 -59.081678) (xy 41.534943 -59.010772) (xy 41.485973 -58.935242) (xy 41.443869 -58.855679)
			(xy 41.408962 -58.772707) (xy 41.381525 -58.686974) (xy 41.361772 -58.599152) (xy 41.349858 -58.509928)
			(xy 41.345876 -58.42) (xy 23.720552 -58.42) (xy 23.720552 -71.239888) (xy 40.838131 -71.239888) (xy 40.842106 -71.129829)
			(xy 40.854014 -71.020343) (xy 40.87379 -70.912002) (xy 40.901333 -70.805371) (xy 40.936498 -70.701005)
			(xy 40.979102 -70.599448) (xy 41.028923 -70.501231) (xy 41.085702 -70.406864) (xy 41.149141 -70.31684)
			(xy 41.218912 -70.231629) (xy 41.294649 -70.151674) (xy 41.375958 -70.077393) (xy 41.462415 -70.009173)
			(xy 41.553569 -69.947368) (xy 41.648946 -69.892303) (xy 41.748047 -69.844263) (xy 41.850356 -69.803499)
			(xy 41.95534 -69.770224) (xy 42.062451 -69.744611) (xy 42.171131 -69.726794) (xy 42.280814 -69.716865)
			(xy 42.390927 -69.714877) (xy 42.500897 -69.720839) (xy 42.61015 -69.734721) (xy 42.718116 -69.756451)
			(xy 42.824233 -69.785914) (xy 42.927947 -69.822957) (xy 43.028718 -69.867388) (xy 43.12602 -69.918975)
			(xy 43.219346 -69.977447) (xy 43.308209 -70.042502) (xy 43.392147 -70.1138) (xy 43.470722 -70.190968)
			(xy 43.543523 -70.273605) (xy 43.610171 -70.361279) (xy 43.67032 -70.453535) (xy 43.723654 -70.54989)
			(xy 43.769897 -70.649842) (xy 43.808807 -70.75287) (xy 43.840181 -70.858438) (xy 43.863856 -70.965994)
			(xy 43.879708 -71.074978) (xy 43.887655 -71.184822) (xy 43.888152 -71.239888) (xy 60.396131 -71.239888)
			(xy 60.400106 -71.129829) (xy 60.412014 -71.020343) (xy 60.43179 -70.912002) (xy 60.459333 -70.805371)
			(xy 60.494498 -70.701005) (xy 60.537102 -70.599448) (xy 60.586923 -70.501231) (xy 60.643702 -70.406864)
			(xy 60.707141 -70.31684) (xy 60.776912 -70.231629) (xy 60.852649 -70.151674) (xy 60.933958 -70.077393)
			(xy 61.020415 -70.009173) (xy 61.111569 -69.947368) (xy 61.206946 -69.892303) (xy 61.306047 -69.844263)
			(xy 61.408356 -69.803499) (xy 61.51334 -69.770224) (xy 61.620451 -69.744611) (xy 61.729131 -69.726794)
			(xy 61.838814 -69.716865) (xy 61.948927 -69.714877) (xy 62.058897 -69.720839) (xy 62.16815 -69.734721)
			(xy 62.276116 -69.756451) (xy 62.382233 -69.785914) (xy 62.485947 -69.822957) (xy 62.586718 -69.867388)
			(xy 62.68402 -69.918975) (xy 62.777346 -69.977447) (xy 62.866209 -70.042502) (xy 62.950147 -70.1138)
			(xy 63.028722 -70.190968) (xy 63.101523 -70.273605) (xy 63.168171 -70.361279) (xy 63.22832 -70.453535)
			(xy 63.281654 -70.54989) (xy 63.327897 -70.649842) (xy 63.366807 -70.75287) (xy 63.398181 -70.858438)
			(xy 63.421856 -70.965994) (xy 63.437708 -71.074978) (xy 63.445655 -71.184822) (xy 63.446152 -71.239888)
			(xy 63.445655 -71.294954) (xy 63.437708 -71.404798) (xy 63.421856 -71.513782) (xy 63.398181 -71.621338)
			(xy 63.366807 -71.726906) (xy 63.327897 -71.829934) (xy 63.281654 -71.929886) (xy 63.22832 -72.026241)
			(xy 63.168171 -72.118497) (xy 63.101523 -72.206171) (xy 63.028722 -72.288808) (xy 62.950147 -72.365976)
			(xy 62.866209 -72.437274) (xy 62.777346 -72.502329) (xy 62.68402 -72.560801) (xy 62.586718 -72.612388)
			(xy 62.485947 -72.656819) (xy 62.382233 -72.693862) (xy 62.276116 -72.723325) (xy 62.16815 -72.745055)
			(xy 62.058897 -72.758937) (xy 61.948927 -72.764899) (xy 61.838814 -72.762911) (xy 61.729131 -72.752982)
			(xy 61.620451 -72.735165) (xy 61.51334 -72.709552) (xy 61.408356 -72.676277) (xy 61.306047 -72.635513)
			(xy 61.206946 -72.587473) (xy 61.111569 -72.532408) (xy 61.020415 -72.470603) (xy 60.933958 -72.402383)
			(xy 60.852649 -72.328102) (xy 60.776912 -72.248147) (xy 60.707141 -72.162936) (xy 60.643702 -72.072912)
			(xy 60.586923 -71.978545) (xy 60.537102 -71.880328) (xy 60.494498 -71.778771) (xy 60.459333 -71.674405)
			(xy 60.43179 -71.567774) (xy 60.412014 -71.459433) (xy 60.400106 -71.349947) (xy 60.396131 -71.239888)
			(xy 43.888152 -71.239888) (xy 43.887655 -71.294954) (xy 43.879708 -71.404798) (xy 43.863856 -71.513782)
			(xy 43.840181 -71.621338) (xy 43.808807 -71.726906) (xy 43.769897 -71.829934) (xy 43.723654 -71.929886)
			(xy 43.67032 -72.026241) (xy 43.610171 -72.118497) (xy 43.543523 -72.206171) (xy 43.470722 -72.288808)
			(xy 43.392147 -72.365976) (xy 43.308209 -72.437274) (xy 43.219346 -72.502329) (xy 43.12602 -72.560801)
			(xy 43.028718 -72.612388) (xy 42.927947 -72.656819) (xy 42.824233 -72.693862) (xy 42.718116 -72.723325)
			(xy 42.61015 -72.745055) (xy 42.500897 -72.758937) (xy 42.390927 -72.764899) (xy 42.280814 -72.762911)
			(xy 42.171131 -72.752982) (xy 42.062451 -72.735165) (xy 41.95534 -72.709552) (xy 41.850356 -72.676277)
			(xy 41.748047 -72.635513) (xy 41.648946 -72.587473) (xy 41.553569 -72.532408) (xy 41.462415 -72.470603)
			(xy 41.375958 -72.402383) (xy 41.294649 -72.328102) (xy 41.218912 -72.248147) (xy 41.149141 -72.162936)
			(xy 41.085702 -72.072912) (xy 41.028923 -71.978545) (xy 40.979102 -71.880328) (xy 40.936498 -71.778771)
			(xy 40.901333 -71.674405) (xy 40.87379 -71.567774) (xy 40.854014 -71.459433) (xy 40.842106 -71.349947)
			(xy 40.838131 -71.239888) (xy 23.720552 -71.239888) (xy 23.720552 -78.74) (xy 41.345876 -78.74) (xy 41.349858 -78.650072)
			(xy 41.361772 -78.560848) (xy 41.381525 -78.473026) (xy 41.408962 -78.387293) (xy 41.443869 -78.304321)
			(xy 41.485973 -78.224758) (xy 41.534943 -78.149228) (xy 41.590398 -78.078322) (xy 41.651902 -78.012594)
			(xy 41.718974 -77.952559) (xy 41.79109 -77.898687) (xy 41.867685 -77.851399) (xy 41.948159 -77.811066)
			(xy 42.031883 -77.778003) (xy 42.118202 -77.752469) (xy 42.20644 -77.734664) (xy 42.295905 -77.724726)
			(xy 42.3859 -77.722735) (xy 42.475717 -77.728705) (xy 42.564656 -77.74259) (xy 42.65202 -77.764281)
			(xy 42.737125 -77.793608) (xy 42.819304 -77.830342) (xy 42.897916 -77.874196) (xy 42.972344 -77.924825)
			(xy 43.042006 -77.981835) (xy 43.106357 -78.044778) (xy 43.164894 -78.113162) (xy 43.217157 -78.186452)
			(xy 43.262739 -78.264074) (xy 43.301282 -78.345421) (xy 43.332485 -78.429856) (xy 43.356103 -78.516718)
			(xy 43.371952 -78.605328) (xy 43.379908 -78.694992) (xy 43.380406 -78.74) (xy 60.903876 -78.74) (xy 60.907858 -78.650072)
			(xy 60.919772 -78.560848) (xy 60.939525 -78.473026) (xy 60.966962 -78.387293) (xy 61.001869 -78.304321)
			(xy 61.043973 -78.224758) (xy 61.092943 -78.149228) (xy 61.148398 -78.078322) (xy 61.209902 -78.012594)
			(xy 61.276974 -77.952559) (xy 61.34909 -77.898687) (xy 61.425685 -77.851399) (xy 61.506159 -77.811066)
			(xy 61.589883 -77.778003) (xy 61.676202 -77.752469) (xy 61.76444 -77.734664) (xy 61.853905 -77.724726)
			(xy 61.9439 -77.722735) (xy 62.033717 -77.728705) (xy 62.122656 -77.74259) (xy 62.21002 -77.764281)
			(xy 62.295125 -77.793608) (xy 62.377304 -77.830342) (xy 62.455916 -77.874196) (xy 62.530344 -77.924825)
			(xy 62.600006 -77.981835) (xy 62.664357 -78.044778) (xy 62.722894 -78.113162) (xy 62.775157 -78.186452)
			(xy 62.820739 -78.264074) (xy 62.859282 -78.345421) (xy 62.890485 -78.429856) (xy 62.914103 -78.516718)
			(xy 62.929952 -78.605328) (xy 62.937908 -78.694992) (xy 62.938406 -78.74) (xy 62.937908 -78.785008)
			(xy 62.929952 -78.874672) (xy 62.914103 -78.963282) (xy 62.890485 -79.050144) (xy 62.859282 -79.134579)
			(xy 62.820739 -79.215926) (xy 62.775157 -79.293548) (xy 62.722894 -79.366838) (xy 62.664357 -79.435222)
			(xy 62.600006 -79.498165) (xy 62.530344 -79.555175) (xy 62.455916 -79.605804) (xy 62.377304 -79.649658)
			(xy 62.295125 -79.686392) (xy 62.21002 -79.715719) (xy 62.122656 -79.73741) (xy 62.033717 -79.751295)
			(xy 61.9439 -79.757265) (xy 61.853905 -79.755274) (xy 61.76444 -79.745336) (xy 61.676202 -79.727531)
			(xy 61.589883 -79.701997) (xy 61.506159 -79.668934) (xy 61.425685 -79.628601) (xy 61.34909 -79.581313)
			(xy 61.276974 -79.527441) (xy 61.209902 -79.467406) (xy 61.148398 -79.401678) (xy 61.092943 -79.330772)
			(xy 61.043973 -79.255242) (xy 61.001869 -79.175679) (xy 60.966962 -79.092707) (xy 60.939525 -79.006974)
			(xy 60.919772 -78.919152) (xy 60.907858 -78.829928) (xy 60.903876 -78.74) (xy 43.380406 -78.74) (xy 43.379908 -78.785008)
			(xy 43.371952 -78.874672) (xy 43.356103 -78.963282) (xy 43.332485 -79.050144) (xy 43.301282 -79.134579)
			(xy 43.262739 -79.215926) (xy 43.217157 -79.293548) (xy 43.164894 -79.366838) (xy 43.106357 -79.435222)
			(xy 43.042006 -79.498165) (xy 42.972344 -79.555175) (xy 42.897916 -79.605804) (xy 42.819304 -79.649658)
			(xy 42.737125 -79.686392) (xy 42.65202 -79.715719) (xy 42.564656 -79.73741) (xy 42.475717 -79.751295)
			(xy 42.3859 -79.757265) (xy 42.295905 -79.755274) (xy 42.20644 -79.745336) (xy 42.118202 -79.727531)
			(xy 42.031883 -79.701997) (xy 41.948159 -79.668934) (xy 41.867685 -79.628601) (xy 41.79109 -79.581313)
			(xy 41.718974 -79.527441) (xy 41.651902 -79.467406) (xy 41.590398 -79.401678) (xy 41.534943 -79.330772)
			(xy 41.485973 -79.255242) (xy 41.443869 -79.175679) (xy 41.408962 -79.092707) (xy 41.381525 -79.006974)
			(xy 41.361772 -78.919152) (xy 41.349858 -78.829928) (xy 41.345876 -78.74) (xy 23.720552 -78.74) (xy 23.720552 -91.559888)
			(xy 40.838131 -91.559888) (xy 40.842106 -91.449829) (xy 40.854014 -91.340343) (xy 40.87379 -91.232002)
			(xy 40.901333 -91.125371) (xy 40.936498 -91.021005) (xy 40.979102 -90.919448) (xy 41.028923 -90.821231)
			(xy 41.085702 -90.726864) (xy 41.149141 -90.63684) (xy 41.218912 -90.551629) (xy 41.294649 -90.471674)
			(xy 41.375958 -90.397393) (xy 41.462415 -90.329173) (xy 41.553569 -90.267368) (xy 41.648946 -90.212303)
			(xy 41.748047 -90.164263) (xy 41.850356 -90.123499) (xy 41.95534 -90.090224) (xy 42.062451 -90.064611)
			(xy 42.171131 -90.046794) (xy 42.280814 -90.036865) (xy 42.390927 -90.034877) (xy 42.500897 -90.040839)
			(xy 42.61015 -90.054721) (xy 42.718116 -90.076451) (xy 42.824233 -90.105914) (xy 42.927947 -90.142957)
			(xy 43.028718 -90.187388) (xy 43.12602 -90.238975) (xy 43.219346 -90.297447) (xy 43.308209 -90.362502)
			(xy 43.392147 -90.4338) (xy 43.470722 -90.510968) (xy 43.543523 -90.593605) (xy 43.610171 -90.681279)
			(xy 43.67032 -90.773535) (xy 43.723654 -90.86989) (xy 43.769897 -90.969842) (xy 43.808807 -91.07287)
			(xy 43.840181 -91.178438) (xy 43.863856 -91.285994) (xy 43.879708 -91.394978) (xy 43.887655 -91.504822)
			(xy 43.888152 -91.559888) (xy 60.396131 -91.559888) (xy 60.400106 -91.449829) (xy 60.412014 -91.340343)
			(xy 60.43179 -91.232002) (xy 60.459333 -91.125371) (xy 60.494498 -91.021005) (xy 60.537102 -90.919448)
			(xy 60.586923 -90.821231) (xy 60.643702 -90.726864) (xy 60.707141 -90.63684) (xy 60.776912 -90.551629)
			(xy 60.852649 -90.471674) (xy 60.933958 -90.397393) (xy 61.020415 -90.329173) (xy 61.111569 -90.267368)
			(xy 61.206946 -90.212303) (xy 61.306047 -90.164263) (xy 61.408356 -90.123499) (xy 61.51334 -90.090224)
			(xy 61.620451 -90.064611) (xy 61.729131 -90.046794) (xy 61.838814 -90.036865) (xy 61.948927 -90.034877)
			(xy 62.058897 -90.040839) (xy 62.16815 -90.054721) (xy 62.276116 -90.076451) (xy 62.382233 -90.105914)
			(xy 62.485947 -90.142957) (xy 62.586718 -90.187388) (xy 62.68402 -90.238975) (xy 62.777346 -90.297447)
			(xy 62.866209 -90.362502) (xy 62.950147 -90.4338) (xy 63.028722 -90.510968) (xy 63.101523 -90.593605)
			(xy 63.168171 -90.681279) (xy 63.22832 -90.773535) (xy 63.281654 -90.86989) (xy 63.327897 -90.969842)
			(xy 63.366807 -91.07287) (xy 63.398181 -91.178438) (xy 63.421856 -91.285994) (xy 63.437708 -91.394978)
			(xy 63.445655 -91.504822) (xy 63.446152 -91.559888) (xy 63.445655 -91.614954) (xy 63.437708 -91.724798)
			(xy 63.421856 -91.833782) (xy 63.398181 -91.941338) (xy 63.366807 -92.046906) (xy 63.327897 -92.149934)
			(xy 63.281654 -92.249886) (xy 63.22832 -92.346241) (xy 63.168171 -92.438497) (xy 63.121269 -92.500196)
			(xy 94.864936 -92.500196) (xy 94.864936 -87.500206) (xy 94.865431 -87.399365) (xy 94.873349 -87.197838)
			(xy 94.889173 -86.996778) (xy 94.912878 -86.796494) (xy 94.944428 -86.597295) (xy 94.983774 -86.399488)
			(xy 95.030856 -86.203379) (xy 95.085601 -86.009269) (xy 95.147924 -85.817458) (xy 95.217729 -85.628241)
			(xy 95.29491 -85.441912) (xy 95.379346 -85.258755) (xy 95.470908 -85.079055) (xy 95.569454 -84.903089)
			(xy 95.674832 -84.731126) (xy 95.786881 -84.563434) (xy 95.905427 -84.40027) (xy 96.030287 -84.241885)
			(xy 96.161269 -84.088525) (xy 96.298171 -83.940425) (xy 96.440781 -83.797815) (xy 96.588881 -83.660913)
			(xy 96.742241 -83.529931) (xy 96.900626 -83.405071) (xy 97.06379 -83.286525) (xy 97.231482 -83.174476)
			(xy 97.403445 -83.069098) (xy 97.579411 -82.970552) (xy 97.759111 -82.87899) (xy 97.942268 -82.794554)
			(xy 98.128597 -82.717373) (xy 98.317814 -82.647568) (xy 98.509625 -82.585245) (xy 98.703735 -82.5305)
			(xy 98.899844 -82.483418) (xy 99.097651 -82.444072) (xy 99.29685 -82.412522) (xy 99.497134 -82.388817)
			(xy 99.698194 -82.372993) (xy 99.899721 -82.365075) (xy 100.101403 -82.365075) (xy 100.30293 -82.372993)
			(xy 100.50399 -82.388817) (xy 100.704274 -82.412522) (xy 100.903473 -82.444072) (xy 101.10128 -82.483418)
			(xy 101.297389 -82.5305) (xy 101.491499 -82.585245) (xy 101.68331 -82.647568) (xy 101.872527 -82.717373)
			(xy 102.058856 -82.794554) (xy 102.242013 -82.87899) (xy 102.421713 -82.970552) (xy 102.597679 -83.069098)
			(xy 102.769642 -83.174476) (xy 102.937334 -83.286525) (xy 103.100498 -83.405071) (xy 103.258883 -83.529931)
			(xy 103.412243 -83.660913) (xy 103.560343 -83.797815) (xy 103.702953 -83.940425) (xy 103.839855 -84.088525)
			(xy 103.970837 -84.241885) (xy 104.095697 -84.40027) (xy 104.214243 -84.563434) (xy 104.326292 -84.731126)
			(xy 104.43167 -84.903089) (xy 104.530216 -85.079055) (xy 104.621778 -85.258755) (xy 104.706214 -85.441912)
			(xy 104.783395 -85.628241) (xy 104.8532 -85.817458) (xy 104.915523 -86.009269) (xy 104.970268 -86.203379)
			(xy 105.01735 -86.399488) (xy 105.056696 -86.597295) (xy 105.088246 -86.796494) (xy 105.111951 -86.996778)
			(xy 105.127775 -87.197838) (xy 105.135693 -87.399365) (xy 105.136188 -87.500206) (xy 105.136188 -92.500196)
			(xy 105.135693 -92.601037) (xy 105.127775 -92.802564) (xy 105.111951 -93.003624) (xy 105.088246 -93.203908)
			(xy 105.056696 -93.403107) (xy 105.01735 -93.600914) (xy 104.970268 -93.797023) (xy 104.915523 -93.991133)
			(xy 104.8532 -94.182944) (xy 104.783395 -94.372161) (xy 104.706214 -94.55849) (xy 104.621778 -94.741647)
			(xy 104.530216 -94.921347) (xy 104.43167 -95.097313) (xy 104.326292 -95.269276) (xy 104.214243 -95.436968)
			(xy 104.095697 -95.600132) (xy 103.970837 -95.758517) (xy 103.839855 -95.911877) (xy 103.702953 -96.059977)
			(xy 103.560343 -96.202587) (xy 103.412243 -96.339489) (xy 103.258883 -96.470471) (xy 103.100498 -96.595331)
			(xy 102.937334 -96.713877) (xy 102.769642 -96.825926) (xy 102.597679 -96.931304) (xy 102.421713 -97.02985)
			(xy 102.242013 -97.121412) (xy 102.058856 -97.205848) (xy 101.872527 -97.283029) (xy 101.68331 -97.352834)
			(xy 101.491499 -97.415157) (xy 101.297389 -97.469902) (xy 101.10128 -97.516984) (xy 100.903473 -97.55633)
			(xy 100.704274 -97.58788) (xy 100.50399 -97.611585) (xy 100.30293 -97.627409) (xy 100.101403 -97.635327)
			(xy 99.899721 -97.635327) (xy 99.698194 -97.627409) (xy 99.497134 -97.611585) (xy 99.29685 -97.58788)
			(xy 99.097651 -97.55633) (xy 98.899844 -97.516984) (xy 98.703735 -97.469902) (xy 98.509625 -97.415157)
			(xy 98.317814 -97.352834) (xy 98.128597 -97.283029) (xy 97.942268 -97.205848) (xy 97.759111 -97.121412)
			(xy 97.579411 -97.02985) (xy 97.403445 -96.931304) (xy 97.231482 -96.825926) (xy 97.06379 -96.713877)
			(xy 96.900626 -96.595331) (xy 96.742241 -96.470471) (xy 96.588881 -96.339489) (xy 96.440781 -96.202587)
			(xy 96.298171 -96.059977) (xy 96.161269 -95.911877) (xy 96.030287 -95.758517) (xy 95.905427 -95.600132)
			(xy 95.786881 -95.436968) (xy 95.674832 -95.269276) (xy 95.569454 -95.097313) (xy 95.470908 -94.921347)
			(xy 95.379346 -94.741647) (xy 95.29491 -94.55849) (xy 95.217729 -94.372161) (xy 95.147924 -94.182944)
			(xy 95.085601 -93.991133) (xy 95.030856 -93.797023) (xy 94.983774 -93.600914) (xy 94.944428 -93.403107)
			(xy 94.912878 -93.203908) (xy 94.889173 -93.003624) (xy 94.873349 -92.802564) (xy 94.865431 -92.601037)
			(xy 94.864936 -92.500196) (xy 63.121269 -92.500196) (xy 63.101523 -92.526171) (xy 63.028722 -92.608808)
			(xy 62.950147 -92.685976) (xy 62.866209 -92.757274) (xy 62.777346 -92.822329) (xy 62.68402 -92.880801)
			(xy 62.586718 -92.932388) (xy 62.485947 -92.976819) (xy 62.382233 -93.013862) (xy 62.276116 -93.043325)
			(xy 62.16815 -93.065055) (xy 62.058897 -93.078937) (xy 61.948927 -93.084899) (xy 61.838814 -93.082911)
			(xy 61.729131 -93.072982) (xy 61.620451 -93.055165) (xy 61.51334 -93.029552) (xy 61.408356 -92.996277)
			(xy 61.306047 -92.955513) (xy 61.206946 -92.907473) (xy 61.111569 -92.852408) (xy 61.020415 -92.790603)
			(xy 60.933958 -92.722383) (xy 60.852649 -92.648102) (xy 60.776912 -92.568147) (xy 60.707141 -92.482936)
			(xy 60.643702 -92.392912) (xy 60.586923 -92.298545) (xy 60.537102 -92.200328) (xy 60.494498 -92.098771)
			(xy 60.459333 -91.994405) (xy 60.43179 -91.887774) (xy 60.412014 -91.779433) (xy 60.400106 -91.669947)
			(xy 60.396131 -91.559888) (xy 43.888152 -91.559888) (xy 43.887655 -91.614954) (xy 43.879708 -91.724798)
			(xy 43.863856 -91.833782) (xy 43.840181 -91.941338) (xy 43.808807 -92.046906) (xy 43.769897 -92.149934)
			(xy 43.723654 -92.249886) (xy 43.67032 -92.346241) (xy 43.610171 -92.438497) (xy 43.543523 -92.526171)
			(xy 43.470722 -92.608808) (xy 43.392147 -92.685976) (xy 43.308209 -92.757274) (xy 43.219346 -92.822329)
			(xy 43.12602 -92.880801) (xy 43.028718 -92.932388) (xy 42.927947 -92.976819) (xy 42.824233 -93.013862)
			(xy 42.718116 -93.043325) (xy 42.61015 -93.065055) (xy 42.500897 -93.078937) (xy 42.390927 -93.084899)
			(xy 42.280814 -93.082911) (xy 42.171131 -93.072982) (xy 42.062451 -93.055165) (xy 41.95534 -93.029552)
			(xy 41.850356 -92.996277) (xy 41.748047 -92.955513) (xy 41.648946 -92.907473) (xy 41.553569 -92.852408)
			(xy 41.462415 -92.790603) (xy 41.375958 -92.722383) (xy 41.294649 -92.648102) (xy 41.218912 -92.568147)
			(xy 41.149141 -92.482936) (xy 41.085702 -92.392912) (xy 41.028923 -92.298545) (xy 40.979102 -92.200328)
			(xy 40.936498 -92.098771) (xy 40.901333 -91.994405) (xy 40.87379 -91.887774) (xy 40.854014 -91.779433)
			(xy 40.842106 -91.669947) (xy 40.838131 -91.559888) (xy 23.720552 -91.559888) (xy 23.720552 -99.06)
			(xy 41.345876 -99.06) (xy 41.349858 -98.970072) (xy 41.361772 -98.880848) (xy 41.381525 -98.793026)
			(xy 41.408962 -98.707293) (xy 41.443869 -98.624321) (xy 41.485973 -98.544758) (xy 41.534943 -98.469228)
			(xy 41.590398 -98.398322) (xy 41.651902 -98.332594) (xy 41.718974 -98.272559) (xy 41.79109 -98.218687)
			(xy 41.867685 -98.171399) (xy 41.948159 -98.131066) (xy 42.031883 -98.098003) (xy 42.118202 -98.072469)
			(xy 42.20644 -98.054664) (xy 42.295905 -98.044726) (xy 42.3859 -98.042735) (xy 42.475717 -98.048705)
			(xy 42.564656 -98.06259) (xy 42.65202 -98.084281) (xy 42.737125 -98.113608) (xy 42.819304 -98.150342)
			(xy 42.897916 -98.194196) (xy 42.972344 -98.244825) (xy 43.042006 -98.301835) (xy 43.106357 -98.364778)
			(xy 43.164894 -98.433162) (xy 43.217157 -98.506452) (xy 43.262739 -98.584074) (xy 43.301282 -98.665421)
			(xy 43.332485 -98.749856) (xy 43.356103 -98.836718) (xy 43.371952 -98.925328) (xy 43.379908 -99.014992)
			(xy 43.380406 -99.06) (xy 60.903876 -99.06) (xy 60.907858 -98.970072) (xy 60.919772 -98.880848) (xy 60.939525 -98.793026)
			(xy 60.966962 -98.707293) (xy 61.001869 -98.624321) (xy 61.043973 -98.544758) (xy 61.092943 -98.469228)
			(xy 61.148398 -98.398322) (xy 61.209902 -98.332594) (xy 61.276974 -98.272559) (xy 61.34909 -98.218687)
			(xy 61.425685 -98.171399) (xy 61.506159 -98.131066) (xy 61.589883 -98.098003) (xy 61.676202 -98.072469)
			(xy 61.76444 -98.054664) (xy 61.853905 -98.044726) (xy 61.9439 -98.042735) (xy 62.033717 -98.048705)
			(xy 62.122656 -98.06259) (xy 62.21002 -98.084281) (xy 62.295125 -98.113608) (xy 62.377304 -98.150342)
			(xy 62.455916 -98.194196) (xy 62.530344 -98.244825) (xy 62.600006 -98.301835) (xy 62.664357 -98.364778)
			(xy 62.722894 -98.433162) (xy 62.775157 -98.506452) (xy 62.820739 -98.584074) (xy 62.859282 -98.665421)
			(xy 62.890485 -98.749856) (xy 62.914103 -98.836718) (xy 62.929952 -98.925328) (xy 62.937908 -99.014992)
			(xy 62.938406 -99.06) (xy 62.937908 -99.105008) (xy 62.929952 -99.194672) (xy 62.914103 -99.283282)
			(xy 62.890485 -99.370144) (xy 62.859282 -99.454579) (xy 62.820739 -99.535926) (xy 62.775157 -99.613548)
			(xy 62.722894 -99.686838) (xy 62.664357 -99.755222) (xy 62.600006 -99.818165) (xy 62.530344 -99.875175)
			(xy 62.455916 -99.925804) (xy 62.377304 -99.969658) (xy 62.295125 -100.006392) (xy 62.21002 -100.035719)
			(xy 62.122656 -100.05741) (xy 62.033717 -100.071295) (xy 61.9439 -100.077265) (xy 61.853905 -100.075274)
			(xy 61.76444 -100.065336) (xy 61.676202 -100.047531) (xy 61.589883 -100.021997) (xy 61.506159 -99.988934)
			(xy 61.425685 -99.948601) (xy 61.34909 -99.901313) (xy 61.276974 -99.847441) (xy 61.209902 -99.787406)
			(xy 61.148398 -99.721678) (xy 61.092943 -99.650772) (xy 61.043973 -99.575242) (xy 61.001869 -99.495679)
			(xy 60.966962 -99.412707) (xy 60.939525 -99.326974) (xy 60.919772 -99.239152) (xy 60.907858 -99.149928)
			(xy 60.903876 -99.06) (xy 43.380406 -99.06) (xy 43.379908 -99.105008) (xy 43.371952 -99.194672) (xy 43.356103 -99.283282)
			(xy 43.332485 -99.370144) (xy 43.301282 -99.454579) (xy 43.262739 -99.535926) (xy 43.217157 -99.613548)
			(xy 43.164894 -99.686838) (xy 43.106357 -99.755222) (xy 43.042006 -99.818165) (xy 42.972344 -99.875175)
			(xy 42.897916 -99.925804) (xy 42.819304 -99.969658) (xy 42.737125 -100.006392) (xy 42.65202 -100.035719)
			(xy 42.564656 -100.05741) (xy 42.475717 -100.071295) (xy 42.3859 -100.077265) (xy 42.295905 -100.075274)
			(xy 42.20644 -100.065336) (xy 42.118202 -100.047531) (xy 42.031883 -100.021997) (xy 41.948159 -99.988934)
			(xy 41.867685 -99.948601) (xy 41.79109 -99.901313) (xy 41.718974 -99.847441) (xy 41.651902 -99.787406)
			(xy 41.590398 -99.721678) (xy 41.534943 -99.650772) (xy 41.485973 -99.575242) (xy 41.443869 -99.495679)
			(xy 41.408962 -99.412707) (xy 41.381525 -99.326974) (xy 41.361772 -99.239152) (xy 41.349858 -99.149928)
			(xy 41.345876 -99.06) (xy 23.720552 -99.06) (xy 23.720552 -111.879888) (xy 40.838131 -111.879888)
			(xy 40.842106 -111.769829) (xy 40.854014 -111.660343) (xy 40.87379 -111.552002) (xy 40.901333 -111.445371)
			(xy 40.936498 -111.341005) (xy 40.979102 -111.239448) (xy 41.028923 -111.141231) (xy 41.085702 -111.046864)
			(xy 41.149141 -110.95684) (xy 41.218912 -110.871629) (xy 41.294649 -110.791674) (xy 41.375958 -110.717393)
			(xy 41.462415 -110.649173) (xy 41.553569 -110.587368) (xy 41.648946 -110.532303) (xy 41.748047 -110.484263)
			(xy 41.850356 -110.443499) (xy 41.95534 -110.410224) (xy 42.062451 -110.384611) (xy 42.171131 -110.366794)
			(xy 42.280814 -110.356865) (xy 42.390927 -110.354877) (xy 42.500897 -110.360839) (xy 42.61015 -110.374721)
			(xy 42.718116 -110.396451) (xy 42.824233 -110.425914) (xy 42.927947 -110.462957) (xy 43.028718 -110.507388)
			(xy 43.12602 -110.558975) (xy 43.219346 -110.617447) (xy 43.308209 -110.682502) (xy 43.392147 -110.7538)
			(xy 43.470722 -110.830968) (xy 43.543523 -110.913605) (xy 43.610171 -111.001279) (xy 43.67032 -111.093535)
			(xy 43.723654 -111.18989) (xy 43.769897 -111.289842) (xy 43.808807 -111.39287) (xy 43.840181 -111.498438)
			(xy 43.863856 -111.605994) (xy 43.879708 -111.714978) (xy 43.887655 -111.824822) (xy 43.888152 -111.879888)
			(xy 60.396131 -111.879888) (xy 60.400106 -111.769829) (xy 60.412014 -111.660343) (xy 60.43179 -111.552002)
			(xy 60.459333 -111.445371) (xy 60.494498 -111.341005) (xy 60.537102 -111.239448) (xy 60.586923 -111.141231)
			(xy 60.643702 -111.046864) (xy 60.707141 -110.95684) (xy 60.776912 -110.871629) (xy 60.852649 -110.791674)
			(xy 60.933958 -110.717393) (xy 61.020415 -110.649173) (xy 61.111569 -110.587368) (xy 61.206946 -110.532303)
			(xy 61.306047 -110.484263) (xy 61.408356 -110.443499) (xy 61.51334 -110.410224) (xy 61.620451 -110.384611)
			(xy 61.729131 -110.366794) (xy 61.838814 -110.356865) (xy 61.948927 -110.354877) (xy 62.058897 -110.360839)
			(xy 62.16815 -110.374721) (xy 62.276116 -110.396451) (xy 62.382233 -110.425914) (xy 62.485947 -110.462957)
			(xy 62.586718 -110.507388) (xy 62.68402 -110.558975) (xy 62.777346 -110.617447) (xy 62.866209 -110.682502)
			(xy 62.950147 -110.7538) (xy 63.028722 -110.830968) (xy 63.101523 -110.913605) (xy 63.168171 -111.001279)
			(xy 63.22832 -111.093535) (xy 63.281654 -111.18989) (xy 63.327897 -111.289842) (xy 63.366807 -111.39287)
			(xy 63.398181 -111.498438) (xy 63.421856 -111.605994) (xy 63.437708 -111.714978) (xy 63.445655 -111.824822)
			(xy 63.446152 -111.879888) (xy 63.445655 -111.934954) (xy 63.437708 -112.044798) (xy 63.421856 -112.153782)
			(xy 63.398181 -112.261338) (xy 63.366807 -112.366906) (xy 63.327897 -112.469934) (xy 63.281654 -112.569886)
			(xy 63.22832 -112.666241) (xy 63.168171 -112.758497) (xy 63.101523 -112.846171) (xy 63.028722 -112.928808)
			(xy 62.950147 -113.005976) (xy 62.866209 -113.077274) (xy 62.777346 -113.142329) (xy 62.68402 -113.200801)
			(xy 62.586718 -113.252388) (xy 62.485947 -113.296819) (xy 62.382233 -113.333862) (xy 62.276116 -113.363325)
			(xy 62.16815 -113.385055) (xy 62.058897 -113.398937) (xy 61.948927 -113.404899) (xy 61.838814 -113.402911)
			(xy 61.729131 -113.392982) (xy 61.620451 -113.375165) (xy 61.51334 -113.349552) (xy 61.408356 -113.316277)
			(xy 61.306047 -113.275513) (xy 61.206946 -113.227473) (xy 61.111569 -113.172408) (xy 61.020415 -113.110603)
			(xy 60.933958 -113.042383) (xy 60.852649 -112.968102) (xy 60.776912 -112.888147) (xy 60.707141 -112.802936)
			(xy 60.643702 -112.712912) (xy 60.586923 -112.618545) (xy 60.537102 -112.520328) (xy 60.494498 -112.418771)
			(xy 60.459333 -112.314405) (xy 60.43179 -112.207774) (xy 60.412014 -112.099433) (xy 60.400106 -111.989947)
			(xy 60.396131 -111.879888) (xy 43.888152 -111.879888) (xy 43.887655 -111.934954) (xy 43.879708 -112.044798)
			(xy 43.863856 -112.153782) (xy 43.840181 -112.261338) (xy 43.808807 -112.366906) (xy 43.769897 -112.469934)
			(xy 43.723654 -112.569886) (xy 43.67032 -112.666241) (xy 43.610171 -112.758497) (xy 43.543523 -112.846171)
			(xy 43.470722 -112.928808) (xy 43.392147 -113.005976) (xy 43.308209 -113.077274) (xy 43.219346 -113.142329)
			(xy 43.12602 -113.200801) (xy 43.028718 -113.252388) (xy 42.927947 -113.296819) (xy 42.824233 -113.333862)
			(xy 42.718116 -113.363325) (xy 42.61015 -113.385055) (xy 42.500897 -113.398937) (xy 42.390927 -113.404899)
			(xy 42.280814 -113.402911) (xy 42.171131 -113.392982) (xy 42.062451 -113.375165) (xy 41.95534 -113.349552)
			(xy 41.850356 -113.316277) (xy 41.748047 -113.275513) (xy 41.648946 -113.227473) (xy 41.553569 -113.172408)
			(xy 41.462415 -113.110603) (xy 41.375958 -113.042383) (xy 41.294649 -112.968102) (xy 41.218912 -112.888147)
			(xy 41.149141 -112.802936) (xy 41.085702 -112.712912) (xy 41.028923 -112.618545) (xy 40.979102 -112.520328)
			(xy 40.936498 -112.418771) (xy 40.901333 -112.314405) (xy 40.87379 -112.207774) (xy 40.854014 -112.099433)
			(xy 40.842106 -111.989947) (xy 40.838131 -111.879888) (xy 23.720552 -111.879888) (xy 23.720552 -119.38)
			(xy 41.345876 -119.38) (xy 41.349858 -119.290072) (xy 41.361772 -119.200848) (xy 41.381525 -119.113026)
			(xy 41.408962 -119.027293) (xy 41.443869 -118.944321) (xy 41.485973 -118.864758) (xy 41.534943 -118.789228)
			(xy 41.590398 -118.718322) (xy 41.651902 -118.652594) (xy 41.718974 -118.592559) (xy 41.79109 -118.538687)
			(xy 41.867685 -118.491399) (xy 41.948159 -118.451066) (xy 42.031883 -118.418003) (xy 42.118202 -118.392469)
			(xy 42.20644 -118.374664) (xy 42.295905 -118.364726) (xy 42.3859 -118.362735) (xy 42.475717 -118.368705)
			(xy 42.564656 -118.38259) (xy 42.65202 -118.404281) (xy 42.737125 -118.433608) (xy 42.819304 -118.470342)
			(xy 42.897916 -118.514196) (xy 42.972344 -118.564825) (xy 43.042006 -118.621835) (xy 43.106357 -118.684778)
			(xy 43.164894 -118.753162) (xy 43.217157 -118.826452) (xy 43.262739 -118.904074) (xy 43.301282 -118.985421)
			(xy 43.332485 -119.069856) (xy 43.356103 -119.156718) (xy 43.371952 -119.245328) (xy 43.379908 -119.334992)
			(xy 43.380406 -119.38) (xy 60.903876 -119.38) (xy 60.907858 -119.290072) (xy 60.919772 -119.200848)
			(xy 60.939525 -119.113026) (xy 60.966962 -119.027293) (xy 61.001869 -118.944321) (xy 61.043973 -118.864758)
			(xy 61.092943 -118.789228) (xy 61.148398 -118.718322) (xy 61.209902 -118.652594) (xy 61.276974 -118.592559)
			(xy 61.34909 -118.538687) (xy 61.425685 -118.491399) (xy 61.506159 -118.451066) (xy 61.589883 -118.418003)
			(xy 61.676202 -118.392469) (xy 61.76444 -118.374664) (xy 61.853905 -118.364726) (xy 61.9439 -118.362735)
			(xy 62.033717 -118.368705) (xy 62.122656 -118.38259) (xy 62.21002 -118.404281) (xy 62.295125 -118.433608)
			(xy 62.377304 -118.470342) (xy 62.455916 -118.514196) (xy 62.530344 -118.564825) (xy 62.600006 -118.621835)
			(xy 62.664357 -118.684778) (xy 62.722894 -118.753162) (xy 62.775157 -118.826452) (xy 62.820739 -118.904074)
			(xy 62.859282 -118.985421) (xy 62.890485 -119.069856) (xy 62.914103 -119.156718) (xy 62.929952 -119.245328)
			(xy 62.937908 -119.334992) (xy 62.938406 -119.38) (xy 62.937908 -119.425008) (xy 62.929952 -119.514672)
			(xy 62.914103 -119.603282) (xy 62.890485 -119.690144) (xy 62.859282 -119.774579) (xy 62.820739 -119.855926)
			(xy 62.775157 -119.933548) (xy 62.722894 -120.006838) (xy 62.664357 -120.075222) (xy 62.600006 -120.138165)
			(xy 62.530344 -120.195175) (xy 62.455916 -120.245804) (xy 62.377304 -120.289658) (xy 62.295125 -120.326392)
			(xy 62.21002 -120.355719) (xy 62.122656 -120.37741) (xy 62.033717 -120.391295) (xy 61.9439 -120.397265)
			(xy 61.853905 -120.395274) (xy 61.76444 -120.385336) (xy 61.676202 -120.367531) (xy 61.589883 -120.341997)
			(xy 61.506159 -120.308934) (xy 61.425685 -120.268601) (xy 61.34909 -120.221313) (xy 61.276974 -120.167441)
			(xy 61.209902 -120.107406) (xy 61.148398 -120.041678) (xy 61.092943 -119.970772) (xy 61.043973 -119.895242)
			(xy 61.001869 -119.815679) (xy 60.966962 -119.732707) (xy 60.939525 -119.646974) (xy 60.919772 -119.559152)
			(xy 60.907858 -119.469928) (xy 60.903876 -119.38) (xy 43.380406 -119.38) (xy 43.379908 -119.425008)
			(xy 43.371952 -119.514672) (xy 43.356103 -119.603282) (xy 43.332485 -119.690144) (xy 43.301282 -119.774579)
			(xy 43.262739 -119.855926) (xy 43.217157 -119.933548) (xy 43.164894 -120.006838) (xy 43.106357 -120.075222)
			(xy 43.042006 -120.138165) (xy 42.972344 -120.195175) (xy 42.897916 -120.245804) (xy 42.819304 -120.289658)
			(xy 42.737125 -120.326392) (xy 42.65202 -120.355719) (xy 42.564656 -120.37741) (xy 42.475717 -120.391295)
			(xy 42.3859 -120.397265) (xy 42.295905 -120.395274) (xy 42.20644 -120.385336) (xy 42.118202 -120.367531)
			(xy 42.031883 -120.341997) (xy 41.948159 -120.308934) (xy 41.867685 -120.268601) (xy 41.79109 -120.221313)
			(xy 41.718974 -120.167441) (xy 41.651902 -120.107406) (xy 41.590398 -120.041678) (xy 41.534943 -119.970772)
			(xy 41.485973 -119.895242) (xy 41.443869 -119.815679) (xy 41.408962 -119.732707) (xy 41.381525 -119.646974)
			(xy 41.361772 -119.559152) (xy 41.349858 -119.469928) (xy 41.345876 -119.38) (xy 23.720552 -119.38)
			(xy 23.720552 -132.199888) (xy 40.838131 -132.199888) (xy 40.842106 -132.089829) (xy 40.854014 -131.980343)
			(xy 40.87379 -131.872002) (xy 40.901333 -131.765371) (xy 40.936498 -131.661005) (xy 40.979102 -131.559448)
			(xy 41.028923 -131.461231) (xy 41.085702 -131.366864) (xy 41.149141 -131.27684) (xy 41.218912 -131.191629)
			(xy 41.294649 -131.111674) (xy 41.375958 -131.037393) (xy 41.462415 -130.969173) (xy 41.553569 -130.907368)
			(xy 41.648946 -130.852303) (xy 41.748047 -130.804263) (xy 41.850356 -130.763499) (xy 41.95534 -130.730224)
			(xy 42.062451 -130.704611) (xy 42.171131 -130.686794) (xy 42.280814 -130.676865) (xy 42.390927 -130.674877)
			(xy 42.500897 -130.680839) (xy 42.61015 -130.694721) (xy 42.718116 -130.716451) (xy 42.824233 -130.745914)
			(xy 42.927947 -130.782957) (xy 43.028718 -130.827388) (xy 43.12602 -130.878975) (xy 43.219346 -130.937447)
			(xy 43.308209 -131.002502) (xy 43.392147 -131.0738) (xy 43.470722 -131.150968) (xy 43.543523 -131.233605)
			(xy 43.610171 -131.321279) (xy 43.67032 -131.413535) (xy 43.723654 -131.50989) (xy 43.769897 -131.609842)
			(xy 43.808807 -131.71287) (xy 43.840181 -131.818438) (xy 43.863856 -131.925994) (xy 43.879708 -132.034978)
			(xy 43.887655 -132.144822) (xy 43.888152 -132.199888) (xy 60.396131 -132.199888) (xy 60.400106 -132.089829)
			(xy 60.412014 -131.980343) (xy 60.43179 -131.872002) (xy 60.459333 -131.765371) (xy 60.494498 -131.661005)
			(xy 60.537102 -131.559448) (xy 60.586923 -131.461231) (xy 60.643702 -131.366864) (xy 60.707141 -131.27684)
			(xy 60.776912 -131.191629) (xy 60.852649 -131.111674) (xy 60.933958 -131.037393) (xy 61.020415 -130.969173)
			(xy 61.111569 -130.907368) (xy 61.206946 -130.852303) (xy 61.306047 -130.804263) (xy 61.408356 -130.763499)
			(xy 61.51334 -130.730224) (xy 61.620451 -130.704611) (xy 61.729131 -130.686794) (xy 61.838814 -130.676865)
			(xy 61.948927 -130.674877) (xy 62.058897 -130.680839) (xy 62.16815 -130.694721) (xy 62.276116 -130.716451)
			(xy 62.382233 -130.745914) (xy 62.485947 -130.782957) (xy 62.586718 -130.827388) (xy 62.68402 -130.878975)
			(xy 62.777346 -130.937447) (xy 62.866209 -131.002502) (xy 62.950147 -131.0738) (xy 63.028722 -131.150968)
			(xy 63.101523 -131.233605) (xy 63.168171 -131.321279) (xy 63.22832 -131.413535) (xy 63.281654 -131.50989)
			(xy 63.327897 -131.609842) (xy 63.366807 -131.71287) (xy 63.398181 -131.818438) (xy 63.421856 -131.925994)
			(xy 63.437708 -132.034978) (xy 63.445655 -132.144822) (xy 63.446152 -132.199888) (xy 63.445655 -132.254954)
			(xy 63.437708 -132.364798) (xy 63.421856 -132.473782) (xy 63.398181 -132.581338) (xy 63.366807 -132.686906)
			(xy 63.327897 -132.789934) (xy 63.281654 -132.889886) (xy 63.22832 -132.986241) (xy 63.168171 -133.078497)
			(xy 63.101523 -133.166171) (xy 63.028722 -133.248808) (xy 62.950147 -133.325976) (xy 62.866209 -133.397274)
			(xy 62.777346 -133.462329) (xy 62.68402 -133.520801) (xy 62.586718 -133.572388) (xy 62.485947 -133.616819)
			(xy 62.382233 -133.653862) (xy 62.276116 -133.683325) (xy 62.16815 -133.705055) (xy 62.058897 -133.718937)
			(xy 61.948927 -133.724899) (xy 61.838814 -133.722911) (xy 61.729131 -133.712982) (xy 61.620451 -133.695165)
			(xy 61.51334 -133.669552) (xy 61.408356 -133.636277) (xy 61.306047 -133.595513) (xy 61.206946 -133.547473)
			(xy 61.111569 -133.492408) (xy 61.020415 -133.430603) (xy 60.933958 -133.362383) (xy 60.852649 -133.288102)
			(xy 60.776912 -133.208147) (xy 60.707141 -133.122936) (xy 60.643702 -133.032912) (xy 60.586923 -132.938545)
			(xy 60.537102 -132.840328) (xy 60.494498 -132.738771) (xy 60.459333 -132.634405) (xy 60.43179 -132.527774)
			(xy 60.412014 -132.419433) (xy 60.400106 -132.309947) (xy 60.396131 -132.199888) (xy 43.888152 -132.199888)
			(xy 43.887655 -132.254954) (xy 43.879708 -132.364798) (xy 43.863856 -132.473782) (xy 43.840181 -132.581338)
			(xy 43.808807 -132.686906) (xy 43.769897 -132.789934) (xy 43.723654 -132.889886) (xy 43.67032 -132.986241)
			(xy 43.610171 -133.078497) (xy 43.543523 -133.166171) (xy 43.470722 -133.248808) (xy 43.392147 -133.325976)
			(xy 43.308209 -133.397274) (xy 43.219346 -133.462329) (xy 43.12602 -133.520801) (xy 43.028718 -133.572388)
			(xy 42.927947 -133.616819) (xy 42.824233 -133.653862) (xy 42.718116 -133.683325) (xy 42.61015 -133.705055)
			(xy 42.500897 -133.718937) (xy 42.390927 -133.724899) (xy 42.280814 -133.722911) (xy 42.171131 -133.712982)
			(xy 42.062451 -133.695165) (xy 41.95534 -133.669552) (xy 41.850356 -133.636277) (xy 41.748047 -133.595513)
			(xy 41.648946 -133.547473) (xy 41.553569 -133.492408) (xy 41.462415 -133.430603) (xy 41.375958 -133.362383)
			(xy 41.294649 -133.288102) (xy 41.218912 -133.208147) (xy 41.149141 -133.122936) (xy 41.085702 -133.032912)
			(xy 41.028923 -132.938545) (xy 40.979102 -132.840328) (xy 40.936498 -132.738771) (xy 40.901333 -132.634405)
			(xy 40.87379 -132.527774) (xy 40.854014 -132.419433) (xy 40.842106 -132.309947) (xy 40.838131 -132.199888)
			(xy 23.720552 -132.199888) (xy 23.720552 -139.7) (xy 41.345876 -139.7) (xy 41.349858 -139.610072)
			(xy 41.361772 -139.520848) (xy 41.381525 -139.433026) (xy 41.408962 -139.347293) (xy 41.443869 -139.264321)
			(xy 41.485973 -139.184758) (xy 41.534943 -139.109228) (xy 41.590398 -139.038322) (xy 41.651902 -138.972594)
			(xy 41.718974 -138.912559) (xy 41.79109 -138.858687) (xy 41.867685 -138.811399) (xy 41.948159 -138.771066)
			(xy 42.031883 -138.738003) (xy 42.118202 -138.712469) (xy 42.20644 -138.694664) (xy 42.295905 -138.684726)
			(xy 42.3859 -138.682735) (xy 42.475717 -138.688705) (xy 42.564656 -138.70259) (xy 42.65202 -138.724281)
			(xy 42.737125 -138.753608) (xy 42.819304 -138.790342) (xy 42.897916 -138.834196) (xy 42.972344 -138.884825)
			(xy 43.042006 -138.941835) (xy 43.106357 -139.004778) (xy 43.164894 -139.073162) (xy 43.217157 -139.146452)
			(xy 43.262739 -139.224074) (xy 43.301282 -139.305421) (xy 43.332485 -139.389856) (xy 43.356103 -139.476718)
			(xy 43.371952 -139.565328) (xy 43.379908 -139.654992) (xy 43.380406 -139.7) (xy 60.903876 -139.7)
			(xy 60.907858 -139.610072) (xy 60.919772 -139.520848) (xy 60.939525 -139.433026) (xy 60.966962 -139.347293)
			(xy 61.001869 -139.264321) (xy 61.043973 -139.184758) (xy 61.092943 -139.109228) (xy 61.148398 -139.038322)
			(xy 61.209902 -138.972594) (xy 61.276974 -138.912559) (xy 61.34909 -138.858687) (xy 61.425685 -138.811399)
			(xy 61.506159 -138.771066) (xy 61.589883 -138.738003) (xy 61.676202 -138.712469) (xy 61.76444 -138.694664)
			(xy 61.853905 -138.684726) (xy 61.9439 -138.682735) (xy 62.033717 -138.688705) (xy 62.122656 -138.70259)
			(xy 62.21002 -138.724281) (xy 62.295125 -138.753608) (xy 62.377304 -138.790342) (xy 62.455916 -138.834196)
			(xy 62.530344 -138.884825) (xy 62.600006 -138.941835) (xy 62.664357 -139.004778) (xy 62.722894 -139.073162)
			(xy 62.775157 -139.146452) (xy 62.820739 -139.224074) (xy 62.859282 -139.305421) (xy 62.890485 -139.389856)
			(xy 62.914103 -139.476718) (xy 62.929952 -139.565328) (xy 62.937908 -139.654992) (xy 62.938406 -139.7)
			(xy 62.937908 -139.745008) (xy 62.929952 -139.834672) (xy 62.914103 -139.923282) (xy 62.890485 -140.010144)
			(xy 62.859282 -140.094579) (xy 62.820739 -140.175926) (xy 62.775157 -140.253548) (xy 62.722894 -140.326838)
			(xy 62.664357 -140.395222) (xy 62.600006 -140.458165) (xy 62.530344 -140.515175) (xy 62.455916 -140.565804)
			(xy 62.377304 -140.609658) (xy 62.295125 -140.646392) (xy 62.21002 -140.675719) (xy 62.122656 -140.69741)
			(xy 62.033717 -140.711295) (xy 61.9439 -140.717265) (xy 61.853905 -140.715274) (xy 61.76444 -140.705336)
			(xy 61.676202 -140.687531) (xy 61.589883 -140.661997) (xy 61.506159 -140.628934) (xy 61.425685 -140.588601)
			(xy 61.34909 -140.541313) (xy 61.276974 -140.487441) (xy 61.209902 -140.427406) (xy 61.148398 -140.361678)
			(xy 61.092943 -140.290772) (xy 61.043973 -140.215242) (xy 61.001869 -140.135679) (xy 60.966962 -140.052707)
			(xy 60.939525 -139.966974) (xy 60.919772 -139.879152) (xy 60.907858 -139.789928) (xy 60.903876 -139.7)
			(xy 43.380406 -139.7) (xy 43.379908 -139.745008) (xy 43.371952 -139.834672) (xy 43.356103 -139.923282)
			(xy 43.332485 -140.010144) (xy 43.301282 -140.094579) (xy 43.262739 -140.175926) (xy 43.217157 -140.253548)
			(xy 43.164894 -140.326838) (xy 43.106357 -140.395222) (xy 43.042006 -140.458165) (xy 42.972344 -140.515175)
			(xy 42.897916 -140.565804) (xy 42.819304 -140.609658) (xy 42.737125 -140.646392) (xy 42.65202 -140.675719)
			(xy 42.564656 -140.69741) (xy 42.475717 -140.711295) (xy 42.3859 -140.717265) (xy 42.295905 -140.715274)
			(xy 42.20644 -140.705336) (xy 42.118202 -140.687531) (xy 42.031883 -140.661997) (xy 41.948159 -140.628934)
			(xy 41.867685 -140.588601) (xy 41.79109 -140.541313) (xy 41.718974 -140.487441) (xy 41.651902 -140.427406)
			(xy 41.590398 -140.361678) (xy 41.534943 -140.290772) (xy 41.485973 -140.215242) (xy 41.443869 -140.135679)
			(xy 41.408962 -140.052707) (xy 41.381525 -139.966974) (xy 41.361772 -139.879152) (xy 41.349858 -139.789928)
			(xy 41.345876 -139.7) (xy 23.720552 -139.7) (xy 23.720552 -147.500086) (xy 74.864468 -147.500086)
			(xy 74.864468 -142.500096) (xy 74.864963 -142.399255) (xy 74.872881 -142.197728) (xy 74.888705 -141.996668)
			(xy 74.91241 -141.796384) (xy 74.94396 -141.597185) (xy 74.983306 -141.399378) (xy 75.030388 -141.203269)
			(xy 75.085133 -141.009159) (xy 75.147456 -140.817348) (xy 75.217261 -140.628131) (xy 75.294442 -140.441802)
			(xy 75.378878 -140.258645) (xy 75.47044 -140.078945) (xy 75.568986 -139.902979) (xy 75.674364 -139.731016)
			(xy 75.786413 -139.563324) (xy 75.904959 -139.40016) (xy 76.029819 -139.241775) (xy 76.160801 -139.088415)
			(xy 76.297703 -138.940315) (xy 76.440313 -138.797705) (xy 76.588413 -138.660803) (xy 76.741773 -138.529821)
			(xy 76.900158 -138.404961) (xy 77.063322 -138.286415) (xy 77.231014 -138.174366) (xy 77.402977 -138.068988)
			(xy 77.578943 -137.970442) (xy 77.758643 -137.87888) (xy 77.9418 -137.794444) (xy 78.128129 -137.717263)
			(xy 78.317346 -137.647458) (xy 78.509157 -137.585135) (xy 78.703267 -137.53039) (xy 78.899376 -137.483308)
			(xy 79.097183 -137.443962) (xy 79.296382 -137.412412) (xy 79.496666 -137.388707) (xy 79.697726 -137.372883)
			(xy 79.899253 -137.364965) (xy 80.100935 -137.364965) (xy 80.302462 -137.372883) (xy 80.503522 -137.388707)
			(xy 80.703806 -137.412412) (xy 80.903005 -137.443962) (xy 81.100812 -137.483308) (xy 81.296921 -137.53039)
			(xy 81.491031 -137.585135) (xy 81.682842 -137.647458) (xy 81.872059 -137.717263) (xy 82.058388 -137.794444)
			(xy 82.241545 -137.87888) (xy 82.421245 -137.970442) (xy 82.597211 -138.068988) (xy 82.769174 -138.174366)
			(xy 82.936866 -138.286415) (xy 83.10003 -138.404961) (xy 83.258415 -138.529821) (xy 83.411775 -138.660803)
			(xy 83.559875 -138.797705) (xy 83.702485 -138.940315) (xy 83.839387 -139.088415) (xy 83.970369 -139.241775)
			(xy 84.095229 -139.40016) (xy 84.213775 -139.563324) (xy 84.325824 -139.731016) (xy 84.431202 -139.902979)
			(xy 84.529748 -140.078945) (xy 84.62131 -140.258645) (xy 84.705746 -140.441802) (xy 84.782927 -140.628131)
			(xy 84.852732 -140.817348) (xy 84.915055 -141.009159) (xy 84.9698 -141.203269) (xy 85.016882 -141.399378)
			(xy 85.056228 -141.597185) (xy 85.087778 -141.796384) (xy 85.111483 -141.996668) (xy 85.127307 -142.197728)
			(xy 85.135225 -142.399255) (xy 85.13572 -142.500096) (xy 85.13572 -147.500086) (xy 85.135225 -147.600927)
			(xy 85.127307 -147.802454) (xy 85.111483 -148.003514) (xy 85.087778 -148.203798) (xy 85.056228 -148.402997)
			(xy 85.016882 -148.600804) (xy 84.9698 -148.796913) (xy 84.915055 -148.991023) (xy 84.852732 -149.182834)
			(xy 84.782927 -149.372051) (xy 84.705746 -149.55838) (xy 84.62131 -149.741537) (xy 84.529748 -149.921237)
			(xy 84.431202 -150.097203) (xy 84.325824 -150.269166) (xy 84.213775 -150.436858) (xy 84.095229 -150.600022)
			(xy 83.970369 -150.758407) (xy 83.839387 -150.911767) (xy 83.702485 -151.059867) (xy 83.559875 -151.202477)
			(xy 83.411775 -151.339379) (xy 83.258415 -151.470361) (xy 83.10003 -151.595221) (xy 82.936866 -151.713767)
			(xy 82.769174 -151.825816) (xy 82.597211 -151.931194) (xy 82.421245 -152.02974) (xy 82.241545 -152.121302)
			(xy 82.058388 -152.205738) (xy 81.872059 -152.282919) (xy 81.682842 -152.352724) (xy 81.491031 -152.415047)
			(xy 81.296921 -152.469792) (xy 81.100812 -152.516874) (xy 80.903005 -152.55622) (xy 80.703806 -152.58777)
			(xy 80.503522 -152.611475) (xy 80.302462 -152.627299) (xy 80.100935 -152.635217) (xy 79.899253 -152.635217)
			(xy 79.697726 -152.627299) (xy 79.496666 -152.611475) (xy 79.296382 -152.58777) (xy 79.097183 -152.55622)
			(xy 78.899376 -152.516874) (xy 78.703267 -152.469792) (xy 78.509157 -152.415047) (xy 78.317346 -152.352724)
			(xy 78.128129 -152.282919) (xy 77.9418 -152.205738) (xy 77.758643 -152.121302) (xy 77.578943 -152.02974)
			(xy 77.402977 -151.931194) (xy 77.231014 -151.825816) (xy 77.063322 -151.713767) (xy 76.900158 -151.595221)
			(xy 76.741773 -151.470361) (xy 76.588413 -151.339379) (xy 76.440313 -151.202477) (xy 76.297703 -151.059867)
			(xy 76.160801 -150.911767) (xy 76.029819 -150.758407) (xy 75.904959 -150.600022) (xy 75.786413 -150.436858)
			(xy 75.674364 -150.269166) (xy 75.568986 -150.097203) (xy 75.47044 -149.921237) (xy 75.378878 -149.741537)
			(xy 75.294442 -149.55838) (xy 75.217261 -149.372051) (xy 75.147456 -149.182834) (xy 75.085133 -148.991023)
			(xy 75.030388 -148.796913) (xy 74.983306 -148.600804) (xy 74.94396 -148.402997) (xy 74.91241 -148.203798)
			(xy 74.888705 -148.003514) (xy 74.872881 -147.802454) (xy 74.864963 -147.600927) (xy 74.864468 -147.500086)
			(xy 23.720552 -147.500086) (xy 23.720552 -156.57703) (xy 23.720982 -156.587097) (xy 23.72871 -156.605688)
			(xy 23.735538 -156.613098) (xy 23.839424 -156.716984) (xy 23.870158 -156.722572) (xy 23.884636 -156.716222)
			(xy 23.927326 -156.697947) (xy 24.015676 -156.669341) (xy 24.106524 -156.650085) (xy 24.198883 -156.64039)
			(xy 24.245316 -156.639768) (xy 24.24557 -156.639768) (xy 24.288357 -156.64028) (xy 24.373534 -156.648504)
			(xy 24.457528 -156.664868) (xy 24.539562 -156.689223) (xy 24.618879 -156.721341) (xy 24.694745 -156.760928)
			(xy 24.76646 -156.807616) (xy 24.833359 -156.860975) (xy 24.894827 -156.920511) (xy 24.950293 -156.985675)
			(xy 24.999246 -157.055863) (xy 25.041233 -157.130427) (xy 25.075866 -157.208679) (xy 25.089866 -157.249114)
			(xy 25.094946 -157.264608) (xy 25.121616 -157.283912) (xy 26.000456 -157.283912) (xy 26.109441 -157.284408)
			(xy 26.327267 -157.292313) (xy 26.544663 -157.308104) (xy 26.761345 -157.33176) (xy 26.977028 -157.363249)
			(xy 27.191428 -157.402531) (xy 27.404265 -157.449554) (xy 27.615259 -157.504256) (xy 27.824132 -157.566566)
			(xy 28.030612 -157.636401) (xy 28.234426 -157.713669) (xy 28.435307 -157.798271) (xy 28.53436 -157.843728)
			(xy 28.55595 -157.848554) (xy 28.589986 -157.835346) (xy 28.62069 -157.807856) (xy 28.686361 -157.758054)
			(xy 28.75636 -157.714545) (xy 28.830086 -157.677702) (xy 28.906906 -157.647841) (xy 28.986159 -157.625219)
			(xy 29.067167 -157.61003) (xy 29.149232 -157.602405) (xy 29.190442 -157.60192) (xy 29.231543 -157.602397)
			(xy 29.313393 -157.609985) (xy 29.394195 -157.625093) (xy 29.473257 -157.647592) (xy 29.549907 -157.67729)
			(xy 29.623489 -157.713934) (xy 29.693376 -157.75721) (xy 29.758972 -157.80675) (xy 29.819718 -157.862132)
			(xy 29.875094 -157.922881) (xy 29.924629 -157.988482) (xy 29.9679 -158.058372) (xy 30.004538 -158.131958)
			(xy 30.03423 -158.208609) (xy 30.056723 -158.287674) (xy 30.071825 -158.368476) (xy 30.079407 -158.450327)
			(xy 30.07995 -158.491428) (xy 30.07954 -158.529447) (xy 30.07303 -158.605205) (xy 30.060077 -158.680131)
			(xy 30.040775 -158.753678) (xy 30.028388 -158.789624) (xy 30.02534 -158.806642) (xy 30.042104 -158.844234)
			(xy 30.124801 -158.919959) (xy 30.285164 -159.076725) (xy 30.439573 -159.239358) (xy 30.587815 -159.407631)
			(xy 30.729684 -159.581311) (xy 30.864983 -159.760157) (xy 30.993524 -159.94392) (xy 31.115128 -160.132345)
			(xy 31.229627 -160.325171) (xy 31.336861 -160.522129) (xy 31.436681 -160.722946) (xy 31.52895 -160.927343)
			(xy 31.613538 -161.135036) (xy 31.690328 -161.345737) (xy 31.759214 -161.559153) (xy 31.790132 -161.666936)
			(xy 31.832804 -161.703766) (xy 31.875396 -161.709498) (xy 31.959303 -161.728113) (xy 32.041022 -161.754735)
			(xy 32.119793 -161.789114) (xy 32.194881 -161.830931) (xy 32.265585 -161.879796) (xy 32.331247 -161.935252)
			(xy 32.391253 -161.996782) (xy 32.445045 -162.063814) (xy 32.492121 -162.135722) (xy 32.532041 -162.211834)
			(xy 32.564434 -162.291443) (xy 32.588998 -162.373804) (xy 32.605503 -162.458151) (xy 32.613796 -162.543697)
			(xy 32.614362 -162.58667) (xy 32.613888 -162.627686) (xy 32.606328 -162.709368) (xy 32.591279 -162.790007)
			(xy 32.568869 -162.868918) (xy 32.539289 -162.94543) (xy 32.502788 -163.018894) (xy 32.459679 -163.088684)
			(xy 32.410326 -163.154208) (xy 32.355149 -163.21491) (xy 32.294618 -163.270273) (xy 32.229246 -163.319828)
			(xy 32.159589 -163.363152) (xy 32.086238 -163.399879) (xy 32.048196 -163.415218) (xy 32.038888 -163.419353)
			(xy 32.024309 -163.43355) (xy 32.016372 -163.452288) (xy 32.015938 -163.462462) (xy 32.015938 -166.649908)
			(xy 32.01644 -166.739312) (xy 32.024462 -166.917941) (xy 32.04049 -167.09603) (xy 32.064492 -167.27322)
			(xy 32.096419 -167.449155) (xy 32.136208 -167.623481) (xy 32.183778 -167.795846) (xy 32.239032 -167.965903)
			(xy 32.301861 -168.13331) (xy 32.372137 -168.297729) (xy 32.449719 -168.45883) (xy 32.534451 -168.616289)
			(xy 32.626162 -168.769787) (xy 32.724667 -168.919016) (xy 32.829768 -169.063675) (xy 32.941253 -169.203473)
			(xy 33.058898 -169.338129) (xy 33.182466 -169.467371) (xy 33.311708 -169.590939) (xy 33.446364 -169.708584)
			(xy 33.586162 -169.82007) (xy 33.730821 -169.925171) (xy 33.88005 -170.023676) (xy 34.033548 -170.115387)
			(xy 34.191006 -170.200119) (xy 34.352107 -170.277701) (xy 34.516526 -170.347977) (xy 34.683933 -170.410806)
			(xy 34.85399 -170.466061) (xy 35.026355 -170.513631) (xy 35.200681 -170.55342) (xy 35.376616 -170.585347)
			(xy 35.553806 -170.60935) (xy 35.731895 -170.625378) (xy 35.910524 -170.6334) (xy 35.999928 -170.633898)
		)
		(stroke
			(width 0)
			(type solid)
		)
		(fill yes)
		(layer "In5.Cu")
		(net "P52V_HS2")
	)
	(gr_poly
		(pts
			(xy 116.451888 -101.984048) (xy 116.461958 -101.983626) (xy 116.480561 -101.975908) (xy 116.487956 -101.969062)
			(xy 116.507568 -101.949938) (xy 116.551293 -101.916943) (xy 116.599291 -101.890547) (xy 116.650573 -101.871294)
			(xy 116.704084 -101.859582) (xy 116.75872 -101.85565) (xy 116.813356 -101.859582) (xy 116.866867 -101.871294)
			(xy 116.918149 -101.890547) (xy 116.966147 -101.916943) (xy 117.009872 -101.949938) (xy 117.029484 -101.969062)
			(xy 117.036885 -101.975899) (xy 117.055484 -101.983609) (xy 117.065552 -101.984048) (xy 121.531888 -101.984048)
			(xy 121.541958 -101.983626) (xy 121.560561 -101.975908) (xy 121.567956 -101.969062) (xy 121.587568 -101.949938)
			(xy 121.631293 -101.916943) (xy 121.679291 -101.890547) (xy 121.730573 -101.871294) (xy 121.784084 -101.859582)
			(xy 121.83872 -101.85565) (xy 121.893356 -101.859582) (xy 121.946867 -101.871294) (xy 121.998149 -101.890547)
			(xy 122.046147 -101.916943) (xy 122.089872 -101.949938) (xy 122.109484 -101.969062) (xy 122.116885 -101.975899)
			(xy 122.135484 -101.983609) (xy 122.145552 -101.984048) (xy 126.611888 -101.984048) (xy 126.621958 -101.983626)
			(xy 126.640561 -101.975908) (xy 126.647956 -101.969062) (xy 126.667568 -101.949938) (xy 126.711293 -101.916943)
			(xy 126.759291 -101.890547) (xy 126.810573 -101.871294) (xy 126.864084 -101.859582) (xy 126.91872 -101.85565)
			(xy 126.973356 -101.859582) (xy 127.026867 -101.871294) (xy 127.078149 -101.890547) (xy 127.126147 -101.916943)
			(xy 127.169872 -101.949938) (xy 127.189484 -101.969062) (xy 127.196885 -101.975899) (xy 127.215484 -101.983609)
			(xy 127.225552 -101.984048) (xy 131.691888 -101.984048) (xy 131.701958 -101.983626) (xy 131.720561 -101.975908)
			(xy 131.727956 -101.969062) (xy 131.747568 -101.949938) (xy 131.791293 -101.916943) (xy 131.839291 -101.890547)
			(xy 131.890573 -101.871294) (xy 131.944084 -101.859582) (xy 131.99872 -101.85565) (xy 132.053356 -101.859582)
			(xy 132.106867 -101.871294) (xy 132.158149 -101.890547) (xy 132.206147 -101.916943) (xy 132.249872 -101.949938)
			(xy 132.269484 -101.969062) (xy 132.276885 -101.975899) (xy 132.295484 -101.983609) (xy 132.305552 -101.984048)
			(xy 136.771888 -101.984048) (xy 136.781958 -101.983626) (xy 136.800561 -101.975908) (xy 136.807956 -101.969062)
			(xy 136.827568 -101.949938) (xy 136.871293 -101.916943) (xy 136.919291 -101.890547) (xy 136.970573 -101.871294)
			(xy 137.024084 -101.859582) (xy 137.07872 -101.85565) (xy 137.133356 -101.859582) (xy 137.186867 -101.871294)
			(xy 137.238149 -101.890547) (xy 137.286147 -101.916943) (xy 137.329872 -101.949938) (xy 137.349484 -101.969062)
			(xy 137.356885 -101.975899) (xy 137.375484 -101.983609) (xy 137.385552 -101.984048) (xy 141.851888 -101.984048)
			(xy 141.861958 -101.983626) (xy 141.880561 -101.975908) (xy 141.887956 -101.969062) (xy 141.907568 -101.949938)
			(xy 141.951293 -101.916943) (xy 141.999291 -101.890547) (xy 142.050573 -101.871294) (xy 142.104084 -101.859582)
			(xy 142.15872 -101.85565) (xy 142.213356 -101.859582) (xy 142.266867 -101.871294) (xy 142.318149 -101.890547)
			(xy 142.366147 -101.916943) (xy 142.409872 -101.949938) (xy 142.429484 -101.969062) (xy 142.436885 -101.975899)
			(xy 142.455484 -101.983609) (xy 142.465552 -101.984048) (xy 146.931888 -101.984048) (xy 146.941958 -101.983626)
			(xy 146.960561 -101.975908) (xy 146.967956 -101.969062) (xy 146.987568 -101.949938) (xy 147.031293 -101.916943)
			(xy 147.079291 -101.890547) (xy 147.130573 -101.871294) (xy 147.184084 -101.859582) (xy 147.23872 -101.85565)
			(xy 147.293356 -101.859582) (xy 147.346867 -101.871294) (xy 147.398149 -101.890547) (xy 147.446147 -101.916943)
			(xy 147.489872 -101.949938) (xy 147.509484 -101.969062) (xy 147.516885 -101.975899) (xy 147.535484 -101.983609)
			(xy 147.545552 -101.984048) (xy 152.011888 -101.984048) (xy 152.021958 -101.983626) (xy 152.040561 -101.975908)
			(xy 152.047956 -101.969062) (xy 152.067568 -101.949938) (xy 152.111293 -101.916943) (xy 152.159291 -101.890547)
			(xy 152.210573 -101.871294) (xy 152.264084 -101.859582) (xy 152.31872 -101.85565) (xy 152.373356 -101.859582)
			(xy 152.426867 -101.871294) (xy 152.478149 -101.890547) (xy 152.526147 -101.916943) (xy 152.569872 -101.949938)
			(xy 152.589484 -101.969062) (xy 152.596885 -101.975899) (xy 152.615484 -101.983609) (xy 152.625552 -101.984048)
			(xy 157.091888 -101.984048) (xy 157.101958 -101.983626) (xy 157.120561 -101.975908) (xy 157.127956 -101.969062)
			(xy 157.147568 -101.949938) (xy 157.191293 -101.916943) (xy 157.239291 -101.890547) (xy 157.290573 -101.871294)
			(xy 157.344084 -101.859582) (xy 157.39872 -101.85565) (xy 157.453356 -101.859582) (xy 157.506867 -101.871294)
			(xy 157.558149 -101.890547) (xy 157.606147 -101.916943) (xy 157.649872 -101.949938) (xy 157.669484 -101.969062)
			(xy 157.676885 -101.975899) (xy 157.695484 -101.983609) (xy 157.705552 -101.984048) (xy 162.171888 -101.984048)
			(xy 162.181958 -101.983626) (xy 162.200561 -101.975908) (xy 162.207956 -101.969062) (xy 162.227568 -101.949938)
			(xy 162.271293 -101.916943) (xy 162.319291 -101.890547) (xy 162.370573 -101.871294) (xy 162.424084 -101.859582)
			(xy 162.47872 -101.85565) (xy 162.533356 -101.859582) (xy 162.586867 -101.871294) (xy 162.638149 -101.890547)
			(xy 162.686147 -101.916943) (xy 162.729872 -101.949938) (xy 162.749484 -101.969062) (xy 162.756885 -101.975899)
			(xy 162.775484 -101.983609) (xy 162.785552 -101.984048) (xy 167.251888 -101.984048) (xy 167.261958 -101.983626)
			(xy 167.280561 -101.975908) (xy 167.287956 -101.969062) (xy 167.307568 -101.949938) (xy 167.351293 -101.916943)
			(xy 167.399291 -101.890547) (xy 167.450573 -101.871294) (xy 167.504084 -101.859582) (xy 167.55872 -101.85565)
			(xy 167.613356 -101.859582) (xy 167.666867 -101.871294) (xy 167.718149 -101.890547) (xy 167.766147 -101.916943)
			(xy 167.809872 -101.949938) (xy 167.829484 -101.969062) (xy 167.836885 -101.975899) (xy 167.855484 -101.983609)
			(xy 167.865552 -101.984048) (xy 172.331888 -101.984048) (xy 172.341958 -101.983626) (xy 172.360561 -101.975908)
			(xy 172.367956 -101.969062) (xy 172.387568 -101.949938) (xy 172.431293 -101.916943) (xy 172.479291 -101.890547)
			(xy 172.530573 -101.871294) (xy 172.584084 -101.859582) (xy 172.63872 -101.85565) (xy 172.693356 -101.859582)
			(xy 172.746867 -101.871294) (xy 172.798149 -101.890547) (xy 172.846147 -101.916943) (xy 172.889872 -101.949938)
			(xy 172.909484 -101.969062) (xy 172.916885 -101.975899) (xy 172.935484 -101.983609) (xy 172.945552 -101.984048)
			(xy 177.411888 -101.984048) (xy 177.421958 -101.983626) (xy 177.440561 -101.975908) (xy 177.447956 -101.969062)
			(xy 177.467568 -101.949938) (xy 177.511293 -101.916943) (xy 177.559291 -101.890547) (xy 177.610573 -101.871294)
			(xy 177.664084 -101.859582) (xy 177.71872 -101.85565) (xy 177.773356 -101.859582) (xy 177.826867 -101.871294)
			(xy 177.878149 -101.890547) (xy 177.926147 -101.916943) (xy 177.969872 -101.949938) (xy 177.989484 -101.969062)
			(xy 177.996885 -101.975899) (xy 178.015484 -101.983609) (xy 178.025552 -101.984048) (xy 182.491888 -101.984048)
			(xy 182.501958 -101.983626) (xy 182.520561 -101.975908) (xy 182.527956 -101.969062) (xy 182.547568 -101.949938)
			(xy 182.591293 -101.916943) (xy 182.639291 -101.890547) (xy 182.690573 -101.871294) (xy 182.744084 -101.859582)
			(xy 182.79872 -101.85565) (xy 182.853356 -101.859582) (xy 182.906867 -101.871294) (xy 182.958149 -101.890547)
			(xy 183.006147 -101.916943) (xy 183.049872 -101.949938) (xy 183.069484 -101.969062) (xy 183.076885 -101.975899)
			(xy 183.095484 -101.983609) (xy 183.105552 -101.984048) (xy 187.571888 -101.984048) (xy 187.581958 -101.983626)
			(xy 187.600561 -101.975908) (xy 187.607956 -101.969062) (xy 187.627568 -101.949938) (xy 187.671293 -101.916943)
			(xy 187.719291 -101.890547) (xy 187.770573 -101.871294) (xy 187.824084 -101.859582) (xy 187.87872 -101.85565)
			(xy 187.933356 -101.859582) (xy 187.986867 -101.871294) (xy 188.038149 -101.890547) (xy 188.086147 -101.916943)
			(xy 188.129872 -101.949938) (xy 188.149484 -101.969062) (xy 188.156885 -101.975899) (xy 188.175484 -101.983609)
			(xy 188.185552 -101.984048) (xy 192.651888 -101.984048) (xy 192.661958 -101.983626) (xy 192.680561 -101.975908)
			(xy 192.687956 -101.969062) (xy 192.707568 -101.949938) (xy 192.751293 -101.916943) (xy 192.799291 -101.890547)
			(xy 192.850573 -101.871294) (xy 192.904084 -101.859582) (xy 192.95872 -101.85565) (xy 193.013356 -101.859582)
			(xy 193.066867 -101.871294) (xy 193.118149 -101.890547) (xy 193.166147 -101.916943) (xy 193.209872 -101.949938)
			(xy 193.229484 -101.969062) (xy 193.236885 -101.975899) (xy 193.255484 -101.983609) (xy 193.265552 -101.984048)
			(xy 197.731888 -101.984048) (xy 197.741958 -101.983626) (xy 197.760561 -101.975908) (xy 197.767956 -101.969062)
			(xy 197.787568 -101.949938) (xy 197.831293 -101.916943) (xy 197.879291 -101.890547) (xy 197.930573 -101.871294)
			(xy 197.984084 -101.859582) (xy 198.03872 -101.85565) (xy 198.093356 -101.859582) (xy 198.146867 -101.871294)
			(xy 198.198149 -101.890547) (xy 198.246147 -101.916943) (xy 198.289872 -101.949938) (xy 198.309484 -101.969062)
			(xy 198.316885 -101.975899) (xy 198.335484 -101.983609) (xy 198.345552 -101.984048) (xy 202.811888 -101.984048)
			(xy 202.821958 -101.983626) (xy 202.840561 -101.975908) (xy 202.847956 -101.969062) (xy 202.867568 -101.949938)
			(xy 202.911293 -101.916943) (xy 202.959291 -101.890547) (xy 203.010573 -101.871294) (xy 203.064084 -101.859582)
			(xy 203.11872 -101.85565) (xy 203.173356 -101.859582) (xy 203.226867 -101.871294) (xy 203.278149 -101.890547)
			(xy 203.326147 -101.916943) (xy 203.369872 -101.949938) (xy 203.389484 -101.969062) (xy 203.396885 -101.975899)
			(xy 203.415484 -101.983609) (xy 203.425552 -101.984048) (xy 207.891888 -101.984048) (xy 207.901958 -101.983626)
			(xy 207.920561 -101.975908) (xy 207.927956 -101.969062) (xy 207.947568 -101.949938) (xy 207.991293 -101.916943)
			(xy 208.039291 -101.890547) (xy 208.090573 -101.871294) (xy 208.144084 -101.859582) (xy 208.19872 -101.85565)
			(xy 208.253356 -101.859582) (xy 208.306867 -101.871294) (xy 208.358149 -101.890547) (xy 208.406147 -101.916943)
			(xy 208.449872 -101.949938) (xy 208.469484 -101.969062) (xy 208.476885 -101.975899) (xy 208.495484 -101.983609)
			(xy 208.505552 -101.984048) (xy 212.971888 -101.984048) (xy 212.981958 -101.983626) (xy 213.000561 -101.975908)
			(xy 213.007956 -101.969062) (xy 213.027568 -101.949938) (xy 213.071293 -101.916943) (xy 213.119291 -101.890547)
			(xy 213.170573 -101.871294) (xy 213.224084 -101.859582) (xy 213.27872 -101.85565) (xy 213.333356 -101.859582)
			(xy 213.386867 -101.871294) (xy 213.438149 -101.890547) (xy 213.486147 -101.916943) (xy 213.529872 -101.949938)
			(xy 213.549484 -101.969062) (xy 213.556885 -101.975899) (xy 213.575484 -101.983609) (xy 213.585552 -101.984048)
			(xy 218.051888 -101.984048) (xy 218.061958 -101.983626) (xy 218.080561 -101.975908) (xy 218.087956 -101.969062)
			(xy 218.107568 -101.949938) (xy 218.151293 -101.916943) (xy 218.199291 -101.890547) (xy 218.250573 -101.871294)
			(xy 218.304084 -101.859582) (xy 218.35872 -101.85565) (xy 218.413356 -101.859582) (xy 218.466867 -101.871294)
			(xy 218.518149 -101.890547) (xy 218.566147 -101.916943) (xy 218.609872 -101.949938) (xy 218.629484 -101.969062)
			(xy 218.636885 -101.975899) (xy 218.655484 -101.983609) (xy 218.665552 -101.984048) (xy 223.131888 -101.984048)
			(xy 223.141958 -101.983626) (xy 223.160561 -101.975908) (xy 223.167956 -101.969062) (xy 223.187568 -101.949938)
			(xy 223.231293 -101.916943) (xy 223.279291 -101.890547) (xy 223.330573 -101.871294) (xy 223.384084 -101.859582)
			(xy 223.43872 -101.85565) (xy 223.493356 -101.859582) (xy 223.546867 -101.871294) (xy 223.598149 -101.890547)
			(xy 223.646147 -101.916943) (xy 223.689872 -101.949938) (xy 223.709484 -101.969062) (xy 223.716885 -101.975899)
			(xy 223.735484 -101.983609) (xy 223.745552 -101.984048) (xy 228.211888 -101.984048) (xy 228.221958 -101.983626)
			(xy 228.240561 -101.975908) (xy 228.247956 -101.969062) (xy 228.267568 -101.949938) (xy 228.311293 -101.916943)
			(xy 228.359291 -101.890547) (xy 228.410573 -101.871294) (xy 228.464084 -101.859582) (xy 228.51872 -101.85565)
			(xy 228.573356 -101.859582) (xy 228.626867 -101.871294) (xy 228.678149 -101.890547) (xy 228.726147 -101.916943)
			(xy 228.769872 -101.949938) (xy 228.789484 -101.969062) (xy 228.796885 -101.975899) (xy 228.815484 -101.983609)
			(xy 228.825552 -101.984048) (xy 233.291888 -101.984048) (xy 233.301958 -101.983626) (xy 233.320561 -101.975908)
			(xy 233.327956 -101.969062) (xy 233.347568 -101.949938) (xy 233.391293 -101.916943) (xy 233.439291 -101.890547)
			(xy 233.490573 -101.871294) (xy 233.544084 -101.859582) (xy 233.59872 -101.85565) (xy 233.653356 -101.859582)
			(xy 233.706867 -101.871294) (xy 233.758149 -101.890547) (xy 233.806147 -101.916943) (xy 233.849872 -101.949938)
			(xy 233.869484 -101.969062) (xy 233.876885 -101.975899) (xy 233.895484 -101.983609) (xy 233.905552 -101.984048)
			(xy 238.371888 -101.984048) (xy 238.381958 -101.983626) (xy 238.400561 -101.975908) (xy 238.407956 -101.969062)
			(xy 238.427568 -101.949938) (xy 238.471293 -101.916943) (xy 238.519291 -101.890547) (xy 238.570573 -101.871294)
			(xy 238.624084 -101.859582) (xy 238.67872 -101.85565) (xy 238.733356 -101.859582) (xy 238.786867 -101.871294)
			(xy 238.838149 -101.890547) (xy 238.886147 -101.916943) (xy 238.929872 -101.949938) (xy 238.949484 -101.969062)
			(xy 238.956885 -101.975899) (xy 238.975484 -101.983609) (xy 238.985552 -101.984048) (xy 243.451888 -101.984048)
			(xy 243.461958 -101.983626) (xy 243.480561 -101.975908) (xy 243.487956 -101.969062) (xy 243.507568 -101.949938)
			(xy 243.551293 -101.916943) (xy 243.599291 -101.890547) (xy 243.650573 -101.871294) (xy 243.704084 -101.859582)
			(xy 243.75872 -101.85565) (xy 243.813356 -101.859582) (xy 243.866867 -101.871294) (xy 243.918149 -101.890547)
			(xy 243.966147 -101.916943) (xy 244.009872 -101.949938) (xy 244.029484 -101.969062) (xy 244.036885 -101.975899)
			(xy 244.055484 -101.983609) (xy 244.065552 -101.984048) (xy 248.531888 -101.984048) (xy 248.541958 -101.983626)
			(xy 248.560561 -101.975908) (xy 248.567956 -101.969062) (xy 248.587568 -101.949938) (xy 248.631293 -101.916943)
			(xy 248.679291 -101.890547) (xy 248.730573 -101.871294) (xy 248.784084 -101.859582) (xy 248.83872 -101.85565)
			(xy 248.893356 -101.859582) (xy 248.946867 -101.871294) (xy 248.998149 -101.890547) (xy 249.046147 -101.916943)
			(xy 249.089872 -101.949938) (xy 249.109484 -101.969062) (xy 249.116885 -101.975899) (xy 249.135484 -101.983609)
			(xy 249.145552 -101.984048) (xy 253.611888 -101.984048) (xy 253.621958 -101.983626) (xy 253.640561 -101.975908)
			(xy 253.647956 -101.969062) (xy 253.667568 -101.949938) (xy 253.711293 -101.916943) (xy 253.759291 -101.890547)
			(xy 253.810573 -101.871294) (xy 253.864084 -101.859582) (xy 253.91872 -101.85565) (xy 253.973356 -101.859582)
			(xy 254.026867 -101.871294) (xy 254.078149 -101.890547) (xy 254.126147 -101.916943) (xy 254.169872 -101.949938)
			(xy 254.189484 -101.969062) (xy 254.196885 -101.975899) (xy 254.215484 -101.983609) (xy 254.225552 -101.984048)
			(xy 258.691888 -101.984048) (xy 258.701958 -101.983626) (xy 258.720561 -101.975908) (xy 258.727956 -101.969062)
			(xy 258.747568 -101.949938) (xy 258.791293 -101.916943) (xy 258.839291 -101.890547) (xy 258.890573 -101.871294)
			(xy 258.944084 -101.859582) (xy 258.99872 -101.85565) (xy 259.053356 -101.859582) (xy 259.106867 -101.871294)
			(xy 259.158149 -101.890547) (xy 259.206147 -101.916943) (xy 259.249872 -101.949938) (xy 259.269484 -101.969062)
			(xy 259.276885 -101.975899) (xy 259.295484 -101.983609) (xy 259.305552 -101.984048) (xy 263.771888 -101.984048)
			(xy 263.781958 -101.983626) (xy 263.800561 -101.975908) (xy 263.807956 -101.969062) (xy 263.827568 -101.949938)
			(xy 263.871293 -101.916943) (xy 263.919291 -101.890547) (xy 263.970573 -101.871294) (xy 264.024084 -101.859582)
			(xy 264.07872 -101.85565) (xy 264.133356 -101.859582) (xy 264.186867 -101.871294) (xy 264.238149 -101.890547)
			(xy 264.286147 -101.916943) (xy 264.329872 -101.949938) (xy 264.349484 -101.969062) (xy 264.356885 -101.975899)
			(xy 264.375484 -101.983609) (xy 264.385552 -101.984048) (xy 268.851888 -101.984048) (xy 268.861958 -101.983626)
			(xy 268.880561 -101.975908) (xy 268.887956 -101.969062) (xy 268.907568 -101.949938) (xy 268.951293 -101.916943)
			(xy 268.999291 -101.890547) (xy 269.050573 -101.871294) (xy 269.104084 -101.859582) (xy 269.15872 -101.85565)
			(xy 269.213356 -101.859582) (xy 269.266867 -101.871294) (xy 269.318149 -101.890547) (xy 269.366147 -101.916943)
			(xy 269.409872 -101.949938) (xy 269.429484 -101.969062) (xy 269.436885 -101.975899) (xy 269.455484 -101.983609)
			(xy 269.465552 -101.984048) (xy 273.931888 -101.984048) (xy 273.941958 -101.983626) (xy 273.960561 -101.975908)
			(xy 273.967956 -101.969062) (xy 273.987568 -101.949938) (xy 274.031293 -101.916943) (xy 274.079291 -101.890547)
			(xy 274.130573 -101.871294) (xy 274.184084 -101.859582) (xy 274.23872 -101.85565) (xy 274.293356 -101.859582)
			(xy 274.346867 -101.871294) (xy 274.398149 -101.890547) (xy 274.446147 -101.916943) (xy 274.489872 -101.949938)
			(xy 274.509484 -101.969062) (xy 274.516885 -101.975899) (xy 274.535484 -101.983609) (xy 274.545552 -101.984048)
			(xy 279.011888 -101.984048) (xy 279.021958 -101.983626) (xy 279.040561 -101.975908) (xy 279.047956 -101.969062)
			(xy 279.067568 -101.949938) (xy 279.111293 -101.916943) (xy 279.159291 -101.890547) (xy 279.210573 -101.871294)
			(xy 279.264084 -101.859582) (xy 279.31872 -101.85565) (xy 279.373356 -101.859582) (xy 279.426867 -101.871294)
			(xy 279.478149 -101.890547) (xy 279.526147 -101.916943) (xy 279.569872 -101.949938) (xy 279.589484 -101.969062)
			(xy 279.596885 -101.975899) (xy 279.615484 -101.983609) (xy 279.625552 -101.984048) (xy 284.091888 -101.984048)
			(xy 284.101958 -101.983626) (xy 284.120561 -101.975908) (xy 284.127956 -101.969062) (xy 284.147568 -101.949938)
			(xy 284.191293 -101.916943) (xy 284.239291 -101.890547) (xy 284.290573 -101.871294) (xy 284.344084 -101.859582)
			(xy 284.39872 -101.85565) (xy 284.453356 -101.859582) (xy 284.506867 -101.871294) (xy 284.558149 -101.890547)
			(xy 284.606147 -101.916943) (xy 284.649872 -101.949938) (xy 284.669484 -101.969062) (xy 284.676885 -101.975899)
			(xy 284.695484 -101.983609) (xy 284.705552 -101.984048) (xy 289.171888 -101.984048) (xy 289.181958 -101.983626)
			(xy 289.200561 -101.975908) (xy 289.207956 -101.969062) (xy 289.227568 -101.949938) (xy 289.271293 -101.916943)
			(xy 289.319291 -101.890547) (xy 289.370573 -101.871294) (xy 289.424084 -101.859582) (xy 289.47872 -101.85565)
			(xy 289.533356 -101.859582) (xy 289.586867 -101.871294) (xy 289.638149 -101.890547) (xy 289.686147 -101.916943)
			(xy 289.729872 -101.949938) (xy 289.749484 -101.969062) (xy 289.756885 -101.975899) (xy 289.775484 -101.983609)
			(xy 289.785552 -101.984048) (xy 294.251888 -101.984048) (xy 294.261958 -101.983626) (xy 294.280561 -101.975908)
			(xy 294.287956 -101.969062) (xy 294.307568 -101.949938) (xy 294.351293 -101.916943) (xy 294.399291 -101.890547)
			(xy 294.450573 -101.871294) (xy 294.504084 -101.859582) (xy 294.55872 -101.85565) (xy 294.613356 -101.859582)
			(xy 294.666867 -101.871294) (xy 294.718149 -101.890547) (xy 294.766147 -101.916943) (xy 294.809872 -101.949938)
			(xy 294.829484 -101.969062) (xy 294.836885 -101.975899) (xy 294.855484 -101.983609) (xy 294.865552 -101.984048)
			(xy 299.331888 -101.984048) (xy 299.341958 -101.983626) (xy 299.360561 -101.975908) (xy 299.367956 -101.969062)
			(xy 299.387568 -101.949938) (xy 299.431293 -101.916943) (xy 299.479291 -101.890547) (xy 299.530573 -101.871294)
			(xy 299.584084 -101.859582) (xy 299.63872 -101.85565) (xy 299.693356 -101.859582) (xy 299.746867 -101.871294)
			(xy 299.798149 -101.890547) (xy 299.846147 -101.916943) (xy 299.889872 -101.949938) (xy 299.909484 -101.969062)
			(xy 299.916885 -101.975899) (xy 299.935484 -101.983609) (xy 299.945552 -101.984048) (xy 304.411888 -101.984048)
			(xy 304.421958 -101.983626) (xy 304.440561 -101.975908) (xy 304.447956 -101.969062) (xy 304.467568 -101.949938)
			(xy 304.511293 -101.916943) (xy 304.559291 -101.890547) (xy 304.610573 -101.871294) (xy 304.664084 -101.859582)
			(xy 304.71872 -101.85565) (xy 304.773356 -101.859582) (xy 304.826867 -101.871294) (xy 304.878149 -101.890547)
			(xy 304.926147 -101.916943) (xy 304.969872 -101.949938) (xy 304.989484 -101.969062) (xy 304.996885 -101.975899)
			(xy 305.015484 -101.983609) (xy 305.025552 -101.984048) (xy 309.491888 -101.984048) (xy 309.501958 -101.983626)
			(xy 309.520561 -101.975908) (xy 309.527956 -101.969062) (xy 309.547568 -101.949938) (xy 309.591293 -101.916943)
			(xy 309.639291 -101.890547) (xy 309.690573 -101.871294) (xy 309.744084 -101.859582) (xy 309.79872 -101.85565)
			(xy 309.853356 -101.859582) (xy 309.906867 -101.871294) (xy 309.958149 -101.890547) (xy 310.006147 -101.916943)
			(xy 310.049872 -101.949938) (xy 310.069484 -101.969062) (xy 310.076885 -101.975899) (xy 310.095484 -101.983609)
			(xy 310.105552 -101.984048) (xy 314.571888 -101.984048) (xy 314.581958 -101.983626) (xy 314.600561 -101.975908)
			(xy 314.607956 -101.969062) (xy 314.627568 -101.949938) (xy 314.671293 -101.916943) (xy 314.719291 -101.890547)
			(xy 314.770573 -101.871294) (xy 314.824084 -101.859582) (xy 314.87872 -101.85565) (xy 314.933356 -101.859582)
			(xy 314.986867 -101.871294) (xy 315.038149 -101.890547) (xy 315.086147 -101.916943) (xy 315.129872 -101.949938)
			(xy 315.149484 -101.969062) (xy 315.156885 -101.975899) (xy 315.175484 -101.983609) (xy 315.185552 -101.984048)
			(xy 319.651888 -101.984048) (xy 319.661958 -101.983626) (xy 319.680561 -101.975908) (xy 319.687956 -101.969062)
			(xy 319.707568 -101.949938) (xy 319.751293 -101.916943) (xy 319.799291 -101.890547) (xy 319.850573 -101.871294)
			(xy 319.904084 -101.859582) (xy 319.95872 -101.85565) (xy 320.013356 -101.859582) (xy 320.066867 -101.871294)
			(xy 320.118149 -101.890547) (xy 320.166147 -101.916943) (xy 320.209872 -101.949938) (xy 320.229484 -101.969062)
			(xy 320.236885 -101.975899) (xy 320.255484 -101.983609) (xy 320.265552 -101.984048) (xy 324.731888 -101.984048)
			(xy 324.741958 -101.983626) (xy 324.760561 -101.975908) (xy 324.767956 -101.969062) (xy 324.787568 -101.949938)
			(xy 324.831293 -101.916943) (xy 324.879291 -101.890547) (xy 324.930573 -101.871294) (xy 324.984084 -101.859582)
			(xy 325.03872 -101.85565) (xy 325.093356 -101.859582) (xy 325.146867 -101.871294) (xy 325.198149 -101.890547)
			(xy 325.246147 -101.916943) (xy 325.289872 -101.949938) (xy 325.309484 -101.969062) (xy 325.316885 -101.975899)
			(xy 325.335484 -101.983609) (xy 325.345552 -101.984048) (xy 328.422 -101.984048) (xy 328.432011 -101.983561)
			(xy 328.450511 -101.975903) (xy 328.464676 -101.961752) (xy 328.472351 -101.943259) (xy 328.4728 -101.933248)
			(xy 328.4728 -81.0768) (xy 328.472312 -81.066792) (xy 328.464652 -81.048301) (xy 328.450499 -81.034148)
			(xy 328.432008 -81.026488) (xy 328.422 -81.026) (xy 311.395364 -81.026) (xy 311.362105 -81.025476)
			(xy 311.296157 -81.016785) (xy 311.231909 -80.999556) (xy 311.170461 -80.974084) (xy 311.112866 -80.940805)
			(xy 311.060109 -80.90029) (xy 311.036208 -80.877156) (xy 310.362854 -80.203802) (xy 310.339695 -80.179923)
			(xy 310.299183 -80.127161) (xy 310.265907 -80.069561) (xy 310.240437 -80.008109) (xy 310.223208 -79.943858)
			(xy 310.214516 -79.877907) (xy 310.21401 -79.844646) (xy 310.21401 -68.489068) (xy 310.213875 -68.484177)
			(xy 310.211961 -68.474583) (xy 310.2102 -68.470018) (xy 310.20639 -68.460366) (xy 310.199024 -68.453254)
			(xy 309.613046 -67.867276) (xy 309.607458 -67.86245) (xy 309.600716 -67.857785) (xy 309.58517 -67.852611)
			(xy 309.576978 -67.85229) (xy 308.29758 -67.85229) (xy 308.288421 -67.852723) (xy 308.27129 -67.859227)
			(xy 308.257508 -67.871303) (xy 308.252876 -67.879214) (xy 308.23281 -67.915996) (xy 308.186744 -67.985991)
			(xy 308.134301 -68.051344) (xy 308.075945 -68.111477) (xy 308.012194 -68.165856) (xy 307.943612 -68.214001)
			(xy 307.870808 -68.255483) (xy 307.794425 -68.289937) (xy 307.715142 -68.317056) (xy 307.633659 -68.3366)
			(xy 307.550701 -68.348396) (xy 307.467 -68.35234) (xy 307.383299 -68.348396) (xy 307.300341 -68.3366)
			(xy 307.218858 -68.317056) (xy 307.139575 -68.289937) (xy 307.063192 -68.255483) (xy 306.990388 -68.214001)
			(xy 306.921806 -68.165856) (xy 306.858055 -68.111477) (xy 306.799699 -68.051344) (xy 306.747256 -67.985991)
			(xy 306.70119 -67.915996) (xy 306.681124 -67.879214) (xy 306.676497 -67.871284) (xy 306.66275 -67.859134)
			(xy 306.645593 -67.852635) (xy 306.63642 -67.85229) (xy 305.487578 -67.85229) (xy 305.478972 -67.852618)
			(xy 305.462731 -67.858318) (xy 305.455828 -67.863466) (xy 305.449399 -67.868975) (xy 305.440311 -67.883248)
			(xy 305.438048 -67.891406) (xy 305.438048 -67.89166) (xy 305.429011 -67.92873) (xy 305.405433 -68.001303)
			(xy 305.375738 -68.071594) (xy 305.358292 -68.105528) (xy 305.355498 -68.110862) (xy 305.35245 -68.122292)
			(xy 305.351025 -68.128564) (xy 305.351023 -68.141421) (xy 305.35245 -68.147692) (xy 305.355498 -68.159122)
			(xy 305.358292 -68.164456) (xy 305.378041 -68.202935) (xy 305.410839 -68.28297) (xy 305.435723 -68.365808)
			(xy 305.452456 -68.450669) (xy 305.460882 -68.536753) (xy 305.461416 -68.58) (xy 305.461416 -68.580508)
			(xy 305.460899 -68.623585) (xy 305.452546 -68.709334) (xy 305.435939 -68.793872) (xy 305.411234 -68.876409)
			(xy 305.378662 -68.956169) (xy 305.359054 -68.994528) (xy 305.356006 -69.000116) (xy 305.353212 -69.011546)
			(xy 305.351688 -69.017896) (xy 305.351688 -69.030342) (xy 305.35626 -69.047868) (xy 305.359054 -69.053202)
			(xy 305.378763 -69.091665) (xy 305.411492 -69.171661) (xy 305.436319 -69.25445) (xy 305.453012 -69.339254)
			(xy 305.461412 -69.425276) (xy 305.461924 -69.468492) (xy 305.461924 -69.469) (xy 305.461368 -69.51276)
			(xy 305.45275 -69.599855) (xy 305.435638 -69.685685) (xy 305.410196 -69.769426) (xy 305.376668 -69.850269)
			(xy 305.356514 -69.889116) (xy 305.353466 -69.894704) (xy 305.350418 -69.906642) (xy 305.350418 -69.920358)
			(xy 305.353466 -69.932296) (xy 305.356514 -69.937884) (xy 305.376716 -69.976709) (xy 305.410264 -70.05755)
			(xy 305.435713 -70.141295) (xy 305.452817 -70.227134) (xy 305.461411 -70.314237) (xy 305.461924 -70.358)
			(xy 305.46142 -70.400397) (xy 305.45336 -70.484807) (xy 305.437312 -70.568068) (xy 305.413423 -70.649427)
			(xy 305.381908 -70.728147) (xy 305.343054 -70.803515) (xy 305.297211 -70.874848) (xy 305.244795 -70.9415)
			(xy 305.18628 -71.002868) (xy 305.122198 -71.058396) (xy 305.053127 -71.107581) (xy 304.979693 -71.149978)
			(xy 304.902562 -71.185203) (xy 304.822432 -71.212936) (xy 304.740028 -71.232927) (xy 304.656098 -71.244994)
			(xy 304.5714 -71.249029) (xy 304.486702 -71.244994) (xy 304.402772 -71.232927) (xy 304.320368 -71.212936)
			(xy 304.240238 -71.185203) (xy 304.163107 -71.149978) (xy 304.089673 -71.107581) (xy 304.020602 -71.058396)
			(xy 303.95652 -71.002868) (xy 303.898005 -70.9415) (xy 303.845589 -70.874848) (xy 303.799746 -70.803515)
			(xy 303.760892 -70.728147) (xy 303.729377 -70.649427) (xy 303.705488 -70.568068) (xy 303.68944 -70.484807)
			(xy 303.68138 -70.400397) (xy 303.680876 -70.358) (xy 303.681432 -70.31424) (xy 303.69005 -70.227145)
			(xy 303.707162 -70.141315) (xy 303.732604 -70.057574) (xy 303.766132 -69.976731) (xy 303.786286 -69.937884)
			(xy 303.789334 -69.932296) (xy 303.792382 -69.920358) (xy 303.792382 -69.906642) (xy 303.789334 -69.894704)
			(xy 303.786286 -69.889116) (xy 303.766084 -69.850291) (xy 303.732536 -69.76945) (xy 303.707087 -69.685705)
			(xy 303.689983 -69.599866) (xy 303.681389 -69.512763) (xy 303.680876 -69.469) (xy 303.680876 -69.468492)
			(xy 303.681397 -69.425276) (xy 303.68979 -69.339252) (xy 303.706475 -69.254446) (xy 303.731296 -69.171655)
			(xy 303.76402 -69.091657) (xy 303.783746 -69.053202) (xy 303.78654 -69.047868) (xy 303.791112 -69.030342)
			(xy 303.791112 -69.017896) (xy 303.789588 -69.011546) (xy 303.786794 -69.000116) (xy 303.783746 -68.994528)
			(xy 303.764141 -68.956169) (xy 303.731591 -68.876403) (xy 303.706898 -68.793865) (xy 303.690293 -68.709329)
			(xy 303.681932 -68.623584) (xy 303.681384 -68.580508) (xy 303.681384 -68.58) (xy 303.681908 -68.536752)
			(xy 303.690323 -68.450665) (xy 303.707053 -68.365802) (xy 303.73194 -68.282963) (xy 303.76475 -68.202931)
			(xy 303.784508 -68.164456) (xy 303.787302 -68.159122) (xy 303.79035 -68.147692) (xy 303.791773 -68.141421)
			(xy 303.791772 -68.128564) (xy 303.79035 -68.122292) (xy 303.787302 -68.110862) (xy 303.784508 -68.105528)
			(xy 303.767053 -68.071598) (xy 303.737344 -68.001311) (xy 303.713778 -67.928733) (xy 303.704752 -67.89166)
			(xy 303.704752 -67.891406) (xy 303.702437 -67.883269) (xy 303.693369 -67.869001) (xy 303.686972 -67.863466)
			(xy 303.680049 -67.858351) (xy 303.663823 -67.852636) (xy 303.655222 -67.85229) (xy 302.50638 -67.85229)
			(xy 302.497221 -67.852723) (xy 302.48009 -67.859227) (xy 302.466308 -67.871303) (xy 302.461676 -67.879214)
			(xy 302.44161 -67.915996) (xy 302.395544 -67.985991) (xy 302.343101 -68.051344) (xy 302.284745 -68.111477)
			(xy 302.220994 -68.165856) (xy 302.152412 -68.214001) (xy 302.079608 -68.255483) (xy 302.003225 -68.289937)
			(xy 301.923942 -68.317056) (xy 301.842459 -68.3366) (xy 301.759501 -68.348396) (xy 301.6758 -68.35234)
			(xy 301.592099 -68.348396) (xy 301.509141 -68.3366) (xy 301.427658 -68.317056) (xy 301.348375 -68.289937)
			(xy 301.271992 -68.255483) (xy 301.199188 -68.214001) (xy 301.130606 -68.165856) (xy 301.066855 -68.111477)
			(xy 301.008499 -68.051344) (xy 300.956056 -67.985991) (xy 300.90999 -67.915996) (xy 300.889924 -67.879214)
			(xy 300.885297 -67.871284) (xy 300.87155 -67.859134) (xy 300.854393 -67.852635) (xy 300.84522 -67.85229)
			(xy 298.591224 -67.85229) (xy 298.584866 -67.852458) (xy 298.572532 -67.855548) (xy 298.56684 -67.858386)
			(xy 298.561506 -67.861434) (xy 298.552362 -67.869816) (xy 298.548806 -67.875404) (xy 298.502578 -67.946016)
			(xy 298.500314 -67.949623) (xy 298.496868 -67.957409) (xy 298.49572 -67.96151) (xy 298.493945 -67.969794)
			(xy 298.49536 -67.986668) (xy 298.498514 -67.99453) (xy 298.498514 -67.994784) (xy 298.516529 -68.037175)
			(xy 298.544722 -68.124868) (xy 298.563719 -68.215002) (xy 298.573317 -68.306614) (xy 298.573952 -68.35267)
			(xy 298.573952 -68.35394) (xy 298.573465 -68.396338) (xy 298.565402 -68.480749) (xy 298.549344 -68.564011)
			(xy 298.525437 -68.645366) (xy 298.493898 -68.724078) (xy 298.455012 -68.799432) (xy 298.409133 -68.870744)
			(xy 298.356676 -68.937366) (xy 298.298119 -68.998696) (xy 298.266358 -69.026786) (xy 298.264834 -69.028056)
			(xy 298.26331 -69.02958) (xy 298.256924 -69.036571) (xy 298.249378 -69.053925) (xy 298.248578 -69.063362)
			(xy 298.248578 -69.14261) (xy 298.249106 -69.153534) (xy 298.258206 -69.173396) (xy 298.266104 -69.180964)
			(xy 298.297869 -69.209077) (xy 298.35647 -69.270418) (xy 298.408966 -69.337057) (xy 298.45488 -69.408391)
			(xy 298.493796 -69.483771) (xy 298.52536 -69.562513) (xy 298.549286 -69.643902) (xy 298.565357 -69.727199)
			(xy 298.573425 -69.811647) (xy 298.573952 -69.854064) (xy 298.573448 -69.896412) (xy 298.565397 -69.980726)
			(xy 298.549368 -70.063892) (xy 298.525507 -70.145159) (xy 298.494028 -70.223789) (xy 298.455217 -70.29907)
			(xy 298.409427 -70.370322) (xy 298.357071 -70.436898) (xy 298.298623 -70.498196) (xy 298.234613 -70.553661)
			(xy 298.165621 -70.60279) (xy 298.092271 -70.645139) (xy 298.015228 -70.680323) (xy 297.935189 -70.708025)
			(xy 297.85288 -70.727993) (xy 297.769045 -70.740046) (xy 297.684444 -70.744077) (xy 297.599843 -70.740046)
			(xy 297.516008 -70.727993) (xy 297.433699 -70.708025) (xy 297.35366 -70.680323) (xy 297.276617 -70.645139)
			(xy 297.203267 -70.60279) (xy 297.134275 -70.553661) (xy 297.070265 -70.498196) (xy 297.011817 -70.436898)
			(xy 296.959461 -70.370322) (xy 296.913671 -70.29907) (xy 296.87486 -70.223789) (xy 296.843381 -70.145159)
			(xy 296.81952 -70.063892) (xy 296.803491 -69.980726) (xy 296.79544 -69.896412) (xy 296.794936 -69.854064)
			(xy 296.795429 -69.811648) (xy 296.803506 -69.7272) (xy 296.819585 -69.643905) (xy 296.843519 -69.562518)
			(xy 296.87509 -69.483779) (xy 296.914013 -69.408402) (xy 296.959933 -69.337072) (xy 297.012434 -69.270436)
			(xy 297.071038 -69.2091) (xy 297.102784 -69.180964) (xy 297.110699 -69.173412) (xy 297.119792 -69.153537)
			(xy 297.12031 -69.14261) (xy 297.12031 -69.06514) (xy 297.12015 -69.059764) (xy 297.117848 -69.049259)
			(xy 297.115738 -69.044312) (xy 297.11142 -69.03466) (xy 297.103038 -69.027294) (xy 297.10253 -69.026786)
			(xy 297.101006 -69.025516) (xy 297.069416 -68.997399) (xy 297.011133 -68.936113) (xy 296.958929 -68.869573)
			(xy 296.913276 -68.798379) (xy 296.874585 -68.723173) (xy 296.843205 -68.644635) (xy 296.819421 -68.563473)
			(xy 296.803447 -68.480421) (xy 296.795426 -68.396227) (xy 296.794936 -68.35394) (xy 296.795422 -68.312328)
			(xy 296.803198 -68.229467) (xy 296.818675 -68.147694) (xy 296.841719 -68.067724) (xy 296.872129 -67.990254)
			(xy 296.909639 -67.915962) (xy 296.953921 -67.845496) (xy 297.004588 -67.779472) (xy 297.061198 -67.718466)
			(xy 297.123256 -67.663013) (xy 297.190221 -67.613595) (xy 297.261506 -67.570645) (xy 297.33649 -67.534538)
			(xy 297.414518 -67.505589) (xy 297.494907 -67.484052) (xy 297.535854 -67.476624) (xy 297.542458 -67.475608)
			(xy 297.556428 -67.469258) (xy 297.560105 -67.467468) (xy 297.566872 -67.462874) (xy 297.56989 -67.460114)
			(xy 297.574583 -67.45552) (xy 297.581649 -67.444455) (xy 297.58386 -67.43827) (xy 297.61053 -67.354958)
			(xy 297.612979 -67.345949) (xy 297.611963 -67.327324) (xy 297.604391 -67.310277) (xy 297.598084 -67.303396)
			(xy 296.185844 -65.891156) (xy 296.162688 -65.867276) (xy 296.122182 -65.814512) (xy 296.088911 -65.756911)
			(xy 296.063447 -65.69546) (xy 296.046225 -65.631209) (xy 296.037539 -65.565259) (xy 296.037 -65.532)
			(xy 296.037 -62.18174) (xy 296.036863 -62.17685) (xy 296.034943 -62.167258) (xy 296.03319 -62.16269)
			(xy 296.02938 -62.153038) (xy 296.022014 -62.145926) (xy 293.200074 -59.323986) (xy 293.194486 -59.31916)
			(xy 293.187746 -59.314491) (xy 293.1722 -59.309307) (xy 293.164006 -59.309) (xy 282.2956 -59.309)
			(xy 282.26234 -59.308479) (xy 282.19639 -59.299791) (xy 282.132139 -59.282566) (xy 282.070688 -59.257097)
			(xy 282.013089 -59.223821) (xy 281.960329 -59.183308) (xy 281.936444 -59.160156) (xy 274.538186 -51.761898)
			(xy 274.532598 -51.757072) (xy 274.525859 -51.7524) (xy 274.510312 -51.747211) (xy 274.502118 -51.746912)
			(xy 266.64793 -51.746912) (xy 266.64304 -51.74705) (xy 266.633449 -51.748972) (xy 266.62888 -51.750722)
			(xy 266.619228 -51.754532) (xy 266.612116 -51.761898) (xy 265.219688 -53.154326) (xy 265.214862 -53.159914)
			(xy 265.210193 -53.166654) (xy 265.205008 -53.1822) (xy 265.204702 -53.190394) (xy 265.204702 -57.912)
			(xy 268.756388 -57.912) (xy 268.760418 -57.827399) (xy 268.772471 -57.743564) (xy 268.792439 -57.661255)
			(xy 268.820141 -57.581216) (xy 268.855325 -57.504173) (xy 268.897674 -57.430823) (xy 268.946803 -57.361831)
			(xy 269.002268 -57.297821) (xy 269.063566 -57.239373) (xy 269.130142 -57.187017) (xy 269.201394 -57.141227)
			(xy 269.276675 -57.102416) (xy 269.355305 -57.070937) (xy 269.436572 -57.047076) (xy 269.519738 -57.031047)
			(xy 269.604052 -57.022996) (xy 269.6464 -57.022492) (xy 269.646908 -57.022492) (xy 269.69324 -57.023098)
			(xy 269.785398 -57.032769) (xy 269.876052 -57.051965) (xy 269.964221 -57.080477) (xy 270.006826 -57.098692)
			(xy 270.016768 -57.102498) (xy 270.038032 -57.102498) (xy 270.047974 -57.098692) (xy 270.090636 -57.080447)
			(xy 270.178929 -57.051903) (xy 270.269714 -57.03271) (xy 270.362004 -57.023077) (xy 270.4084 -57.022492)
			(xy 270.451753 -57.02298) (xy 270.538049 -57.031388) (xy 270.623118 -57.048154) (xy 270.706152 -57.073118)
			(xy 270.786362 -57.106044) (xy 270.862988 -57.146619) (xy 270.935302 -57.194458) (xy 271.002617 -57.249107)
			(xy 271.064295 -57.310046) (xy 271.092422 -57.34304) (xy 271.099534 -57.351676) (xy 271.119854 -57.361328)
			(xy 271.220946 -57.361328) (xy 271.241266 -57.351676) (xy 271.248378 -57.34304) (xy 271.276524 -57.310064)
			(xy 271.338205 -57.249132) (xy 271.40552 -57.194489) (xy 271.477833 -57.146654) (xy 271.554455 -57.106081)
			(xy 271.634662 -57.073155) (xy 271.717692 -57.048188) (xy 271.802756 -57.031418) (xy 271.889049 -57.023002)
			(xy 271.9324 -57.022492) (xy 271.978796 -57.023075) (xy 272.071084 -57.03272) (xy 272.161868 -57.051916)
			(xy 272.250161 -57.080454) (xy 272.292826 -57.098692) (xy 272.302768 -57.102498) (xy 272.324032 -57.102498)
			(xy 272.333974 -57.098692) (xy 272.376577 -57.08047) (xy 272.464744 -57.051952) (xy 272.5554 -57.03276)
			(xy 272.64756 -57.0231) (xy 272.693892 -57.022492) (xy 272.6944 -57.022492) (xy 272.736748 -57.022996)
			(xy 272.821062 -57.031047) (xy 272.904228 -57.047076) (xy 272.985495 -57.070937) (xy 273.064125 -57.102416)
			(xy 273.139406 -57.141227) (xy 273.210658 -57.187017) (xy 273.277234 -57.239373) (xy 273.338532 -57.297821)
			(xy 273.393997 -57.361831) (xy 273.443126 -57.430823) (xy 273.485475 -57.504173) (xy 273.520659 -57.581216)
			(xy 273.548361 -57.661255) (xy 273.568329 -57.743564) (xy 273.580382 -57.827399) (xy 273.584413 -57.912)
			(xy 273.580382 -57.996601) (xy 273.568329 -58.080436) (xy 273.548361 -58.162745) (xy 273.520659 -58.242784)
			(xy 273.485475 -58.319827) (xy 273.443126 -58.393177) (xy 273.393997 -58.462169) (xy 273.338532 -58.526179)
			(xy 273.277234 -58.584627) (xy 273.210658 -58.636983) (xy 273.139406 -58.682773) (xy 273.064125 -58.721584)
			(xy 272.985495 -58.753063) (xy 272.904228 -58.776924) (xy 272.821062 -58.792953) (xy 272.736748 -58.801004)
			(xy 272.6944 -58.801508) (xy 272.693892 -58.801508) (xy 272.64756 -58.800902) (xy 272.555402 -58.791231)
			(xy 272.464748 -58.772035) (xy 272.376579 -58.743523) (xy 272.333974 -58.725308) (xy 272.324032 -58.721502)
			(xy 272.302768 -58.721502) (xy 272.292826 -58.725308) (xy 272.250164 -58.743553) (xy 272.161871 -58.772097)
			(xy 272.071086 -58.79129) (xy 271.978796 -58.800923) (xy 271.9324 -58.801508) (xy 271.889047 -58.80102)
			(xy 271.802751 -58.792612) (xy 271.717682 -58.775846) (xy 271.634648 -58.750882) (xy 271.554438 -58.717956)
			(xy 271.477812 -58.677381) (xy 271.405498 -58.629542) (xy 271.338183 -58.574893) (xy 271.276505 -58.513954)
			(xy 271.248378 -58.48096) (xy 271.241266 -58.472324) (xy 271.220946 -58.462672) (xy 271.119854 -58.462672)
			(xy 271.099534 -58.472324) (xy 271.092422 -58.48096) (xy 271.064276 -58.513936) (xy 271.002595 -58.574868)
			(xy 270.93528 -58.629511) (xy 270.862967 -58.677346) (xy 270.786345 -58.717919) (xy 270.706138 -58.750845)
			(xy 270.623108 -58.775812) (xy 270.538044 -58.792582) (xy 270.451751 -58.800998) (xy 270.4084 -58.801508)
			(xy 270.362004 -58.800925) (xy 270.269716 -58.79128) (xy 270.178932 -58.772084) (xy 270.090639 -58.743546)
			(xy 270.047974 -58.725308) (xy 270.038032 -58.721502) (xy 270.016768 -58.721502) (xy 270.006826 -58.725308)
			(xy 269.964223 -58.74353) (xy 269.876056 -58.772048) (xy 269.7854 -58.79124) (xy 269.69324 -58.8009)
			(xy 269.646908 -58.801508) (xy 269.6464 -58.801508) (xy 269.604052 -58.801004) (xy 269.519738 -58.792953)
			(xy 269.436572 -58.776924) (xy 269.355305 -58.753063) (xy 269.276675 -58.721584) (xy 269.201394 -58.682773)
			(xy 269.130142 -58.636983) (xy 269.063566 -58.584627) (xy 269.002268 -58.526179) (xy 268.946803 -58.462169)
			(xy 268.897674 -58.393177) (xy 268.855325 -58.319827) (xy 268.820141 -58.242784) (xy 268.792439 -58.162745)
			(xy 268.772471 -58.080436) (xy 268.760418 -57.996601) (xy 268.756388 -57.912) (xy 265.204702 -57.912)
			(xy 265.204702 -68.199) (xy 267.232388 -68.199) (xy 267.236418 -68.114399) (xy 267.248471 -68.030564)
			(xy 267.268439 -67.948255) (xy 267.296141 -67.868216) (xy 267.331325 -67.791173) (xy 267.373674 -67.717823)
			(xy 267.422803 -67.648831) (xy 267.478268 -67.584821) (xy 267.539566 -67.526373) (xy 267.606142 -67.474017)
			(xy 267.677394 -67.428227) (xy 267.752675 -67.389416) (xy 267.831305 -67.357937) (xy 267.912572 -67.334076)
			(xy 267.995738 -67.318047) (xy 268.080052 -67.309996) (xy 268.1224 -67.309492) (xy 268.122908 -67.309492)
			(xy 268.161656 -67.309926) (xy 268.238857 -67.316687) (xy 268.315177 -67.330139) (xy 268.390036 -67.350181)
			(xy 268.462869 -67.37666) (xy 268.53312 -67.409376) (xy 268.5669 -67.428364) (xy 268.574774 -67.432523)
			(xy 268.5923 -67.435617) (xy 268.609826 -67.432523) (xy 268.6177 -67.428364) (xy 268.651489 -67.409393)
			(xy 268.721739 -67.376677) (xy 268.79457 -67.350196) (xy 268.869428 -67.330151) (xy 268.945745 -67.316693)
			(xy 269.022945 -67.309925) (xy 269.061692 -67.309492) (xy 269.0622 -67.309492) (xy 269.104548 -67.309996)
			(xy 269.188862 -67.318047) (xy 269.272028 -67.334076) (xy 269.353295 -67.357937) (xy 269.431925 -67.389416)
			(xy 269.507206 -67.428227) (xy 269.578458 -67.474017) (xy 269.645034 -67.526373) (xy 269.706332 -67.584821)
			(xy 269.761797 -67.648831) (xy 269.810926 -67.717823) (xy 269.853275 -67.791173) (xy 269.888459 -67.868216)
			(xy 269.916161 -67.948255) (xy 269.936129 -68.030564) (xy 269.948182 -68.114399) (xy 269.952213 -68.199)
			(xy 269.948182 -68.283601) (xy 269.936129 -68.367436) (xy 269.916161 -68.449745) (xy 269.888459 -68.529784)
			(xy 269.853275 -68.606827) (xy 269.810926 -68.680177) (xy 269.761797 -68.749169) (xy 269.706332 -68.813179)
			(xy 269.645034 -68.871627) (xy 269.578458 -68.923983) (xy 269.507206 -68.969773) (xy 269.431925 -69.008584)
			(xy 269.353295 -69.040063) (xy 269.272028 -69.063924) (xy 269.188862 -69.079953) (xy 269.104548 -69.088004)
			(xy 269.0622 -69.088508) (xy 269.061692 -69.088508) (xy 269.022944 -69.088074) (xy 268.945743 -69.081313)
			(xy 268.869423 -69.067861) (xy 268.794564 -69.047819) (xy 268.721731 -69.02134) (xy 268.65148 -68.988624)
			(xy 268.6177 -68.969636) (xy 268.609826 -68.965477) (xy 268.5923 -68.962383) (xy 268.574774 -68.965477)
			(xy 268.5669 -68.969636) (xy 268.533111 -68.988607) (xy 268.462861 -69.021323) (xy 268.39003 -69.047804)
			(xy 268.315172 -69.067849) (xy 268.238855 -69.081307) (xy 268.161655 -69.088075) (xy 268.122908 -69.088508)
			(xy 268.1224 -69.088508) (xy 268.080052 -69.088004) (xy 267.995738 -69.079953) (xy 267.912572 -69.063924)
			(xy 267.831305 -69.040063) (xy 267.752675 -69.008584) (xy 267.677394 -68.969773) (xy 267.606142 -68.923983)
			(xy 267.539566 -68.871627) (xy 267.478268 -68.813179) (xy 267.422803 -68.749169) (xy 267.373674 -68.680177)
			(xy 267.331325 -68.606827) (xy 267.296141 -68.529784) (xy 267.268439 -68.449745) (xy 267.248471 -68.367436)
			(xy 267.236418 -68.283601) (xy 267.232388 -68.199) (xy 265.204702 -68.199) (xy 265.204702 -68.475098)
			(xy 265.204702 -68.478146) (xy 265.204956 -68.480686) (xy 265.205742 -68.488972) (xy 265.211972 -68.504393)
			(xy 265.217148 -68.510912) (xy 265.222482 -68.517008) (xy 265.226546 -68.522596) (xy 265.2268 -68.52285)
			(xy 265.22972 -68.527162) (xy 265.237015 -68.534591) (xy 265.241278 -68.537582) (xy 265.248136 -68.541392)
			(xy 265.285979 -68.559634) (xy 265.358383 -68.602253) (xy 265.426446 -68.65151) (xy 265.489561 -68.706964)
			(xy 265.547166 -68.768123) (xy 265.598747 -68.834441) (xy 265.643845 -68.905327) (xy 265.682058 -68.98015)
			(xy 265.713046 -69.058242) (xy 265.736532 -69.138909) (xy 265.752308 -69.22143) (xy 265.760232 -69.305072)
			(xy 265.760708 -69.34708) (xy 265.760134 -69.392386) (xy 265.750895 -69.482525) (xy 265.732532 -69.571256)
			(xy 265.705235 -69.657658) (xy 265.669287 -69.740834) (xy 265.647678 -69.780658) (xy 265.647678 -69.780912)
			(xy 265.647424 -69.781166) (xy 265.644959 -69.785983) (xy 265.641894 -69.796358) (xy 265.641328 -69.80174)
			(xy 265.640566 -69.81317) (xy 265.671808 -69.896228) (xy 265.673934 -69.901409) (xy 265.680084 -69.910767)
			(xy 265.684 -69.91477) (xy 265.69162 -69.922136) (xy 265.702288 -69.925946) (xy 265.741776 -69.940498)
			(xy 265.818065 -69.97604) (xy 265.890656 -70.018627) (xy 265.958901 -70.06788) (xy 266.02219 -70.123357)
			(xy 266.079957 -70.184563) (xy 266.131686 -70.25095) (xy 266.176914 -70.321926) (xy 266.215238 -70.396856)
			(xy 266.246314 -70.475071) (xy 266.269865 -70.55587) (xy 266.28568 -70.638533) (xy 266.293619 -70.722319)
			(xy 266.294108 -70.7644) (xy 266.293633 -70.805502) (xy 266.286048 -70.887357) (xy 266.270943 -70.968162)
			(xy 266.256649 -71.0184) (xy 267.232388 -71.0184) (xy 267.236418 -70.933799) (xy 267.248471 -70.849964)
			(xy 267.268439 -70.767655) (xy 267.296141 -70.687616) (xy 267.331325 -70.610573) (xy 267.373674 -70.537223)
			(xy 267.422803 -70.468231) (xy 267.478268 -70.404221) (xy 267.539566 -70.345773) (xy 267.606142 -70.293417)
			(xy 267.677394 -70.247627) (xy 267.752675 -70.208816) (xy 267.831305 -70.177337) (xy 267.912572 -70.153476)
			(xy 267.995738 -70.137447) (xy 268.080052 -70.129396) (xy 268.1224 -70.128892) (xy 268.122908 -70.128892)
			(xy 268.161656 -70.129326) (xy 268.238857 -70.136087) (xy 268.315177 -70.149539) (xy 268.390036 -70.169581)
			(xy 268.462869 -70.19606) (xy 268.53312 -70.228776) (xy 268.5669 -70.247764) (xy 268.574774 -70.251923)
			(xy 268.5923 -70.255017) (xy 268.609826 -70.251923) (xy 268.6177 -70.247764) (xy 268.651489 -70.228793)
			(xy 268.721739 -70.196077) (xy 268.79457 -70.169596) (xy 268.869428 -70.149551) (xy 268.945745 -70.136093)
			(xy 269.022945 -70.129325) (xy 269.061692 -70.128892) (xy 269.0622 -70.128892) (xy 269.104548 -70.129396)
			(xy 269.188862 -70.137447) (xy 269.272028 -70.153476) (xy 269.353295 -70.177337) (xy 269.431925 -70.208816)
			(xy 269.507206 -70.247627) (xy 269.578458 -70.293417) (xy 269.645034 -70.345773) (xy 269.706332 -70.404221)
			(xy 269.761797 -70.468231) (xy 269.810926 -70.537223) (xy 269.853275 -70.610573) (xy 269.888459 -70.687616)
			(xy 269.916161 -70.767655) (xy 269.936129 -70.849964) (xy 269.948182 -70.933799) (xy 269.952213 -71.0184)
			(xy 269.948182 -71.103001) (xy 269.936129 -71.186836) (xy 269.916161 -71.269145) (xy 269.888459 -71.349184)
			(xy 269.853275 -71.426227) (xy 269.810926 -71.499577) (xy 269.761797 -71.568569) (xy 269.706332 -71.632579)
			(xy 269.645034 -71.691027) (xy 269.578458 -71.743383) (xy 269.507206 -71.789173) (xy 269.431925 -71.827984)
			(xy 269.353295 -71.859463) (xy 269.272028 -71.883324) (xy 269.188862 -71.899353) (xy 269.104548 -71.907404)
			(xy 269.0622 -71.907908) (xy 269.061692 -71.907908) (xy 269.022944 -71.907474) (xy 268.945743 -71.900713)
			(xy 268.869423 -71.887261) (xy 268.794564 -71.867219) (xy 268.721731 -71.84074) (xy 268.65148 -71.808024)
			(xy 268.6177 -71.789036) (xy 268.609826 -71.784877) (xy 268.5923 -71.781783) (xy 268.574774 -71.784877)
			(xy 268.5669 -71.789036) (xy 268.533111 -71.808007) (xy 268.462861 -71.840723) (xy 268.39003 -71.867204)
			(xy 268.315172 -71.887249) (xy 268.238855 -71.900707) (xy 268.161655 -71.907475) (xy 268.122908 -71.907908)
			(xy 268.1224 -71.907908) (xy 268.080052 -71.907404) (xy 267.995738 -71.899353) (xy 267.912572 -71.883324)
			(xy 267.831305 -71.859463) (xy 267.752675 -71.827984) (xy 267.677394 -71.789173) (xy 267.606142 -71.743383)
			(xy 267.539566 -71.691027) (xy 267.478268 -71.632579) (xy 267.422803 -71.568569) (xy 267.373674 -71.499577)
			(xy 267.331325 -71.426227) (xy 267.296141 -71.349184) (xy 267.268439 -71.269145) (xy 267.248471 -71.186836)
			(xy 267.236418 -71.103001) (xy 267.232388 -71.0184) (xy 266.256649 -71.0184) (xy 266.248447 -71.047229)
			(xy 266.218751 -71.123883) (xy 266.182109 -71.19747) (xy 266.138834 -71.267362) (xy 266.089294 -71.332963)
			(xy 266.033913 -71.393713) (xy 265.973163 -71.449094) (xy 265.907562 -71.498634) (xy 265.83767 -71.541909)
			(xy 265.764083 -71.578551) (xy 265.687429 -71.608247) (xy 265.608362 -71.630743) (xy 265.527557 -71.645848)
			(xy 265.445702 -71.653433) (xy 265.4046 -71.653908) (xy 265.40333 -71.653908) (xy 265.382469 -71.653753)
			(xy 265.340795 -71.651723) (xy 265.320018 -71.649844) (xy 265.317732 -71.64959) (xy 265.310874 -71.64959)
			(xy 265.306198 -71.649671) (xy 265.296994 -71.651328) (xy 265.292586 -71.652892) (xy 265.283696 -71.656448)
			(xy 265.277092 -71.662544) (xy 265.221466 -71.712836) (xy 265.21396 -71.720381) (xy 265.205309 -71.739801)
			(xy 265.204702 -71.750428) (xy 265.204702 -73.8886) (xy 266.368788 -73.8886) (xy 266.372818 -73.803999)
			(xy 266.384871 -73.720164) (xy 266.404839 -73.637855) (xy 266.432541 -73.557816) (xy 266.467725 -73.480773)
			(xy 266.510074 -73.407423) (xy 266.559203 -73.338431) (xy 266.614668 -73.274421) (xy 266.675966 -73.215973)
			(xy 266.742542 -73.163617) (xy 266.813794 -73.117827) (xy 266.889075 -73.079016) (xy 266.967705 -73.047537)
			(xy 267.048972 -73.023676) (xy 267.132138 -73.007647) (xy 267.216452 -72.999596) (xy 267.2588 -72.999092)
			(xy 267.259562 -72.999092) (xy 267.297909 -72.999501) (xy 267.374317 -73.006133) (xy 267.449868 -73.019325)
			(xy 267.524002 -73.038978) (xy 267.596166 -73.064947) (xy 267.631164 -73.080626) (xy 267.641437 -73.084766)
			(xy 267.663563 -73.084766) (xy 267.673836 -73.080626) (xy 267.708833 -73.064947) (xy 267.781003 -73.039)
			(xy 267.855138 -73.019357) (xy 267.930687 -73.006163) (xy 268.007092 -72.999518) (xy 268.045438 -72.999092)
			(xy 268.0462 -72.999092) (xy 268.088548 -72.999596) (xy 268.172862 -73.007647) (xy 268.256028 -73.023676)
			(xy 268.337295 -73.047537) (xy 268.415925 -73.079016) (xy 268.491206 -73.117827) (xy 268.562458 -73.163617)
			(xy 268.629034 -73.215973) (xy 268.690332 -73.274421) (xy 268.745797 -73.338431) (xy 268.794926 -73.407423)
			(xy 268.837275 -73.480773) (xy 268.872459 -73.557816) (xy 268.900161 -73.637855) (xy 268.920129 -73.720164)
			(xy 268.932182 -73.803999) (xy 268.936213 -73.8886) (xy 268.932182 -73.973201) (xy 268.920129 -74.057036)
			(xy 268.900161 -74.139345) (xy 268.872459 -74.219384) (xy 268.837275 -74.296427) (xy 268.794926 -74.369777)
			(xy 268.745797 -74.438769) (xy 268.697852 -74.4941) (xy 303.021024 -74.4941) (xy 303.025053 -74.409502)
			(xy 303.037107 -74.325671) (xy 303.057074 -74.243365) (xy 303.084774 -74.163329) (xy 303.119957 -74.086289)
			(xy 303.162304 -74.012942) (xy 303.211431 -73.943953) (xy 303.266894 -73.879946) (xy 303.328189 -73.821501)
			(xy 303.394763 -73.769147) (xy 303.466012 -73.723358) (xy 303.54129 -73.684549) (xy 303.619917 -73.653071)
			(xy 303.70118 -73.629211) (xy 303.784343 -73.613182) (xy 303.868653 -73.605132) (xy 303.911 -73.604628)
			(xy 303.951046 -73.605059) (xy 304.030815 -73.612254) (xy 304.109614 -73.626586) (xy 304.186807 -73.647939)
			(xy 304.26177 -73.67614) (xy 304.333897 -73.710962) (xy 304.402603 -73.752123) (xy 304.467334 -73.799289)
			(xy 304.49774 -73.825354) (xy 304.504826 -73.831124) (xy 304.521886 -73.837632) (xy 304.531014 -73.838054)
			(xy 304.560986 -73.838054) (xy 304.570108 -73.837612) (xy 304.587158 -73.831097) (xy 304.59426 -73.825354)
			(xy 304.624664 -73.799286) (xy 304.689385 -73.752101) (xy 304.758087 -73.710928) (xy 304.830213 -73.676099)
			(xy 304.905178 -73.647896) (xy 304.982375 -73.626549) (xy 305.06118 -73.61223) (xy 305.140952 -73.605055)
			(xy 305.181 -73.604628) (xy 305.22335 -73.60506) (xy 305.307667 -73.613111) (xy 305.390837 -73.629141)
			(xy 305.472106 -73.653003) (xy 305.55074 -73.684483) (xy 305.626024 -73.723295) (xy 305.697279 -73.769088)
			(xy 305.763858 -73.821446) (xy 305.825158 -73.879896) (xy 305.880625 -73.943909) (xy 305.929756 -74.012903)
			(xy 305.972107 -74.086256) (xy 306.007292 -74.163302) (xy 306.034995 -74.243344) (xy 306.054964 -74.325657)
			(xy 306.067018 -74.409496) (xy 306.071049 -74.4941) (xy 306.067018 -74.578704) (xy 306.054964 -74.662543)
			(xy 306.034995 -74.744856) (xy 306.007292 -74.824898) (xy 305.972107 -74.901944) (xy 305.929756 -74.975297)
			(xy 305.880625 -75.044291) (xy 305.825158 -75.108304) (xy 305.763858 -75.166754) (xy 305.697279 -75.219112)
			(xy 305.626024 -75.264905) (xy 305.55074 -75.303717) (xy 305.472106 -75.335197) (xy 305.390837 -75.359059)
			(xy 305.307667 -75.375089) (xy 305.22335 -75.38314) (xy 305.181 -75.383644) (xy 305.140954 -75.38322)
			(xy 305.061185 -75.376025) (xy 304.982385 -75.361692) (xy 304.905191 -75.340339) (xy 304.830228 -75.312136)
			(xy 304.758102 -75.277313) (xy 304.689396 -75.236152) (xy 304.624665 -75.188984) (xy 304.59426 -75.162918)
			(xy 304.587168 -75.157157) (xy 304.570113 -75.150642) (xy 304.560986 -75.150218) (xy 304.531014 -75.150218)
			(xy 304.521893 -75.150666) (xy 304.504843 -75.157178) (xy 304.49774 -75.162918) (xy 304.467332 -75.188982)
			(xy 304.402612 -75.236167) (xy 304.333911 -75.277342) (xy 304.261786 -75.312171) (xy 304.186821 -75.340374)
			(xy 304.109624 -75.361722) (xy 304.03082 -75.376042) (xy 303.951047 -75.383217) (xy 303.911 -75.383644)
			(xy 303.868653 -75.383068) (xy 303.784343 -75.375018) (xy 303.70118 -75.358989) (xy 303.619917 -75.335129)
			(xy 303.54129 -75.303651) (xy 303.466012 -75.264842) (xy 303.394763 -75.219053) (xy 303.328189 -75.166699)
			(xy 303.266894 -75.108254) (xy 303.211431 -75.044247) (xy 303.162304 -74.975258) (xy 303.119957 -74.901911)
			(xy 303.084774 -74.824871) (xy 303.057074 -74.744835) (xy 303.037107 -74.662529) (xy 303.025053 -74.578698)
			(xy 303.021024 -74.4941) (xy 268.697852 -74.4941) (xy 268.690332 -74.502779) (xy 268.629034 -74.561227)
			(xy 268.562458 -74.613583) (xy 268.491206 -74.659373) (xy 268.415925 -74.698184) (xy 268.337295 -74.729663)
			(xy 268.256028 -74.753524) (xy 268.172862 -74.769553) (xy 268.088548 -74.777604) (xy 268.0462 -74.778108)
			(xy 268.045438 -74.778108) (xy 268.007091 -74.777699) (xy 267.930683 -74.771067) (xy 267.855132 -74.757875)
			(xy 267.780998 -74.738222) (xy 267.708834 -74.712253) (xy 267.673836 -74.696574) (xy 267.663563 -74.692434)
			(xy 267.641437 -74.692434) (xy 267.631164 -74.696574) (xy 267.596167 -74.712253) (xy 267.523997 -74.7382)
			(xy 267.449862 -74.757843) (xy 267.374313 -74.771037) (xy 267.297908 -74.777682) (xy 267.259562 -74.778108)
			(xy 267.2588 -74.778108) (xy 267.216452 -74.777604) (xy 267.132138 -74.769553) (xy 267.048972 -74.753524)
			(xy 266.967705 -74.729663) (xy 266.889075 -74.698184) (xy 266.813794 -74.659373) (xy 266.742542 -74.613583)
			(xy 266.675966 -74.561227) (xy 266.614668 -74.502779) (xy 266.559203 -74.438769) (xy 266.510074 -74.369777)
			(xy 266.467725 -74.296427) (xy 266.432541 -74.219384) (xy 266.404839 -74.139345) (xy 266.384871 -74.057036)
			(xy 266.372818 -73.973201) (xy 266.368788 -73.8886) (xy 265.204702 -73.8886) (xy 265.204702 -75.861361)
			(xy 297.179742 -75.861361) (xy 297.179742 -75.776639) (xy 297.187795 -75.692302) (xy 297.203829 -75.609112)
			(xy 297.227697 -75.527822) (xy 297.259185 -75.44917) (xy 297.298007 -75.373867) (xy 297.34381 -75.302595)
			(xy 297.396181 -75.235999) (xy 297.454646 -75.174684) (xy 297.518674 -75.119203) (xy 297.587686 -75.07006)
			(xy 297.661056 -75.0277) (xy 297.738121 -74.992505) (xy 297.818183 -74.964796) (xy 297.900516 -74.944822)
			(xy 297.984375 -74.932765) (xy 298.069 -74.928734) (xy 298.153625 -74.932765) (xy 298.237484 -74.944822)
			(xy 298.319817 -74.964796) (xy 298.399879 -74.992505) (xy 298.476944 -75.0277) (xy 298.550314 -75.07006)
			(xy 298.619326 -75.119203) (xy 298.683354 -75.174684) (xy 298.741819 -75.235999) (xy 298.79419 -75.302595)
			(xy 298.839993 -75.373867) (xy 298.878815 -75.44917) (xy 298.910303 -75.527822) (xy 298.934171 -75.609112)
			(xy 298.950205 -75.692302) (xy 298.958258 -75.776639) (xy 298.958762 -75.819) (xy 298.958258 -75.861361)
			(xy 298.950205 -75.945698) (xy 298.934171 -76.028888) (xy 298.910303 -76.110178) (xy 298.878815 -76.18883)
			(xy 298.839993 -76.264133) (xy 298.810167 -76.310544) (xy 305.873647 -76.310544) (xy 305.873647 -76.181404)
			(xy 305.881597 -76.052509) (xy 305.897467 -75.924349) (xy 305.921196 -75.797408) (xy 305.952695 -75.672169)
			(xy 305.991844 -75.549106) (xy 306.038495 -75.428687) (xy 306.09247 -75.311368) (xy 306.153565 -75.197594)
			(xy 306.221548 -75.087797) (xy 306.296162 -74.982394) (xy 306.377123 -74.881784) (xy 306.464123 -74.786349)
			(xy 306.556834 -74.69645) (xy 306.654904 -74.612429) (xy 306.757959 -74.534605) (xy 306.86561 -74.463273)
			(xy 306.977449 -74.398703) (xy 307.09305 -74.341141) (xy 307.211975 -74.290804) (xy 307.333774 -74.247884)
			(xy 307.457984 -74.212543) (xy 307.584133 -74.184916) (xy 307.711745 -74.165107) (xy 307.840334 -74.153191)
			(xy 307.969412 -74.149215) (xy 308.09849 -74.153191) (xy 308.227079 -74.165107) (xy 308.354691 -74.184916)
			(xy 308.48084 -74.212543) (xy 308.60505 -74.247884) (xy 308.726849 -74.290804) (xy 308.845774 -74.341141)
			(xy 308.961375 -74.398703) (xy 309.073214 -74.463273) (xy 309.180865 -74.534605) (xy 309.28392 -74.612429)
			(xy 309.38199 -74.69645) (xy 309.474701 -74.786349) (xy 309.561701 -74.881784) (xy 309.642662 -74.982394)
			(xy 309.717276 -75.087797) (xy 309.785259 -75.197594) (xy 309.846354 -75.311368) (xy 309.900329 -75.428687)
			(xy 309.94698 -75.549106) (xy 309.986129 -75.672169) (xy 310.017628 -75.797408) (xy 310.041357 -75.924349)
			(xy 310.057227 -76.052509) (xy 310.065177 -76.181404) (xy 310.065674 -76.245974) (xy 310.065177 -76.310544)
			(xy 310.057227 -76.439439) (xy 310.041357 -76.567599) (xy 310.017628 -76.69454) (xy 309.986129 -76.819779)
			(xy 309.94698 -76.942842) (xy 309.900329 -77.063261) (xy 309.846354 -77.18058) (xy 309.785259 -77.294354)
			(xy 309.717276 -77.404151) (xy 309.642662 -77.509554) (xy 309.561701 -77.610164) (xy 309.474701 -77.705599)
			(xy 309.38199 -77.795498) (xy 309.28392 -77.879519) (xy 309.180865 -77.957343) (xy 309.073214 -78.028675)
			(xy 308.961375 -78.093245) (xy 308.845774 -78.150807) (xy 308.726849 -78.201144) (xy 308.60505 -78.244064)
			(xy 308.48084 -78.279405) (xy 308.354691 -78.307032) (xy 308.227079 -78.326841) (xy 308.09849 -78.338757)
			(xy 307.969412 -78.342734) (xy 307.840334 -78.338757) (xy 307.711745 -78.326841) (xy 307.584133 -78.307032)
			(xy 307.457984 -78.279405) (xy 307.333774 -78.244064) (xy 307.211975 -78.201144) (xy 307.09305 -78.150807)
			(xy 306.977449 -78.093245) (xy 306.86561 -78.028675) (xy 306.757959 -77.957343) (xy 306.654904 -77.879519)
			(xy 306.556834 -77.795498) (xy 306.464123 -77.705599) (xy 306.377123 -77.610164) (xy 306.296162 -77.509554)
			(xy 306.221548 -77.404151) (xy 306.153565 -77.294354) (xy 306.09247 -77.18058) (xy 306.038495 -77.063261)
			(xy 305.991844 -76.942842) (xy 305.952695 -76.819779) (xy 305.921196 -76.69454) (xy 305.897467 -76.567599)
			(xy 305.881597 -76.439439) (xy 305.873647 -76.310544) (xy 298.810167 -76.310544) (xy 298.79419 -76.335405)
			(xy 298.741819 -76.402001) (xy 298.683354 -76.463316) (xy 298.619326 -76.518797) (xy 298.550314 -76.56794)
			(xy 298.476944 -76.6103) (xy 298.399879 -76.645495) (xy 298.319817 -76.673204) (xy 298.237484 -76.693178)
			(xy 298.153625 -76.705235) (xy 298.069 -76.709267) (xy 297.984375 -76.705235) (xy 297.900516 -76.693178)
			(xy 297.818183 -76.673204) (xy 297.738121 -76.645495) (xy 297.661056 -76.6103) (xy 297.587686 -76.56794)
			(xy 297.518674 -76.518797) (xy 297.454646 -76.463316) (xy 297.396181 -76.402001) (xy 297.34381 -76.335405)
			(xy 297.298007 -76.264133) (xy 297.259185 -76.18883) (xy 297.227697 -76.110178) (xy 297.203829 -76.028888)
			(xy 297.187795 -75.945698) (xy 297.179742 -75.861361) (xy 265.204702 -75.861361) (xy 265.204702 -78.1558)
			(xy 279.439887 -78.1558) (xy 279.443918 -78.071199) (xy 279.455971 -77.987365) (xy 279.475939 -77.905056)
			(xy 279.50364 -77.825017) (xy 279.538825 -77.747974) (xy 279.581173 -77.674625) (xy 279.630301 -77.605633)
			(xy 279.685766 -77.541623) (xy 279.747063 -77.483176) (xy 279.813639 -77.430819) (xy 279.88489 -77.385029)
			(xy 279.960171 -77.346218) (xy 280.038801 -77.314739) (xy 280.120067 -77.290877) (xy 280.203233 -77.274847)
			(xy 280.287546 -77.266796) (xy 280.329894 -77.266292) (xy 280.330402 -77.266292) (xy 280.376734 -77.2669)
			(xy 280.468892 -77.276571) (xy 280.559546 -77.295766) (xy 280.647715 -77.324277) (xy 280.69032 -77.342492)
			(xy 280.700262 -77.346298) (xy 280.721526 -77.346298) (xy 280.731468 -77.342492) (xy 280.774072 -77.324272)
			(xy 280.862239 -77.295754) (xy 280.952894 -77.276561) (xy 281.045054 -77.2669) (xy 281.091386 -77.266292)
			(xy 281.091894 -77.266292) (xy 281.134243 -77.26678) (xy 281.218559 -77.27483) (xy 281.301727 -77.290859)
			(xy 281.382995 -77.314721) (xy 281.461627 -77.3462) (xy 281.536911 -77.385011) (xy 281.608164 -77.430802)
			(xy 281.674742 -77.48316) (xy 281.736042 -77.541608) (xy 281.791508 -77.605619) (xy 281.840638 -77.674613)
			(xy 281.882988 -77.747964) (xy 281.918173 -77.825009) (xy 281.945875 -77.905049) (xy 281.965844 -77.98736)
			(xy 281.977898 -78.071197) (xy 281.981928 -78.1558) (xy 281.977898 -78.240403) (xy 281.965844 -78.32424)
			(xy 281.945875 -78.406551) (xy 281.918173 -78.486591) (xy 281.882988 -78.563636) (xy 281.840638 -78.636987)
			(xy 281.791508 -78.705981) (xy 281.736042 -78.769992) (xy 281.674742 -78.82844) (xy 281.608164 -78.880798)
			(xy 281.536911 -78.926589) (xy 281.461627 -78.9654) (xy 281.382995 -78.996879) (xy 281.301727 -79.020741)
			(xy 281.218559 -79.03677) (xy 281.134243 -79.04482) (xy 281.091894 -79.045308) (xy 281.091386 -79.045308)
			(xy 281.045054 -79.044704) (xy 280.952896 -79.035032) (xy 280.862242 -79.015836) (xy 280.774073 -78.987323)
			(xy 280.731468 -78.969108) (xy 280.721526 -78.965302) (xy 280.700262 -78.965302) (xy 280.69032 -78.969108)
			(xy 280.647718 -78.987332) (xy 280.55955 -79.015849) (xy 280.468894 -79.035041) (xy 280.376734 -79.0447)
			(xy 280.330402 -79.045308) (xy 280.329894 -79.045308) (xy 280.287546 -79.044804) (xy 280.203233 -79.036753)
			(xy 280.120067 -79.020723) (xy 280.038801 -78.996861) (xy 279.960171 -78.965382) (xy 279.88489 -78.926571)
			(xy 279.813639 -78.880781) (xy 279.747063 -78.828424) (xy 279.685766 -78.769977) (xy 279.630301 -78.705967)
			(xy 279.581173 -78.636975) (xy 279.538825 -78.563626) (xy 279.50364 -78.486583) (xy 279.475939 -78.406544)
			(xy 279.455971 -78.324235) (xy 279.443918 -78.240401) (xy 279.439887 -78.1558) (xy 265.204702 -78.1558)
			(xy 265.204702 -80.391) (xy 297.102788 -80.391) (xy 297.106818 -80.306399) (xy 297.118871 -80.222564)
			(xy 297.138839 -80.140255) (xy 297.166541 -80.060216) (xy 297.201725 -79.983173) (xy 297.244074 -79.909823)
			(xy 297.293203 -79.840831) (xy 297.348668 -79.776821) (xy 297.409966 -79.718373) (xy 297.476542 -79.666017)
			(xy 297.547794 -79.620227) (xy 297.623075 -79.581416) (xy 297.701705 -79.549937) (xy 297.782972 -79.526076)
			(xy 297.866138 -79.510047) (xy 297.950452 -79.501996) (xy 297.9928 -79.501492) (xy 297.993308 -79.501492)
			(xy 298.03964 -79.502098) (xy 298.131798 -79.511769) (xy 298.222452 -79.530965) (xy 298.310621 -79.559477)
			(xy 298.353226 -79.577692) (xy 298.363168 -79.581498) (xy 298.384432 -79.581498) (xy 298.394374 -79.577692)
			(xy 298.436977 -79.55947) (xy 298.525144 -79.530952) (xy 298.6158 -79.51176) (xy 298.70796 -79.5021)
			(xy 298.754292 -79.501492) (xy 298.7548 -79.501492) (xy 298.797148 -79.501996) (xy 298.881462 -79.510047)
			(xy 298.964628 -79.526076) (xy 299.045895 -79.549937) (xy 299.124525 -79.581416) (xy 299.199806 -79.620227)
			(xy 299.271058 -79.666017) (xy 299.337634 -79.718373) (xy 299.398932 -79.776821) (xy 299.450937 -79.836838)
			(xy 303.180186 -79.836838) (xy 303.182815 -79.753015) (xy 303.19332 -79.66981) (xy 303.211608 -79.587964)
			(xy 303.237517 -79.508202) (xy 303.270817 -79.431231) (xy 303.311212 -79.357736) (xy 303.358343 -79.288368)
			(xy 303.411794 -79.223743) (xy 303.471088 -79.164435) (xy 303.5357 -79.110969) (xy 303.605057 -79.063821)
			(xy 303.678543 -79.023409) (xy 303.755505 -78.990091) (xy 303.835261 -78.964164) (xy 303.917103 -78.945856)
			(xy 304.000305 -78.935331) (xy 304.084128 -78.932683) (xy 304.167828 -78.937934) (xy 304.250663 -78.951038)
			(xy 304.331897 -78.971879) (xy 304.410809 -79.000271) (xy 304.4867 -79.035964) (xy 304.558894 -79.078639)
			(xy 304.626753 -79.127919) (xy 304.689673 -79.183366) (xy 304.747097 -79.244487) (xy 304.798514 -79.310741)
			(xy 304.843468 -79.38154) (xy 304.881561 -79.456254) (xy 304.912453 -79.534222) (xy 304.935872 -79.61475)
			(xy 304.951609 -79.697125) (xy 304.959525 -79.780616) (xy 304.96002 -79.822548) (xy 304.96002 -79.823056)
			(xy 304.959492 -79.865875) (xy 304.951224 -79.951114) (xy 304.94351 -79.993236) (xy 304.941789 -80.004521)
			(xy 304.94747 -80.026607) (xy 304.954432 -80.035654) (xy 305.012852 -80.104996) (xy 305.03368 -80.114394)
			(xy 305.044856 -80.11414) (xy 305.045872 -80.11414) (xy 305.063398 -80.11414) (xy 305.105333 -80.11462)
			(xy 305.18883 -80.122512) (xy 305.271215 -80.138226) (xy 305.351755 -80.161624) (xy 305.429736 -80.192496)
			(xy 305.504465 -80.23057) (xy 305.57528 -80.275507) (xy 305.641553 -80.326908) (xy 305.702694 -80.384318)
			(xy 305.758161 -80.447227) (xy 305.807463 -80.515076) (xy 305.85016 -80.587263) (xy 305.885876 -80.663148)
			(xy 305.914292 -80.742058) (xy 305.935156 -80.823291) (xy 305.948283 -80.906127) (xy 305.953557 -80.98983)
			(xy 305.950931 -81.073659) (xy 305.940428 -81.156868) (xy 305.922142 -81.23872) (xy 305.896234 -81.318488)
			(xy 305.862935 -81.395464) (xy 305.82254 -81.468965) (xy 305.775407 -81.538338) (xy 305.721955 -81.602968)
			(xy 305.662659 -81.662282) (xy 305.598045 -81.715752) (xy 305.528685 -81.762905) (xy 305.455196 -81.803321)
			(xy 305.37823 -81.836643) (xy 305.298469 -81.862574) (xy 305.216623 -81.880884) (xy 305.133416 -81.891411)
			(xy 305.049589 -81.894061) (xy 304.965883 -81.888812) (xy 304.883044 -81.875708) (xy 304.801804 -81.854868)
			(xy 304.722887 -81.826475) (xy 304.646992 -81.790781) (xy 304.574792 -81.748104) (xy 304.506928 -81.698823)
			(xy 304.444004 -81.643373) (xy 304.386576 -81.582249) (xy 304.335155 -81.515992) (xy 304.290198 -81.445189)
			(xy 304.252102 -81.370471) (xy 304.221207 -81.292499) (xy 304.197787 -81.211966) (xy 304.182048 -81.129586)
			(xy 304.174132 -81.046091) (xy 304.173636 -81.004156) (xy 304.173636 -81.003648) (xy 304.174164 -80.960829)
			(xy 304.182432 -80.87559) (xy 304.190146 -80.833468) (xy 304.191851 -80.822182) (xy 304.186179 -80.800099)
			(xy 304.179224 -80.79105) (xy 304.120804 -80.721708) (xy 304.099976 -80.71231) (xy 304.0888 -80.712564)
			(xy 304.087784 -80.712564) (xy 304.070258 -80.712564) (xy 304.028326 -80.712034) (xy 303.944833 -80.704139)
			(xy 303.862455 -80.688421) (xy 303.78192 -80.665021) (xy 303.703946 -80.634147) (xy 303.629222 -80.596072)
			(xy 303.558413 -80.551135) (xy 303.492147 -80.499733) (xy 303.431012 -80.442324) (xy 303.37555 -80.379417)
			(xy 303.326255 -80.31157) (xy 303.283562 -80.239385) (xy 303.247852 -80.163503) (xy 303.219441 -80.084598)
			(xy 303.198581 -80.003369) (xy 303.185457 -79.920537) (xy 303.180186 -79.836838) (xy 299.450937 -79.836838)
			(xy 299.454397 -79.840831) (xy 299.503526 -79.909823) (xy 299.545875 -79.983173) (xy 299.581059 -80.060216)
			(xy 299.608761 -80.140255) (xy 299.628729 -80.222564) (xy 299.640782 -80.306399) (xy 299.644813 -80.391)
			(xy 299.640782 -80.475601) (xy 299.628729 -80.559436) (xy 299.608761 -80.641745) (xy 299.581059 -80.721784)
			(xy 299.545875 -80.798827) (xy 299.503526 -80.872177) (xy 299.454397 -80.941169) (xy 299.398932 -81.005179)
			(xy 299.337634 -81.063627) (xy 299.271058 -81.115983) (xy 299.199806 -81.161773) (xy 299.124525 -81.200584)
			(xy 299.045895 -81.232063) (xy 298.964628 -81.255924) (xy 298.881462 -81.271953) (xy 298.797148 -81.280004)
			(xy 298.7548 -81.280508) (xy 298.754292 -81.280508) (xy 298.70796 -81.279902) (xy 298.615802 -81.270231)
			(xy 298.525148 -81.251035) (xy 298.436979 -81.222523) (xy 298.394374 -81.204308) (xy 298.384432 -81.200502)
			(xy 298.363168 -81.200502) (xy 298.353226 -81.204308) (xy 298.310623 -81.22253) (xy 298.222456 -81.251048)
			(xy 298.1318 -81.27024) (xy 298.03964 -81.2799) (xy 297.993308 -81.280508) (xy 297.9928 -81.280508)
			(xy 297.950452 -81.280004) (xy 297.866138 -81.271953) (xy 297.782972 -81.255924) (xy 297.701705 -81.232063)
			(xy 297.623075 -81.200584) (xy 297.547794 -81.161773) (xy 297.476542 -81.115983) (xy 297.409966 -81.063627)
			(xy 297.348668 -81.005179) (xy 297.293203 -80.941169) (xy 297.244074 -80.872177) (xy 297.201725 -80.798827)
			(xy 297.166541 -80.721784) (xy 297.138839 -80.641745) (xy 297.118871 -80.559436) (xy 297.106818 -80.475601)
			(xy 297.102788 -80.391) (xy 265.204702 -80.391) (xy 265.204702 -82.52968) (xy 265.204956 -82.534506)
			(xy 265.206168 -82.543264) (xy 265.213698 -82.559246) (xy 265.219688 -82.565748) (xy 266.020042 -83.366102)
			(xy 266.026506 -83.372147) (xy 266.042508 -83.379683) (xy 266.051284 -83.380834) (xy 266.053824 -83.381088)
			(xy 279.229566 -83.381088) (xy 279.262827 -83.381607) (xy 279.32878 -83.39029) (xy 279.393033 -83.407512)
			(xy 279.454488 -83.432978) (xy 279.51209 -83.466251) (xy 279.564854 -83.506762) (xy 279.588722 -83.529932)
			(xy 280.012394 -83.953604) (xy 280.035555 -83.977482) (xy 280.07607 -84.030243) (xy 280.109349 -84.087843)
			(xy 280.134821 -84.149295) (xy 280.152051 -84.213547) (xy 280.160742 -84.279499) (xy 280.161238 -84.31276)
			(xy 280.161238 -87.84336) (xy 280.160719 -87.876621) (xy 280.152037 -87.942575) (xy 280.134817 -88.006829)
			(xy 280.109353 -88.068285) (xy 280.076081 -88.125889) (xy 280.035572 -88.178655) (xy 280.012394 -88.202516)
			(xy 279.212548 -89.002362) (xy 279.18867 -89.025522) (xy 279.135909 -89.066034) (xy 279.078308 -89.09931)
			(xy 279.016856 -89.124778) (xy 278.952604 -89.142003) (xy 278.886652 -89.150689) (xy 278.853392 -89.151206)
			(xy 263.66343 -89.151206) (xy 263.630169 -89.150687) (xy 263.564217 -89.142003) (xy 263.499964 -89.124781)
			(xy 263.43851 -89.099314) (xy 263.380908 -89.066041) (xy 263.328145 -89.025529) (xy 263.304274 -89.002362)
			(xy 260.154674 -85.852762) (xy 260.131516 -85.828883) (xy 260.091007 -85.77612) (xy 260.057734 -85.71852)
			(xy 260.032268 -85.657067) (xy 260.015044 -85.592816) (xy 260.006357 -85.526866) (xy 260.00583 -85.493606)
			(xy 260.00583 -77.754988) (xy 260.005472 -77.74695) (xy 260.000433 -77.731679) (xy 259.995924 -77.725016)
			(xy 259.993892 -77.722222) (xy 259.992876 -77.720952) (xy 259.964553 -77.686554) (xy 259.914172 -77.613054)
			(xy 259.871393 -77.534885) (xy 259.836644 -77.45283) (xy 259.810273 -77.367712) (xy 259.792546 -77.280384)
			(xy 259.783639 -77.191721) (xy 259.783072 -77.147166) (xy 259.783618 -77.102611) (xy 259.792531 -77.013949)
			(xy 259.810265 -76.926621) (xy 259.836641 -76.841505) (xy 259.871395 -76.759452) (xy 259.91418 -76.681286)
			(xy 259.964566 -76.607789) (xy 259.992876 -76.57338) (xy 259.993892 -76.57211) (xy 259.995924 -76.569316)
			(xy 260.000486 -76.562677) (xy 260.005547 -76.547394) (xy 260.00583 -76.539344) (xy 260.00583 -54.955186)
			(xy 260.005666 -54.949667) (xy 260.003236 -54.9389) (xy 260.001004 -54.93385) (xy 259.987796 -54.905402)
			(xy 259.979668 -54.898544) (xy 259.959346 -54.880341) (xy 259.923599 -54.839127) (xy 259.894086 -54.793243)
			(xy 259.871408 -54.743623) (xy 259.856027 -54.691279) (xy 259.848258 -54.637278) (xy 259.848258 -54.582722)
			(xy 259.856027 -54.528721) (xy 259.871408 -54.476377) (xy 259.894086 -54.426757) (xy 259.923599 -54.380873)
			(xy 259.959346 -54.339659) (xy 259.979668 -54.321456) (xy 259.987796 -54.314598) (xy 260.001004 -54.28615)
			(xy 260.003211 -54.281092) (xy 260.005642 -54.27033) (xy 260.00583 -54.264814) (xy 260.00583 -49.16297)
			(xy 260.005696 -49.158079) (xy 260.003782 -49.148484) (xy 260.00202 -49.14392) (xy 259.99821 -49.134268)
			(xy 259.990844 -49.127156) (xy 258.786122 -47.922434) (xy 258.785614 -47.921926) (xy 258.780534 -47.916592)
			(xy 258.767326 -47.90948) (xy 258.752086 -47.906432) (xy 258.737608 -47.907702) (xy 258.730496 -47.91075)
			(xy 258.721479 -47.914973) (xy 258.707347 -47.928969) (xy 258.699607 -47.947292) (xy 258.699 -47.957232)
			(xy 258.699 -50.894996) (xy 258.698479 -50.928256) (xy 258.689792 -50.994207) (xy 258.672567 -51.058458)
			(xy 258.647098 -51.119909) (xy 258.613823 -51.177508) (xy 258.57331 -51.230269) (xy 258.550156 -51.254152)
			(xy 257.878072 -51.926236) (xy 257.854193 -51.949394) (xy 257.80143 -51.989903) (xy 257.74383 -52.023177)
			(xy 257.682378 -52.048644) (xy 257.618126 -52.065869) (xy 257.552176 -52.074557) (xy 257.518916 -52.07508)
			(xy 247.302782 -52.07508) (xy 247.269523 -52.074557) (xy 247.203574 -52.065868) (xy 247.139325 -52.04864)
			(xy 247.077876 -52.023169) (xy 247.02028 -51.989891) (xy 246.967523 -51.949375) (xy 246.943626 -51.926236)
			(xy 246.398796 -51.381406) (xy 246.375635 -51.357528) (xy 246.33512 -51.304767) (xy 246.30184 -51.247167)
			(xy 246.276368 -51.185715) (xy 246.259137 -51.121463) (xy 246.250444 -51.055511) (xy 246.249952 -51.02225)
			(xy 246.249952 -46.654466) (xy 246.250475 -46.621207) (xy 246.259166 -46.555258) (xy 246.276394 -46.491009)
			(xy 246.301864 -46.429559) (xy 246.33514 -46.371961) (xy 246.375652 -46.319202) (xy 246.398796 -46.29531)
			(xy 249.172984 -43.521122) (xy 249.173492 -43.520614) (xy 249.178826 -43.515534) (xy 249.185938 -43.502326)
			(xy 249.188986 -43.487086) (xy 249.187716 -43.472608) (xy 249.184668 -43.465496) (xy 249.180446 -43.456477)
			(xy 249.16645 -43.44234) (xy 249.148127 -43.434594) (xy 249.138186 -43.434) (xy 248.148094 -43.434)
			(xy 248.143202 -43.434132) (xy 248.133607 -43.436042) (xy 248.129044 -43.43781) (xy 248.119392 -43.44162)
			(xy 248.11228 -43.448986) (xy 243.32311 -48.238156) (xy 243.299231 -48.261315) (xy 243.246469 -48.301827)
			(xy 243.188869 -48.335103) (xy 243.127417 -48.360574) (xy 243.063166 -48.377803) (xy 242.997215 -48.386496)
			(xy 242.963954 -48.387) (xy 230.251 -48.387) (xy 230.21774 -48.386479) (xy 230.15179 -48.377791)
			(xy 230.087539 -48.360566) (xy 230.026088 -48.335097) (xy 229.968489 -48.301821) (xy 229.915729 -48.261308)
			(xy 229.891844 -48.238156) (xy 229.002844 -47.349156) (xy 228.979688 -47.325276) (xy 228.939182 -47.272512)
			(xy 228.905911 -47.214911) (xy 228.880447 -47.15346) (xy 228.863225 -47.089209) (xy 228.854539 -47.023259)
			(xy 228.854 -46.99) (xy 228.854 -30.226) (xy 228.854521 -30.19274) (xy 228.863209 -30.12679) (xy 228.880434 -30.062539)
			(xy 228.905903 -30.001088) (xy 228.939179 -29.943489) (xy 228.979692 -29.890729) (xy 229.002844 -29.866844)
			(xy 230.780844 -28.088844) (xy 230.804724 -28.065688) (xy 230.857488 -28.025182) (xy 230.915089 -27.991911)
			(xy 230.97654 -27.966447) (xy 231.040791 -27.949225) (xy 231.106741 -27.940539) (xy 231.14 -27.94)
			(xy 278.156924 -27.94) (xy 278.16175 -27.939746) (xy 278.170504 -27.938527) (xy 278.186477 -27.930988)
			(xy 278.192992 -27.925014) (xy 279.131014 -26.986992) (xy 279.137062 -26.980529) (xy 279.144607 -26.964528)
			(xy 279.145746 -26.95575) (xy 279.146 -26.95321) (xy 279.146 -16.146018) (xy 279.14652 -16.112758)
			(xy 279.155205 -16.046806) (xy 279.172429 -15.982554) (xy 279.197896 -15.921101) (xy 279.231171 -15.863501)
			(xy 279.271684 -15.810739) (xy 279.294844 -15.786862) (xy 282.994862 -12.086844) (xy 283.018742 -12.063689)
			(xy 283.071506 -12.023184) (xy 283.129108 -11.989916) (xy 283.190559 -11.964454) (xy 283.25481 -11.947234)
			(xy 283.320759 -11.938551) (xy 283.354018 -11.938) (xy 323.977 -11.938) (xy 323.997574 -11.938508)
			(xy 324.007988 -11.939016) (xy 324.017894 -11.935206) (xy 324.022518 -11.933289) (xy 324.030959 -11.927911)
			(xy 324.034658 -11.924538) (xy 324.088252 -11.873738) (xy 324.095366 -11.866312) (xy 324.103477 -11.847434)
			(xy 324.104 -11.837162) (xy 324.104 -10.336784) (xy 324.103867 -10.331893) (xy 324.101955 -10.322297)
			(xy 324.10019 -10.317734) (xy 324.09638 -10.308082) (xy 324.089014 -10.30097) (xy 322.94703 -9.158986)
			(xy 322.941442 -9.15416) (xy 322.9347 -9.149497) (xy 322.919154 -9.144326) (xy 322.910962 -9.144)
			(xy 258.794758 -9.144) (xy 258.786722 -9.144364) (xy 258.771458 -9.149412) (xy 258.764786 -9.153906)
			(xy 258.738426 -9.172834) (xy 258.681815 -9.204563) (xy 258.621624 -9.228823) (xy 258.558833 -9.245221)
			(xy 258.494466 -9.253488) (xy 258.462018 -9.253982) (xy 123.3932 -9.253982) (xy 123.383191 -9.25447)
			(xy 123.364696 -9.262129) (xy 123.350539 -9.276281) (xy 123.342873 -9.294773) (xy 123.3424 -9.304782)
			(xy 123.3424 -11.836908) (xy 123.342825 -11.846978) (xy 123.350541 -11.86558) (xy 123.357386 -11.872976)
			(xy 123.35764 -11.87323) (xy 123.411234 -11.924538) (xy 123.418713 -11.931174) (xy 123.437305 -11.938491)
			(xy 123.447302 -11.938762) (xy 123.468384 -11.938254) (xy 123.468638 -11.938) (xy 156.980382 -11.938)
			(xy 157.013642 -11.93852) (xy 157.079594 -11.947205) (xy 157.143846 -11.964429) (xy 157.205299 -11.989896)
			(xy 157.262899 -12.023171) (xy 157.315661 -12.063684) (xy 157.339538 -12.086844) (xy 161.039556 -15.786862)
			(xy 161.062711 -15.810742) (xy 161.103216 -15.863506) (xy 161.136484 -15.921108) (xy 161.161946 -15.982559)
			(xy 161.179166 -16.04681) (xy 161.187849 -16.112759) (xy 161.1884 -16.146018) (xy 161.1884 -22.560114)
			(xy 205.177635 -22.560114) (xy 205.177635 -22.389758) (xy 205.18562 -22.21959) (xy 205.201572 -22.049983)
			(xy 205.225457 -21.881311) (xy 205.257221 -21.713943) (xy 205.296796 -21.548248) (xy 205.344093 -21.38459)
			(xy 205.39901 -21.223329) (xy 205.461425 -21.064819) (xy 205.531201 -20.909409) (xy 205.608184 -20.757441)
			(xy 205.692206 -20.609247) (xy 205.783082 -20.465155) (xy 205.880612 -20.325481) (xy 205.984582 -20.190532)
			(xy 206.094763 -20.060604) (xy 206.210912 -19.935984) (xy 206.332776 -19.816945) (xy 206.460084 -19.703749)
			(xy 206.592559 -19.596644) (xy 206.729909 -19.495867) (xy 206.871831 -19.401638) (xy 207.018013 -19.314165)
			(xy 207.168136 -19.23364) (xy 207.321867 -19.16024) (xy 207.47887 -19.094126) (xy 207.6388 -19.035444)
			(xy 207.801304 -18.984323) (xy 207.966025 -18.940875) (xy 208.132603 -18.905196) (xy 208.300669 -18.877364)
			(xy 208.469855 -18.85744) (xy 208.639789 -18.845468) (xy 208.810098 -18.841475) (xy 208.980407 -18.845468)
			(xy 209.150341 -18.85744) (xy 209.319527 -18.877364) (xy 209.487593 -18.905196) (xy 209.654171 -18.940875)
			(xy 209.818892 -18.984323) (xy 209.981396 -19.035444) (xy 210.141326 -19.094126) (xy 210.298329 -19.16024)
			(xy 210.45206 -19.23364) (xy 210.602183 -19.314165) (xy 210.748365 -19.401638) (xy 210.890287 -19.495867)
			(xy 211.027637 -19.596644) (xy 211.160112 -19.703749) (xy 211.28742 -19.816945) (xy 211.409284 -19.935984)
			(xy 211.525433 -20.060604) (xy 211.635614 -20.190532) (xy 211.739584 -20.325481) (xy 211.837114 -20.465155)
			(xy 211.92799 -20.609247) (xy 212.012012 -20.757441) (xy 212.088995 -20.909409) (xy 212.158771 -21.064819)
			(xy 212.221186 -21.223329) (xy 212.276103 -21.38459) (xy 212.3234 -21.548248) (xy 212.362975 -21.713943)
			(xy 212.394739 -21.881311) (xy 212.418624 -22.049983) (xy 212.434576 -22.21959) (xy 212.442561 -22.389758)
			(xy 212.44306 -22.474936) (xy 212.442561 -22.560114) (xy 235.177575 -22.560114) (xy 235.177575 -22.389758)
			(xy 235.18556 -22.21959) (xy 235.201512 -22.049983) (xy 235.225397 -21.881311) (xy 235.257161 -21.713943)
			(xy 235.296736 -21.548248) (xy 235.344033 -21.38459) (xy 235.39895 -21.223329) (xy 235.461365 -21.064819)
			(xy 235.531141 -20.909409) (xy 235.608124 -20.757441) (xy 235.692146 -20.609247) (xy 235.783022 -20.465155)
			(xy 235.880552 -20.325481) (xy 235.984522 -20.190532) (xy 236.094703 -20.060604) (xy 236.210852 -19.935984)
			(xy 236.332716 -19.816945) (xy 236.460024 -19.703749) (xy 236.592499 -19.596644) (xy 236.729849 -19.495867)
			(xy 236.871771 -19.401638) (xy 237.017953 -19.314165) (xy 237.168076 -19.23364) (xy 237.321807 -19.16024)
			(xy 237.47881 -19.094126) (xy 237.63874 -19.035444) (xy 237.801244 -18.984323) (xy 237.965965 -18.940875)
			(xy 238.132543 -18.905196) (xy 238.300609 -18.877364) (xy 238.469795 -18.85744) (xy 238.639729 -18.845468)
			(xy 238.810038 -18.841475) (xy 238.980347 -18.845468) (xy 239.150281 -18.85744) (xy 239.319467 -18.877364)
			(xy 239.487533 -18.905196) (xy 239.654111 -18.940875) (xy 239.818832 -18.984323) (xy 239.981336 -19.035444)
			(xy 240.141266 -19.094126) (xy 240.298269 -19.16024) (xy 240.452 -19.23364) (xy 240.602123 -19.314165)
			(xy 240.748305 -19.401638) (xy 240.890227 -19.495867) (xy 241.027577 -19.596644) (xy 241.160052 -19.703749)
			(xy 241.28736 -19.816945) (xy 241.409224 -19.935984) (xy 241.525373 -20.060604) (xy 241.635554 -20.190532)
			(xy 241.739524 -20.325481) (xy 241.837054 -20.465155) (xy 241.92793 -20.609247) (xy 242.011952 -20.757441)
			(xy 242.088935 -20.909409) (xy 242.158711 -21.064819) (xy 242.221126 -21.223329) (xy 242.276043 -21.38459)
			(xy 242.32334 -21.548248) (xy 242.362915 -21.713943) (xy 242.394679 -21.881311) (xy 242.418564 -22.049983)
			(xy 242.434516 -22.21959) (xy 242.442501 -22.389758) (xy 242.443 -22.474936) (xy 242.442501 -22.560114)
			(xy 242.434516 -22.730282) (xy 242.418564 -22.899889) (xy 242.394679 -23.068561) (xy 242.362915 -23.235929)
			(xy 242.32334 -23.401624) (xy 242.276043 -23.565282) (xy 242.221126 -23.726543) (xy 242.158711 -23.885053)
			(xy 242.088935 -24.040463) (xy 242.011952 -24.192431) (xy 241.92793 -24.340625) (xy 241.837054 -24.484717)
			(xy 241.739524 -24.624391) (xy 241.635554 -24.75934) (xy 241.525373 -24.889268) (xy 241.409224 -25.013888)
			(xy 241.28736 -25.132927) (xy 241.160052 -25.246123) (xy 241.027577 -25.353228) (xy 240.890227 -25.454005)
			(xy 240.748305 -25.548234) (xy 240.602123 -25.635707) (xy 240.452 -25.716232) (xy 240.298269 -25.789632)
			(xy 240.141266 -25.855746) (xy 239.981336 -25.914428) (xy 239.818832 -25.965549) (xy 239.654111 -26.008997)
			(xy 239.487533 -26.044676) (xy 239.319467 -26.072508) (xy 239.150281 -26.092432) (xy 238.980347 -26.104404)
			(xy 238.810038 -26.108398) (xy 238.639729 -26.104404) (xy 238.469795 -26.092432) (xy 238.300609 -26.072508)
			(xy 238.132543 -26.044676) (xy 237.965965 -26.008997) (xy 237.801244 -25.965549) (xy 237.63874 -25.914428)
			(xy 237.47881 -25.855746) (xy 237.321807 -25.789632) (xy 237.168076 -25.716232) (xy 237.017953 -25.635707)
			(xy 236.871771 -25.548234) (xy 236.729849 -25.454005) (xy 236.592499 -25.353228) (xy 236.460024 -25.246123)
			(xy 236.332716 -25.132927) (xy 236.210852 -25.013888) (xy 236.094703 -24.889268) (xy 235.984522 -24.75934)
			(xy 235.880552 -24.624391) (xy 235.783022 -24.484717) (xy 235.692146 -24.340625) (xy 235.608124 -24.192431)
			(xy 235.531141 -24.040463) (xy 235.461365 -23.885053) (xy 235.39895 -23.726543) (xy 235.344033 -23.565282)
			(xy 235.296736 -23.401624) (xy 235.257161 -23.235929) (xy 235.225397 -23.068561) (xy 235.201512 -22.899889)
			(xy 235.18556 -22.730282) (xy 235.177575 -22.560114) (xy 212.442561 -22.560114) (xy 212.434576 -22.730282)
			(xy 212.418624 -22.899889) (xy 212.394739 -23.068561) (xy 212.362975 -23.235929) (xy 212.3234 -23.401624)
			(xy 212.276103 -23.565282) (xy 212.221186 -23.726543) (xy 212.158771 -23.885053) (xy 212.088995 -24.040463)
			(xy 212.012012 -24.192431) (xy 211.92799 -24.340625) (xy 211.837114 -24.484717) (xy 211.739584 -24.624391)
			(xy 211.635614 -24.75934) (xy 211.525433 -24.889268) (xy 211.409284 -25.013888) (xy 211.28742 -25.132927)
			(xy 211.160112 -25.246123) (xy 211.027637 -25.353228) (xy 210.890287 -25.454005) (xy 210.748365 -25.548234)
			(xy 210.602183 -25.635707) (xy 210.45206 -25.716232) (xy 210.298329 -25.789632) (xy 210.141326 -25.855746)
			(xy 209.981396 -25.914428) (xy 209.818892 -25.965549) (xy 209.654171 -26.008997) (xy 209.487593 -26.044676)
			(xy 209.319527 -26.072508) (xy 209.150341 -26.092432) (xy 208.980407 -26.104404) (xy 208.810098 -26.108398)
			(xy 208.639789 -26.104404) (xy 208.469855 -26.092432) (xy 208.300669 -26.072508) (xy 208.132603 -26.044676)
			(xy 207.966025 -26.008997) (xy 207.801304 -25.965549) (xy 207.6388 -25.914428) (xy 207.47887 -25.855746)
			(xy 207.321867 -25.789632) (xy 207.168136 -25.716232) (xy 207.018013 -25.635707) (xy 206.871831 -25.548234)
			(xy 206.729909 -25.454005) (xy 206.592559 -25.353228) (xy 206.460084 -25.246123) (xy 206.332776 -25.132927)
			(xy 206.210912 -25.013888) (xy 206.094763 -24.889268) (xy 205.984582 -24.75934) (xy 205.880612 -24.624391)
			(xy 205.783082 -24.484717) (xy 205.692206 -24.340625) (xy 205.608184 -24.192431) (xy 205.531201 -24.040463)
			(xy 205.461425 -23.885053) (xy 205.39901 -23.726543) (xy 205.344093 -23.565282) (xy 205.296796 -23.401624)
			(xy 205.257221 -23.235929) (xy 205.225457 -23.068561) (xy 205.201572 -22.899889) (xy 205.18562 -22.730282)
			(xy 205.177635 -22.560114) (xy 161.1884 -22.560114) (xy 161.1884 -26.950924) (xy 161.188654 -26.95575)
			(xy 161.189873 -26.964504) (xy 161.197412 -26.980477) (xy 161.203386 -26.986992) (xy 162.141408 -27.925014)
			(xy 162.147871 -27.931062) (xy 162.163872 -27.938607) (xy 162.17265 -27.939746) (xy 162.17519 -27.94)
			(xy 209.1944 -27.94) (xy 209.22766 -27.940521) (xy 209.29361 -27.949209) (xy 209.357861 -27.966434)
			(xy 209.419312 -27.991903) (xy 209.476911 -28.025179) (xy 209.529671 -28.065692) (xy 209.553556 -28.088844)
			(xy 211.331556 -29.866844) (xy 211.354712 -29.890724) (xy 211.395218 -29.943488) (xy 211.428489 -30.001089)
			(xy 211.453953 -30.06254) (xy 211.471175 -30.126791) (xy 211.479861 -30.192741) (xy 211.4804 -30.226)
			(xy 211.4804 -46.99) (xy 211.479879 -47.02326) (xy 211.471191 -47.08921) (xy 211.453966 -47.153461)
			(xy 211.428497 -47.214912) (xy 211.395221 -47.272511) (xy 211.354708 -47.325271) (xy 211.331556 -47.349156)
			(xy 210.442556 -48.238156) (xy 210.418676 -48.261312) (xy 210.365912 -48.301818) (xy 210.308311 -48.335089)
			(xy 210.24686 -48.360553) (xy 210.182609 -48.377775) (xy 210.116659 -48.386461) (xy 210.0834 -48.387)
			(xy 197.797166 -48.387) (xy 197.763907 -48.386476) (xy 197.697959 -48.377785) (xy 197.633711 -48.360556)
			(xy 197.572262 -48.335084) (xy 197.514667 -48.301806) (xy 197.461911 -48.261291) (xy 197.43801 -48.238156)
			(xy 191.552068 -42.352214) (xy 191.54648 -42.347388) (xy 191.53974 -42.342717) (xy 191.524194 -42.337532)
			(xy 191.516 -42.337228) (xy 190.211202 -42.337228) (xy 190.201102 -42.338272) (xy 190.182897 -42.347223)
			(xy 190.169581 -42.362529) (xy 190.16599 -42.372026) (xy 190.13551 -42.463466) (xy 190.134383 -42.467178)
			(xy 190.13311 -42.474829) (xy 190.13297 -42.478706) (xy 190.132716 -42.486834) (xy 190.135256 -42.494454)
			(xy 190.137542 -42.502074) (xy 190.146686 -42.515028) (xy 190.15329 -42.520108) (xy 190.16746 -42.530951)
			(xy 190.19441 -42.55434) (xy 190.207138 -42.566844) (xy 193.935604 -46.29531) (xy 193.958764 -46.319188)
			(xy 193.999278 -46.37195) (xy 194.032555 -46.42955) (xy 194.058026 -46.491002) (xy 194.075255 -46.555254)
			(xy 194.083946 -46.621205) (xy 194.084448 -46.654466) (xy 194.084448 -51.02225) (xy 194.084017 -51.049936)
			(xy 207.409803 -51.049936) (xy 207.413813 -50.944033) (xy 207.425821 -50.838737) (xy 207.445758 -50.734651)
			(xy 207.47351 -50.632371) (xy 207.508918 -50.532482) (xy 207.551779 -50.435558) (xy 207.601847 -50.342152)
			(xy 207.658837 -50.252801) (xy 207.72242 -50.168015) (xy 207.792234 -50.088281) (xy 207.867878 -50.014056)
			(xy 207.948918 -49.945763) (xy 208.034892 -49.883796) (xy 208.125306 -49.828508) (xy 208.219642 -49.780216)
			(xy 208.317361 -49.739197) (xy 208.417901 -49.705686) (xy 208.520689 -49.679874) (xy 208.625133 -49.66191)
			(xy 208.730638 -49.651897) (xy 208.836597 -49.649891) (xy 208.942405 -49.655905) (xy 209.047455 -49.669904)
			(xy 209.151145 -49.691807) (xy 209.252882 -49.72149) (xy 209.352083 -49.758781) (xy 209.448179 -49.803469)
			(xy 209.54062 -49.855296) (xy 209.628877 -49.913966) (xy 209.712444 -49.979143) (xy 209.790843 -50.050453)
			(xy 209.863624 -50.127487) (xy 209.93037 -50.209806) (xy 209.9907 -50.296937) (xy 210.044267 -50.388381)
			(xy 210.090765 -50.483614) (xy 210.129927 -50.582091) (xy 210.16153 -50.683248) (xy 210.185391 -50.786506)
			(xy 210.201376 -50.891272) (xy 210.209391 -50.996947) (xy 210.209892 -51.049936) (xy 237.409743 -51.049936)
			(xy 237.413753 -50.944033) (xy 237.425761 -50.838737) (xy 237.445698 -50.734651) (xy 237.47345 -50.632371)
			(xy 237.508858 -50.532482) (xy 237.551719 -50.435558) (xy 237.601787 -50.342152) (xy 237.658777 -50.252801)
			(xy 237.72236 -50.168015) (xy 237.792174 -50.088281) (xy 237.867818 -50.014056) (xy 237.948858 -49.945763)
			(xy 238.034832 -49.883796) (xy 238.125246 -49.828508) (xy 238.219582 -49.780216) (xy 238.317301 -49.739197)
			(xy 238.417841 -49.705686) (xy 238.520629 -49.679874) (xy 238.625073 -49.66191) (xy 238.730578 -49.651897)
			(xy 238.836537 -49.649891) (xy 238.942345 -49.655905) (xy 239.047395 -49.669904) (xy 239.151085 -49.691807)
			(xy 239.252822 -49.72149) (xy 239.352023 -49.758781) (xy 239.448119 -49.803469) (xy 239.54056 -49.855296)
			(xy 239.628817 -49.913966) (xy 239.712384 -49.979143) (xy 239.790783 -50.050453) (xy 239.863564 -50.127487)
			(xy 239.93031 -50.209806) (xy 239.99064 -50.296937) (xy 240.044207 -50.388381) (xy 240.090705 -50.483614)
			(xy 240.129867 -50.582091) (xy 240.16147 -50.683248) (xy 240.185331 -50.786506) (xy 240.201316 -50.891272)
			(xy 240.209331 -50.996947) (xy 240.209832 -51.049936) (xy 240.209331 -51.102925) (xy 240.201316 -51.2086)
			(xy 240.185331 -51.313366) (xy 240.16147 -51.416624) (xy 240.129867 -51.517781) (xy 240.090705 -51.616258)
			(xy 240.044207 -51.711491) (xy 239.99064 -51.802935) (xy 239.93031 -51.890066) (xy 239.863564 -51.972385)
			(xy 239.790783 -52.049419) (xy 239.712384 -52.120729) (xy 239.628817 -52.185906) (xy 239.54056 -52.244576)
			(xy 239.448119 -52.296403) (xy 239.352023 -52.341091) (xy 239.252822 -52.378382) (xy 239.151085 -52.408065)
			(xy 239.047395 -52.429968) (xy 238.942345 -52.443967) (xy 238.836537 -52.449981) (xy 238.730578 -52.447975)
			(xy 238.625073 -52.437962) (xy 238.520629 -52.419998) (xy 238.417841 -52.394186) (xy 238.317301 -52.360675)
			(xy 238.219582 -52.319656) (xy 238.125246 -52.271364) (xy 238.034832 -52.216076) (xy 237.948858 -52.154109)
			(xy 237.867818 -52.085816) (xy 237.792174 -52.011591) (xy 237.72236 -51.931857) (xy 237.658777 -51.847071)
			(xy 237.601787 -51.75772) (xy 237.551719 -51.664314) (xy 237.508858 -51.56739) (xy 237.47345 -51.467501)
			(xy 237.445698 -51.365221) (xy 237.425761 -51.261135) (xy 237.413753 -51.155839) (xy 237.409743 -51.049936)
			(xy 210.209892 -51.049936) (xy 210.209391 -51.102925) (xy 210.201376 -51.2086) (xy 210.185391 -51.313366)
			(xy 210.16153 -51.416624) (xy 210.129927 -51.517781) (xy 210.090765 -51.616258) (xy 210.044267 -51.711491)
			(xy 209.9907 -51.802935) (xy 209.93037 -51.890066) (xy 209.863624 -51.972385) (xy 209.790843 -52.049419)
			(xy 209.712444 -52.120729) (xy 209.628877 -52.185906) (xy 209.54062 -52.244576) (xy 209.448179 -52.296403)
			(xy 209.352083 -52.341091) (xy 209.252882 -52.378382) (xy 209.151145 -52.408065) (xy 209.047455 -52.429968)
			(xy 208.942405 -52.443967) (xy 208.836597 -52.449981) (xy 208.730638 -52.447975) (xy 208.625133 -52.437962)
			(xy 208.520689 -52.419998) (xy 208.417901 -52.394186) (xy 208.317361 -52.360675) (xy 208.219642 -52.319656)
			(xy 208.125306 -52.271364) (xy 208.034892 -52.216076) (xy 207.948918 -52.154109) (xy 207.867878 -52.085816)
			(xy 207.792234 -52.011591) (xy 207.72242 -51.931857) (xy 207.658837 -51.847071) (xy 207.601847 -51.75772)
			(xy 207.551779 -51.664314) (xy 207.508918 -51.56739) (xy 207.47351 -51.467501) (xy 207.445758 -51.365221)
			(xy 207.425821 -51.261135) (xy 207.413813 -51.155839) (xy 207.409803 -51.049936) (xy 194.084017 -51.049936)
			(xy 194.08393 -51.055512) (xy 194.075249 -51.121466) (xy 194.05803 -51.185722) (xy 194.032567 -51.247179)
			(xy 193.999297 -51.304784) (xy 193.958789 -51.357551) (xy 193.935604 -51.381406) (xy 193.390774 -51.926236)
			(xy 193.366895 -51.949394) (xy 193.314132 -51.989904) (xy 193.256532 -52.023177) (xy 193.19508 -52.048645)
			(xy 193.130828 -52.06587) (xy 193.064878 -52.074558) (xy 193.031618 -52.07508) (xy 182.815484 -52.07508)
			(xy 182.782225 -52.074558) (xy 182.716276 -52.065868) (xy 182.652026 -52.04864) (xy 182.590577 -52.023169)
			(xy 182.532981 -51.989891) (xy 182.480224 -51.949376) (xy 182.456328 -51.926236) (xy 181.784244 -51.254152)
			(xy 181.761088 -51.230272) (xy 181.720582 -51.177508) (xy 181.687312 -51.119907) (xy 181.661849 -51.058455)
			(xy 181.644627 -50.994205) (xy 181.635942 -50.928255) (xy 181.6354 -50.894996) (xy 181.6354 -46.609)
			(xy 181.635921 -46.57574) (xy 181.644609 -46.50979) (xy 181.661834 -46.445539) (xy 181.687303 -46.384088)
			(xy 181.720579 -46.326489) (xy 181.761092 -46.273729) (xy 181.784244 -46.249844) (xy 185.467244 -42.566844)
			(xy 185.478655 -42.555648) (xy 185.502675 -42.53455) (xy 185.51525 -42.52468) (xy 185.521092 -42.519854)
			(xy 185.530998 -42.505884) (xy 185.537398 -42.495795) (xy 185.54098 -42.472204) (xy 185.537856 -42.460672)
			(xy 185.508392 -42.372026) (xy 185.504781 -42.362541) (xy 185.491461 -42.347249) (xy 185.473274 -42.338277)
			(xy 185.46318 -42.337228) (xy 174.146972 -42.337228) (xy 174.142081 -42.337363) (xy 174.132487 -42.339278)
			(xy 174.127922 -42.341038) (xy 174.11827 -42.344848) (xy 174.111158 -42.352214) (xy 172.697648 -43.765724)
			(xy 172.692822 -43.771312) (xy 172.688155 -43.778053) (xy 172.682975 -43.793599) (xy 172.682662 -43.801792)
			(xy 172.682662 -47.032361) (xy 177.987702 -47.032361) (xy 177.987702 -46.947639) (xy 177.995755 -46.863302)
			(xy 178.011789 -46.780112) (xy 178.035657 -46.698822) (xy 178.067145 -46.62017) (xy 178.105967 -46.544867)
			(xy 178.15177 -46.473595) (xy 178.204141 -46.406999) (xy 178.262606 -46.345684) (xy 178.326634 -46.290203)
			(xy 178.395646 -46.24106) (xy 178.469016 -46.1987) (xy 178.546081 -46.163505) (xy 178.626143 -46.135796)
			(xy 178.708476 -46.115822) (xy 178.792335 -46.103765) (xy 178.87696 -46.099734) (xy 178.961585 -46.103765)
			(xy 179.045444 -46.115822) (xy 179.127777 -46.135796) (xy 179.207839 -46.163505) (xy 179.284904 -46.1987)
			(xy 179.358274 -46.24106) (xy 179.427286 -46.290203) (xy 179.491314 -46.345684) (xy 179.549779 -46.406999)
			(xy 179.60215 -46.473595) (xy 179.647953 -46.544867) (xy 179.686775 -46.62017) (xy 179.718263 -46.698822)
			(xy 179.742131 -46.780112) (xy 179.758165 -46.863302) (xy 179.766218 -46.947639) (xy 179.766722 -46.99)
			(xy 179.766218 -47.032361) (xy 179.758165 -47.116698) (xy 179.742131 -47.199888) (xy 179.718263 -47.281178)
			(xy 179.686775 -47.35983) (xy 179.647953 -47.435133) (xy 179.60215 -47.506405) (xy 179.549779 -47.573001)
			(xy 179.491314 -47.634316) (xy 179.427286 -47.689797) (xy 179.358274 -47.73894) (xy 179.284904 -47.7813)
			(xy 179.207839 -47.816495) (xy 179.127777 -47.844204) (xy 179.045444 -47.864178) (xy 178.961585 -47.876235)
			(xy 178.87696 -47.880267) (xy 178.792335 -47.876235) (xy 178.708476 -47.864178) (xy 178.626143 -47.844204)
			(xy 178.546081 -47.816495) (xy 178.469016 -47.7813) (xy 178.395646 -47.73894) (xy 178.326634 -47.689797)
			(xy 178.262606 -47.634316) (xy 178.204141 -47.573001) (xy 178.15177 -47.506405) (xy 178.105967 -47.435133)
			(xy 178.067145 -47.35983) (xy 178.035657 -47.281178) (xy 178.011789 -47.199888) (xy 177.995755 -47.116698)
			(xy 177.987702 -47.032361) (xy 172.682662 -47.032361) (xy 172.682662 -50.465228) (xy 172.682916 -50.470054)
			(xy 172.684135 -50.478809) (xy 172.69167 -50.494784) (xy 172.697648 -50.501296) (xy 172.778674 -50.582322)
			(xy 172.785135 -50.588374) (xy 172.801135 -50.595928) (xy 172.809916 -50.597054) (xy 172.812456 -50.597308)
			(xy 173.980348 -50.597308) (xy 174.013609 -50.597826) (xy 174.079563 -50.606507) (xy 174.143818 -50.623728)
			(xy 174.205273 -50.649193) (xy 174.262876 -50.682466) (xy 174.315641 -50.722977) (xy 174.339504 -50.746152)
			(xy 176.661318 -53.067966) (xy 176.684475 -53.091846) (xy 176.724982 -53.144609) (xy 176.758252 -53.20221)
			(xy 176.783715 -53.263662) (xy 176.800936 -53.327913) (xy 176.80962 -53.393863) (xy 176.810162 -53.427122)
			(xy 176.810162 -54.679088) (xy 176.809641 -54.712349) (xy 176.800957 -54.778301) (xy 176.783734 -54.842554)
			(xy 176.758268 -54.904008) (xy 176.724996 -54.96161) (xy 176.684487 -55.014375) (xy 176.661318 -55.038244)
			(xy 175.970438 -55.729124) (xy 175.946558 -55.752281) (xy 175.893795 -55.792787) (xy 175.836194 -55.826058)
			(xy 175.774742 -55.851521) (xy 175.710491 -55.868743) (xy 175.644541 -55.877426) (xy 175.611282 -55.877968)
			(xy 160.852104 -55.877968) (xy 160.847214 -55.878109) (xy 160.837624 -55.880033) (xy 160.833054 -55.881778)
			(xy 160.823402 -55.885588) (xy 160.81629 -55.892954) (xy 156.333444 -60.3758) (xy 165.632388 -60.3758)
			(xy 165.636418 -60.291199) (xy 165.648471 -60.207364) (xy 165.668439 -60.125055) (xy 165.696141 -60.045016)
			(xy 165.731325 -59.967973) (xy 165.773674 -59.894623) (xy 165.822803 -59.825631) (xy 165.878268 -59.761621)
			(xy 165.939566 -59.703173) (xy 166.006142 -59.650817) (xy 166.077394 -59.605027) (xy 166.152675 -59.566216)
			(xy 166.231305 -59.534737) (xy 166.312572 -59.510876) (xy 166.395738 -59.494847) (xy 166.480052 -59.486796)
			(xy 166.5224 -59.486292) (xy 166.522908 -59.486292) (xy 166.56924 -59.486898) (xy 166.661398 -59.496569)
			(xy 166.752052 -59.515765) (xy 166.840221 -59.544277) (xy 166.882826 -59.562492) (xy 166.892768 -59.566298)
			(xy 166.914032 -59.566298) (xy 166.923974 -59.562492) (xy 166.966577 -59.54427) (xy 167.054744 -59.515752)
			(xy 167.1454 -59.49656) (xy 167.23756 -59.4869) (xy 167.283892 -59.486292) (xy 167.2844 -59.486292)
			(xy 167.326748 -59.486796) (xy 167.411062 -59.494847) (xy 167.494228 -59.510876) (xy 167.575495 -59.534737)
			(xy 167.654125 -59.566216) (xy 167.729406 -59.605027) (xy 167.800658 -59.650817) (xy 167.867234 -59.703173)
			(xy 167.928532 -59.761621) (xy 167.983997 -59.825631) (xy 168.033126 -59.894623) (xy 168.075475 -59.967973)
			(xy 168.110659 -60.045016) (xy 168.138361 -60.125055) (xy 168.158329 -60.207364) (xy 168.170382 -60.291199)
			(xy 168.174413 -60.3758) (xy 168.170382 -60.460401) (xy 168.158329 -60.544236) (xy 168.138361 -60.626545)
			(xy 168.110659 -60.706584) (xy 168.075475 -60.783627) (xy 168.033126 -60.856977) (xy 167.983997 -60.925969)
			(xy 167.928532 -60.989979) (xy 167.867234 -61.048427) (xy 167.800658 -61.100783) (xy 167.729406 -61.146573)
			(xy 167.654125 -61.185384) (xy 167.575495 -61.216863) (xy 167.494228 -61.240724) (xy 167.411062 -61.256753)
			(xy 167.326748 -61.264804) (xy 167.2844 -61.265308) (xy 167.283892 -61.265308) (xy 167.23756 -61.264702)
			(xy 167.145402 -61.255031) (xy 167.054748 -61.235835) (xy 166.966579 -61.207323) (xy 166.923974 -61.189108)
			(xy 166.914032 -61.185302) (xy 166.892768 -61.185302) (xy 166.882826 -61.189108) (xy 166.840223 -61.20733)
			(xy 166.752056 -61.235848) (xy 166.6614 -61.25504) (xy 166.56924 -61.2647) (xy 166.522908 -61.265308)
			(xy 166.5224 -61.265308) (xy 166.480052 -61.264804) (xy 166.395738 -61.256753) (xy 166.312572 -61.240724)
			(xy 166.231305 -61.216863) (xy 166.152675 -61.185384) (xy 166.077394 -61.146573) (xy 166.006142 -61.100783)
			(xy 165.939566 -61.048427) (xy 165.878268 -60.989979) (xy 165.822803 -60.925969) (xy 165.773674 -60.856977)
			(xy 165.731325 -60.783627) (xy 165.696141 -60.706584) (xy 165.668439 -60.626545) (xy 165.648471 -60.544236)
			(xy 165.636418 -60.460401) (xy 165.632388 -60.3758) (xy 156.333444 -60.3758) (xy 153.111708 -63.597536)
			(xy 153.106882 -63.603124) (xy 153.102212 -63.609864) (xy 153.097029 -63.62541) (xy 153.096722 -63.633604)
			(xy 153.096722 -66.3194) (xy 178.683872 -66.3194) (xy 178.687902 -66.234795) (xy 178.699957 -66.150957)
			(xy 178.719926 -66.068644) (xy 178.74763 -65.988602) (xy 178.782817 -65.911556) (xy 178.825168 -65.838204)
			(xy 178.8743 -65.769209) (xy 178.929768 -65.705198) (xy 178.99107 -65.646749) (xy 179.057651 -65.594392)
			(xy 179.128907 -65.548601) (xy 179.204193 -65.509791) (xy 179.282827 -65.478314) (xy 179.364098 -65.454453)
			(xy 179.447268 -65.438427) (xy 179.531586 -65.430378) (xy 179.573936 -65.429892) (xy 179.574698 -65.429892)
			(xy 179.613046 -65.430288) (xy 179.689453 -65.436923) (xy 179.765005 -65.450117) (xy 179.839139 -65.469774)
			(xy 179.911302 -65.495746) (xy 179.9463 -65.511426) (xy 179.956573 -65.515566) (xy 179.978699 -65.515566)
			(xy 179.988972 -65.511426) (xy 180.023978 -65.49577) (xy 180.096146 -65.469818) (xy 180.170278 -65.45017)
			(xy 180.245826 -65.436971) (xy 180.322228 -65.430321) (xy 180.360574 -65.429892) (xy 180.361336 -65.429892)
			(xy 180.403683 -65.430397) (xy 180.487994 -65.438451) (xy 180.571158 -65.454483) (xy 180.652421 -65.478347)
			(xy 180.731048 -65.509827) (xy 180.806327 -65.548639) (xy 180.877576 -65.59443) (xy 180.944149 -65.646786)
			(xy 181.005444 -65.705234) (xy 181.060907 -65.769243) (xy 181.110033 -65.838234) (xy 181.15238 -65.911582)
			(xy 181.187562 -65.988624) (xy 181.215263 -66.068661) (xy 181.23523 -66.150968) (xy 181.247283 -66.234801)
			(xy 181.251313 -66.3194) (xy 181.247283 -66.403999) (xy 181.23523 -66.487832) (xy 181.215263 -66.570139)
			(xy 181.187562 -66.650176) (xy 181.15238 -66.727218) (xy 181.110033 -66.800566) (xy 181.060907 -66.869557)
			(xy 181.005444 -66.933566) (xy 180.944149 -66.992014) (xy 180.877576 -67.04437) (xy 180.806327 -67.090161)
			(xy 180.731048 -67.128973) (xy 180.652421 -67.160453) (xy 180.571158 -67.184317) (xy 180.487994 -67.200349)
			(xy 180.403683 -67.208403) (xy 180.361336 -67.208908) (xy 180.360574 -67.208908) (xy 180.322227 -67.208485)
			(xy 180.24582 -67.201857) (xy 180.170269 -67.188668) (xy 180.096135 -67.169018) (xy 180.02397 -67.143051)
			(xy 179.988972 -67.127374) (xy 179.978699 -67.123234) (xy 179.956573 -67.123234) (xy 179.9463 -67.127374)
			(xy 179.911298 -67.14304) (xy 179.839129 -67.16899) (xy 179.764996 -67.188636) (xy 179.689447 -67.201832)
			(xy 179.613044 -67.20848) (xy 179.574698 -67.208908) (xy 179.573936 -67.208908) (xy 179.531586 -67.208422)
			(xy 179.447268 -67.200373) (xy 179.364098 -67.184347) (xy 179.282827 -67.160486) (xy 179.204193 -67.129009)
			(xy 179.128907 -67.090199) (xy 179.057651 -67.044408) (xy 178.99107 -66.992051) (xy 178.929768 -66.933602)
			(xy 178.8743 -66.869591) (xy 178.825168 -66.800596) (xy 178.782817 -66.727244) (xy 178.74763 -66.650198)
			(xy 178.719926 -66.570156) (xy 178.699957 -66.487843) (xy 178.687902 -66.404005) (xy 178.683872 -66.3194)
			(xy 153.096722 -66.3194) (xy 153.096722 -69.1896) (xy 177.667872 -69.1896) (xy 177.671902 -69.104995)
			(xy 177.683957 -69.021157) (xy 177.703926 -68.938844) (xy 177.73163 -68.858802) (xy 177.766817 -68.781756)
			(xy 177.809168 -68.708404) (xy 177.8583 -68.639409) (xy 177.913768 -68.575398) (xy 177.97507 -68.516949)
			(xy 178.041651 -68.464592) (xy 178.112907 -68.418801) (xy 178.188193 -68.379991) (xy 178.266827 -68.348514)
			(xy 178.348098 -68.324653) (xy 178.431268 -68.308627) (xy 178.515586 -68.300578) (xy 178.557936 -68.300092)
			(xy 178.558444 -68.300092) (xy 178.597192 -68.300509) (xy 178.674394 -68.307273) (xy 178.750714 -68.320729)
			(xy 178.825573 -68.340774) (xy 178.898405 -68.367256) (xy 178.968657 -68.399975) (xy 179.002436 -68.418964)
			(xy 179.01031 -68.423123) (xy 179.027836 -68.426217) (xy 179.045362 -68.423123) (xy 179.053236 -68.418964)
			(xy 179.087017 -68.399978) (xy 179.157269 -68.367265) (xy 179.230101 -68.340786) (xy 179.304961 -68.320743)
			(xy 179.38128 -68.307289) (xy 179.45848 -68.300524) (xy 179.497228 -68.300092) (xy 179.497736 -68.300092)
			(xy 179.540083 -68.300597) (xy 179.624394 -68.308651) (xy 179.707558 -68.324683) (xy 179.788821 -68.348547)
			(xy 179.867448 -68.380027) (xy 179.942727 -68.418839) (xy 180.013976 -68.46463) (xy 180.080549 -68.516986)
			(xy 180.141844 -68.575434) (xy 180.197307 -68.639443) (xy 180.246433 -68.708434) (xy 180.28878 -68.781782)
			(xy 180.323962 -68.858824) (xy 180.351663 -68.938861) (xy 180.37163 -69.021168) (xy 180.383683 -69.105001)
			(xy 180.387713 -69.1896) (xy 180.383683 -69.274199) (xy 180.37163 -69.358032) (xy 180.351663 -69.440339)
			(xy 180.350534 -69.4436) (xy 181.326028 -69.4436) (xy 181.326532 -69.401252) (xy 181.334583 -69.316938)
			(xy 181.350612 -69.233772) (xy 181.374473 -69.152505) (xy 181.405952 -69.073875) (xy 181.444763 -68.998594)
			(xy 181.490553 -68.927342) (xy 181.542909 -68.860766) (xy 181.601357 -68.799468) (xy 181.665367 -68.744003)
			(xy 181.734359 -68.694874) (xy 181.807709 -68.652525) (xy 181.884752 -68.617341) (xy 181.964791 -68.589639)
			(xy 182.0471 -68.569671) (xy 182.130935 -68.557618) (xy 182.215536 -68.553588) (xy 182.300137 -68.557618)
			(xy 182.383972 -68.569671) (xy 182.426549 -68.58) (xy 183.920388 -68.58) (xy 183.924418 -68.495399)
			(xy 183.936471 -68.411564) (xy 183.956439 -68.329255) (xy 183.984141 -68.249216) (xy 184.019325 -68.172173)
			(xy 184.061674 -68.098823) (xy 184.110803 -68.029831) (xy 184.166268 -67.965821) (xy 184.227566 -67.907373)
			(xy 184.294142 -67.855017) (xy 184.365394 -67.809227) (xy 184.440675 -67.770416) (xy 184.519305 -67.738937)
			(xy 184.600572 -67.715076) (xy 184.683738 -67.699047) (xy 184.768052 -67.690996) (xy 184.8104 -67.690492)
			(xy 184.810908 -67.690492) (xy 184.85724 -67.691098) (xy 184.949398 -67.700769) (xy 185.040052 -67.719965)
			(xy 185.128221 -67.748477) (xy 185.170826 -67.766692) (xy 185.180768 -67.770498) (xy 185.202032 -67.770498)
			(xy 185.211974 -67.766692) (xy 185.254577 -67.74847) (xy 185.342744 -67.719952) (xy 185.4334 -67.70076)
			(xy 185.52556 -67.6911) (xy 185.571892 -67.690492) (xy 185.5724 -67.690492) (xy 185.614748 -67.690996)
			(xy 185.699062 -67.699047) (xy 185.782228 -67.715076) (xy 185.863495 -67.738937) (xy 185.942125 -67.770416)
			(xy 186.017406 -67.809227) (xy 186.088658 -67.855017) (xy 186.155234 -67.907373) (xy 186.216532 -67.965821)
			(xy 186.271997 -68.029831) (xy 186.321126 -68.098823) (xy 186.363475 -68.172173) (xy 186.398659 -68.249216)
			(xy 186.426361 -68.329255) (xy 186.446329 -68.411564) (xy 186.458382 -68.495399) (xy 186.462413 -68.58)
			(xy 186.458382 -68.664601) (xy 186.446329 -68.748436) (xy 186.426361 -68.830745) (xy 186.398659 -68.910784)
			(xy 186.363475 -68.987827) (xy 186.321126 -69.061177) (xy 186.271997 -69.130169) (xy 186.216532 -69.194179)
			(xy 186.155234 -69.252627) (xy 186.088658 -69.304983) (xy 186.017406 -69.350773) (xy 185.942125 -69.389584)
			(xy 185.863495 -69.421063) (xy 185.782228 -69.444924) (xy 185.699062 -69.460953) (xy 185.614748 -69.469004)
			(xy 185.5724 -69.469508) (xy 185.571892 -69.469508) (xy 185.52556 -69.468902) (xy 185.433402 -69.459231)
			(xy 185.342748 -69.440035) (xy 185.254579 -69.411523) (xy 185.211974 -69.393308) (xy 185.202032 -69.389502)
			(xy 185.180768 -69.389502) (xy 185.170826 -69.393308) (xy 185.128223 -69.41153) (xy 185.040056 -69.440048)
			(xy 184.9494 -69.45924) (xy 184.85724 -69.4689) (xy 184.810908 -69.469508) (xy 184.8104 -69.469508)
			(xy 184.768052 -69.469004) (xy 184.683738 -69.460953) (xy 184.600572 -69.444924) (xy 184.519305 -69.421063)
			(xy 184.440675 -69.389584) (xy 184.365394 -69.350773) (xy 184.294142 -69.304983) (xy 184.227566 -69.252627)
			(xy 184.166268 -69.194179) (xy 184.110803 -69.130169) (xy 184.061674 -69.061177) (xy 184.019325 -68.987827)
			(xy 183.984141 -68.910784) (xy 183.956439 -68.830745) (xy 183.936471 -68.748436) (xy 183.924418 -68.664601)
			(xy 183.920388 -68.58) (xy 182.426549 -68.58) (xy 182.466281 -68.589639) (xy 182.54632 -68.617341)
			(xy 182.623363 -68.652525) (xy 182.696713 -68.694874) (xy 182.765705 -68.744003) (xy 182.829715 -68.799468)
			(xy 182.888163 -68.860766) (xy 182.940519 -68.927342) (xy 182.986309 -68.998594) (xy 183.02512 -69.073875)
			(xy 183.056599 -69.152505) (xy 183.08046 -69.233772) (xy 183.096489 -69.316938) (xy 183.10454 -69.401252)
			(xy 183.105044 -69.4436) (xy 183.105044 -69.444362) (xy 183.104477 -69.489611) (xy 183.095255 -69.579637)
			(xy 183.076932 -69.66826) (xy 183.049699 -69.754562) (xy 183.013837 -69.837651) (xy 182.992268 -69.877432)
			(xy 182.98741 -69.887417) (xy 182.985813 -69.909537) (xy 182.98922 -69.920104) (xy 183.020462 -70.003416)
			(xy 183.03621 -70.01891) (xy 183.046878 -70.02272) (xy 183.08635 -70.037268) (xy 183.162598 -70.072818)
			(xy 183.23515 -70.115407) (xy 183.303358 -70.164655) (xy 183.366613 -70.220121) (xy 183.424349 -70.28131)
			(xy 183.476052 -70.347676) (xy 183.521259 -70.418626) (xy 183.559567 -70.493527) (xy 183.590634 -70.571709)
			(xy 183.614182 -70.652475) (xy 183.630002 -70.735103) (xy 183.63795 -70.818856) (xy 183.638444 -70.86092)
			(xy 183.63794 -70.903268) (xy 183.629889 -70.987582) (xy 183.61386 -71.070748) (xy 183.589999 -71.152015)
			(xy 183.55852 -71.230645) (xy 183.519709 -71.305926) (xy 183.473919 -71.377178) (xy 183.421563 -71.443754)
			(xy 183.363115 -71.505052) (xy 183.299105 -71.560517) (xy 183.230113 -71.609646) (xy 183.156763 -71.651995)
			(xy 183.07972 -71.687179) (xy 182.999681 -71.714881) (xy 182.917372 -71.734849) (xy 182.833537 -71.746902)
			(xy 182.748936 -71.750933) (xy 182.664335 -71.746902) (xy 182.5805 -71.734849) (xy 182.498191 -71.714881)
			(xy 182.418152 -71.687179) (xy 182.341109 -71.651995) (xy 182.267759 -71.609646) (xy 182.198767 -71.560517)
			(xy 182.134757 -71.505052) (xy 182.076309 -71.443754) (xy 182.023953 -71.377178) (xy 181.978163 -71.305926)
			(xy 181.939352 -71.230645) (xy 181.907873 -71.152015) (xy 181.884012 -71.070748) (xy 181.867983 -70.987582)
			(xy 181.859932 -70.903268) (xy 181.859428 -70.86092) (xy 181.859428 -70.860158) (xy 181.860007 -70.81491)
			(xy 181.869227 -70.724884) (xy 181.887547 -70.636261) (xy 181.914778 -70.549959) (xy 181.950636 -70.466869)
			(xy 181.972204 -70.427088) (xy 181.977111 -70.417122) (xy 181.978678 -70.394985) (xy 181.975252 -70.384416)
			(xy 181.94401 -70.301104) (xy 181.928262 -70.28561) (xy 181.917594 -70.2818) (xy 181.878145 -70.267193)
			(xy 181.801896 -70.23165) (xy 181.729343 -70.189068) (xy 181.661134 -70.139826) (xy 181.597877 -70.084366)
			(xy 181.540139 -70.023182) (xy 181.488434 -69.956821) (xy 181.443225 -69.885875) (xy 181.404914 -69.810979)
			(xy 181.373845 -69.7328) (xy 181.350295 -69.652037) (xy 181.334473 -69.569413) (xy 181.326523 -69.485663)
			(xy 181.326028 -69.4436) (xy 180.350534 -69.4436) (xy 180.323962 -69.520376) (xy 180.28878 -69.597418)
			(xy 180.246433 -69.670766) (xy 180.197307 -69.739757) (xy 180.141844 -69.803766) (xy 180.080549 -69.862214)
			(xy 180.013976 -69.91457) (xy 179.942727 -69.960361) (xy 179.867448 -69.999173) (xy 179.788821 -70.030653)
			(xy 179.707558 -70.054517) (xy 179.624394 -70.070549) (xy 179.540083 -70.078603) (xy 179.497736 -70.079108)
			(xy 179.497228 -70.079108) (xy 179.45848 -70.078658) (xy 179.38128 -70.0719) (xy 179.304961 -70.058451)
			(xy 179.230101 -70.038412) (xy 179.157268 -70.011936) (xy 179.087016 -69.979222) (xy 179.053236 -69.960236)
			(xy 179.045362 -69.956077) (xy 179.027836 -69.952983) (xy 179.01031 -69.956077) (xy 179.002436 -69.960236)
			(xy 178.968662 -69.979233) (xy 178.898407 -70.011945) (xy 178.825574 -70.038422) (xy 178.750713 -70.058462)
			(xy 178.674393 -70.071915) (xy 178.597192 -70.078678) (xy 178.558444 -70.079108) (xy 178.557936 -70.079108)
			(xy 178.515586 -70.078622) (xy 178.431268 -70.070573) (xy 178.348098 -70.054547) (xy 178.266827 -70.030686)
			(xy 178.188193 -69.999209) (xy 178.112907 -69.960399) (xy 178.041651 -69.914608) (xy 177.97507 -69.862251)
			(xy 177.913768 -69.803802) (xy 177.8583 -69.739791) (xy 177.809168 -69.670796) (xy 177.766817 -69.597444)
			(xy 177.73163 -69.520398) (xy 177.703926 -69.440356) (xy 177.683957 -69.358043) (xy 177.671902 -69.274205)
			(xy 177.667872 -69.1896) (xy 153.096722 -69.1896) (xy 153.096722 -72.009) (xy 177.667872 -72.009)
			(xy 177.671902 -71.924395) (xy 177.683957 -71.840557) (xy 177.703926 -71.758244) (xy 177.73163 -71.678202)
			(xy 177.766817 -71.601156) (xy 177.809168 -71.527804) (xy 177.8583 -71.458809) (xy 177.913768 -71.394798)
			(xy 177.97507 -71.336349) (xy 178.041651 -71.283992) (xy 178.112907 -71.238201) (xy 178.188193 -71.199391)
			(xy 178.266827 -71.167914) (xy 178.348098 -71.144053) (xy 178.431268 -71.128027) (xy 178.515586 -71.119978)
			(xy 178.557936 -71.119492) (xy 178.596727 -71.119889) (xy 178.674016 -71.126624) (xy 178.750424 -71.140065)
			(xy 178.825371 -71.16011) (xy 178.898288 -71.186607) (xy 178.968619 -71.219355) (xy 179.002436 -71.238364)
			(xy 179.01031 -71.242523) (xy 179.027836 -71.245617) (xy 179.045362 -71.242523) (xy 179.053236 -71.238364)
			(xy 179.087054 -71.219359) (xy 179.157387 -71.186616) (xy 179.230303 -71.160122) (xy 179.30525 -71.140079)
			(xy 179.381658 -71.126639) (xy 179.458946 -71.119903) (xy 179.497736 -71.119492) (xy 179.540083 -71.119997)
			(xy 179.624394 -71.128051) (xy 179.707558 -71.144083) (xy 179.788821 -71.167947) (xy 179.867448 -71.199427)
			(xy 179.942727 -71.238239) (xy 180.013976 -71.28403) (xy 180.080549 -71.336386) (xy 180.141844 -71.394834)
			(xy 180.197307 -71.458843) (xy 180.246433 -71.527834) (xy 180.28878 -71.601182) (xy 180.323962 -71.678224)
			(xy 180.351663 -71.758261) (xy 180.37163 -71.840568) (xy 180.383683 -71.924401) (xy 180.387713 -72.009)
			(xy 180.383683 -72.093599) (xy 180.37163 -72.177432) (xy 180.351663 -72.259739) (xy 180.323962 -72.339776)
			(xy 180.28878 -72.416818) (xy 180.246433 -72.490166) (xy 180.197307 -72.559157) (xy 180.141844 -72.623166)
			(xy 180.080549 -72.681614) (xy 180.013976 -72.73397) (xy 179.942727 -72.779761) (xy 179.867448 -72.818573)
			(xy 179.788821 -72.850053) (xy 179.707558 -72.873917) (xy 179.624394 -72.889949) (xy 179.540083 -72.898003)
			(xy 179.497736 -72.898508) (xy 179.458945 -72.898124) (xy 179.381656 -72.891387) (xy 179.305247 -72.877943)
			(xy 179.2303 -72.857895) (xy 179.157383 -72.831396) (xy 179.087053 -72.798646) (xy 179.053236 -72.779636)
			(xy 179.045362 -72.775477) (xy 179.027836 -72.772383) (xy 179.01031 -72.775477) (xy 179.002436 -72.779636)
			(xy 178.968624 -72.798653) (xy 178.89829 -72.831394) (xy 178.825372 -72.857885) (xy 178.750424 -72.877926)
			(xy 178.674015 -72.891365) (xy 178.596727 -72.898098) (xy 178.557936 -72.898508) (xy 178.515586 -72.898022)
			(xy 178.431268 -72.889973) (xy 178.348098 -72.873947) (xy 178.266827 -72.850086) (xy 178.188193 -72.818609)
			(xy 178.112907 -72.779799) (xy 178.041651 -72.734008) (xy 177.97507 -72.681651) (xy 177.913768 -72.623202)
			(xy 177.8583 -72.559191) (xy 177.809168 -72.490196) (xy 177.766817 -72.416844) (xy 177.73163 -72.339798)
			(xy 177.703926 -72.259756) (xy 177.683957 -72.177443) (xy 177.671902 -72.093605) (xy 177.667872 -72.009)
			(xy 153.096722 -72.009) (xy 153.096722 -74.337361) (xy 183.260742 -74.337361) (xy 183.260742 -74.252639)
			(xy 183.268795 -74.168302) (xy 183.284829 -74.085112) (xy 183.308697 -74.003822) (xy 183.340185 -73.92517)
			(xy 183.379007 -73.849867) (xy 183.42481 -73.778595) (xy 183.477181 -73.711999) (xy 183.535646 -73.650684)
			(xy 183.599674 -73.595203) (xy 183.668686 -73.54606) (xy 183.742056 -73.5037) (xy 183.819121 -73.468505)
			(xy 183.899183 -73.440796) (xy 183.981516 -73.420822) (xy 184.065375 -73.408765) (xy 184.15 -73.404734)
			(xy 184.234625 -73.408765) (xy 184.318484 -73.420822) (xy 184.400817 -73.440796) (xy 184.480879 -73.468505)
			(xy 184.557944 -73.5037) (xy 184.631314 -73.54606) (xy 184.700326 -73.595203) (xy 184.764354 -73.650684)
			(xy 184.822819 -73.711999) (xy 184.87519 -73.778595) (xy 184.920993 -73.849867) (xy 184.959815 -73.92517)
			(xy 184.991303 -74.003822) (xy 185.015171 -74.085112) (xy 185.031205 -74.168302) (xy 185.039258 -74.252639)
			(xy 185.039762 -74.295) (xy 185.039258 -74.337361) (xy 185.031205 -74.421698) (xy 185.015171 -74.504888)
			(xy 184.991303 -74.586178) (xy 184.959815 -74.66483) (xy 184.920993 -74.740133) (xy 184.87519 -74.811405)
			(xy 184.822819 -74.878001) (xy 184.764354 -74.939316) (xy 184.700326 -74.994797) (xy 184.631314 -75.04394)
			(xy 184.557944 -75.0863) (xy 184.480879 -75.121495) (xy 184.400817 -75.149204) (xy 184.318484 -75.169178)
			(xy 184.234625 -75.181235) (xy 184.15 -75.185267) (xy 184.065375 -75.181235) (xy 183.981516 -75.169178)
			(xy 183.899183 -75.149204) (xy 183.819121 -75.121495) (xy 183.742056 -75.0863) (xy 183.668686 -75.04394)
			(xy 183.599674 -74.994797) (xy 183.535646 -74.939316) (xy 183.477181 -74.878001) (xy 183.42481 -74.811405)
			(xy 183.379007 -74.740133) (xy 183.340185 -74.66483) (xy 183.308697 -74.586178) (xy 183.284829 -74.504888)
			(xy 183.268795 -74.421698) (xy 183.260742 -74.337361) (xy 153.096722 -74.337361) (xy 153.096722 -77.318362)
			(xy 153.096818 -77.323116) (xy 153.098605 -77.332453) (xy 153.100278 -77.336904) (xy 153.109676 -77.361288)
			(xy 153.115264 -77.367892) (xy 153.132482 -77.38873) (xy 153.161484 -77.434345) (xy 153.183757 -77.483596)
			(xy 153.198857 -77.535498) (xy 153.206481 -77.589011) (xy 153.206475 -77.643065) (xy 153.198841 -77.696577)
			(xy 153.183731 -77.748476) (xy 153.161448 -77.797722) (xy 153.132437 -77.843331) (xy 153.115264 -77.864208)
			(xy 153.109676 -77.870812) (xy 153.100278 -77.895196) (xy 153.098655 -77.89966) (xy 153.096871 -77.90899)
			(xy 153.096722 -77.913738) (xy 153.096722 -79.655416) (xy 153.0962 -79.688676) (xy 153.093375 -79.710114)
			(xy 205.177635 -79.710114) (xy 205.177635 -79.539758) (xy 205.18562 -79.36959) (xy 205.201572 -79.199983)
			(xy 205.225457 -79.031311) (xy 205.257221 -78.863943) (xy 205.296796 -78.698248) (xy 205.344093 -78.53459)
			(xy 205.39901 -78.373329) (xy 205.461425 -78.214819) (xy 205.531201 -78.059409) (xy 205.608184 -77.907441)
			(xy 205.692206 -77.759247) (xy 205.783082 -77.615155) (xy 205.880612 -77.475481) (xy 205.984582 -77.340532)
			(xy 206.094763 -77.210604) (xy 206.210912 -77.085984) (xy 206.332776 -76.966945) (xy 206.460084 -76.853749)
			(xy 206.592559 -76.746644) (xy 206.729909 -76.645867) (xy 206.871831 -76.551638) (xy 207.018013 -76.464165)
			(xy 207.168136 -76.38364) (xy 207.321867 -76.31024) (xy 207.47887 -76.244126) (xy 207.6388 -76.185444)
			(xy 207.801304 -76.134323) (xy 207.966025 -76.090875) (xy 208.132603 -76.055196) (xy 208.300669 -76.027364)
			(xy 208.469855 -76.00744) (xy 208.639789 -75.995468) (xy 208.810098 -75.991475) (xy 208.980407 -75.995468)
			(xy 209.150341 -76.00744) (xy 209.319527 -76.027364) (xy 209.487593 -76.055196) (xy 209.654171 -76.090875)
			(xy 209.818892 -76.134323) (xy 209.981396 -76.185444) (xy 210.141326 -76.244126) (xy 210.298329 -76.31024)
			(xy 210.45206 -76.38364) (xy 210.602183 -76.464165) (xy 210.748365 -76.551638) (xy 210.890287 -76.645867)
			(xy 211.027637 -76.746644) (xy 211.160112 -76.853749) (xy 211.28742 -76.966945) (xy 211.409284 -77.085984)
			(xy 211.525433 -77.210604) (xy 211.635614 -77.340532) (xy 211.739584 -77.475481) (xy 211.837114 -77.615155)
			(xy 211.92799 -77.759247) (xy 212.012012 -77.907441) (xy 212.088995 -78.059409) (xy 212.158771 -78.214819)
			(xy 212.221186 -78.373329) (xy 212.276103 -78.53459) (xy 212.3234 -78.698248) (xy 212.362975 -78.863943)
			(xy 212.394739 -79.031311) (xy 212.418624 -79.199983) (xy 212.434576 -79.36959) (xy 212.442561 -79.539758)
			(xy 212.44306 -79.624936) (xy 212.442561 -79.710114) (xy 235.177575 -79.710114) (xy 235.177575 -79.539758)
			(xy 235.18556 -79.36959) (xy 235.201512 -79.199983) (xy 235.225397 -79.031311) (xy 235.257161 -78.863943)
			(xy 235.296736 -78.698248) (xy 235.344033 -78.53459) (xy 235.39895 -78.373329) (xy 235.461365 -78.214819)
			(xy 235.531141 -78.059409) (xy 235.608124 -77.907441) (xy 235.692146 -77.759247) (xy 235.783022 -77.615155)
			(xy 235.880552 -77.475481) (xy 235.984522 -77.340532) (xy 236.094703 -77.210604) (xy 236.210852 -77.085984)
			(xy 236.332716 -76.966945) (xy 236.460024 -76.853749) (xy 236.592499 -76.746644) (xy 236.729849 -76.645867)
			(xy 236.871771 -76.551638) (xy 237.017953 -76.464165) (xy 237.168076 -76.38364) (xy 237.321807 -76.31024)
			(xy 237.47881 -76.244126) (xy 237.63874 -76.185444) (xy 237.801244 -76.134323) (xy 237.965965 -76.090875)
			(xy 238.132543 -76.055196) (xy 238.300609 -76.027364) (xy 238.469795 -76.00744) (xy 238.639729 -75.995468)
			(xy 238.810038 -75.991475) (xy 238.980347 -75.995468) (xy 239.150281 -76.00744) (xy 239.319467 -76.027364)
			(xy 239.487533 -76.055196) (xy 239.654111 -76.090875) (xy 239.818832 -76.134323) (xy 239.981336 -76.185444)
			(xy 240.141266 -76.244126) (xy 240.298269 -76.31024) (xy 240.452 -76.38364) (xy 240.602123 -76.464165)
			(xy 240.748305 -76.551638) (xy 240.890227 -76.645867) (xy 241.027577 -76.746644) (xy 241.160052 -76.853749)
			(xy 241.28736 -76.966945) (xy 241.409224 -77.085984) (xy 241.525373 -77.210604) (xy 241.635554 -77.340532)
			(xy 241.739524 -77.475481) (xy 241.837054 -77.615155) (xy 241.92793 -77.759247) (xy 242.011952 -77.907441)
			(xy 242.088935 -78.059409) (xy 242.158711 -78.214819) (xy 242.221126 -78.373329) (xy 242.276043 -78.53459)
			(xy 242.32334 -78.698248) (xy 242.362915 -78.863943) (xy 242.394679 -79.031311) (xy 242.418564 -79.199983)
			(xy 242.434516 -79.36959) (xy 242.442501 -79.539758) (xy 242.443 -79.624936) (xy 242.442501 -79.710114)
			(xy 242.434516 -79.880282) (xy 242.418564 -80.049889) (xy 242.394679 -80.218561) (xy 242.362915 -80.385929)
			(xy 242.32334 -80.551624) (xy 242.276043 -80.715282) (xy 242.221126 -80.876543) (xy 242.158711 -81.035053)
			(xy 242.088935 -81.190463) (xy 242.011952 -81.342431) (xy 241.92793 -81.490625) (xy 241.837054 -81.634717)
			(xy 241.739524 -81.774391) (xy 241.635554 -81.90934) (xy 241.525373 -82.039268) (xy 241.409224 -82.163888)
			(xy 241.28736 -82.282927) (xy 241.160052 -82.396123) (xy 241.027577 -82.503228) (xy 240.890227 -82.604005)
			(xy 240.748305 -82.698234) (xy 240.602123 -82.785707) (xy 240.452 -82.866232) (xy 240.298269 -82.939632)
			(xy 240.141266 -83.005746) (xy 239.981336 -83.064428) (xy 239.818832 -83.115549) (xy 239.654111 -83.158997)
			(xy 239.487533 -83.194676) (xy 239.319467 -83.222508) (xy 239.150281 -83.242432) (xy 238.980347 -83.254404)
			(xy 238.810038 -83.258398) (xy 238.639729 -83.254404) (xy 238.469795 -83.242432) (xy 238.300609 -83.222508)
			(xy 238.132543 -83.194676) (xy 237.965965 -83.158997) (xy 237.801244 -83.115549) (xy 237.63874 -83.064428)
			(xy 237.47881 -83.005746) (xy 237.321807 -82.939632) (xy 237.168076 -82.866232) (xy 237.017953 -82.785707)
			(xy 236.871771 -82.698234) (xy 236.729849 -82.604005) (xy 236.592499 -82.503228) (xy 236.460024 -82.396123)
			(xy 236.332716 -82.282927) (xy 236.210852 -82.163888) (xy 236.094703 -82.039268) (xy 235.984522 -81.90934)
			(xy 235.880552 -81.774391) (xy 235.783022 -81.634717) (xy 235.692146 -81.490625) (xy 235.608124 -81.342431)
			(xy 235.531141 -81.190463) (xy 235.461365 -81.035053) (xy 235.39895 -80.876543) (xy 235.344033 -80.715282)
			(xy 235.296736 -80.551624) (xy 235.257161 -80.385929) (xy 235.225397 -80.218561) (xy 235.201512 -80.049889)
			(xy 235.18556 -79.880282) (xy 235.177575 -79.710114) (xy 212.442561 -79.710114) (xy 212.434576 -79.880282)
			(xy 212.418624 -80.049889) (xy 212.394739 -80.218561) (xy 212.362975 -80.385929) (xy 212.3234 -80.551624)
			(xy 212.276103 -80.715282) (xy 212.221186 -80.876543) (xy 212.158771 -81.035053) (xy 212.088995 -81.190463)
			(xy 212.012012 -81.342431) (xy 211.92799 -81.490625) (xy 211.837114 -81.634717) (xy 211.739584 -81.774391)
			(xy 211.635614 -81.90934) (xy 211.525433 -82.039268) (xy 211.409284 -82.163888) (xy 211.28742 -82.282927)
			(xy 211.160112 -82.396123) (xy 211.027637 -82.503228) (xy 210.890287 -82.604005) (xy 210.748365 -82.698234)
			(xy 210.602183 -82.785707) (xy 210.45206 -82.866232) (xy 210.298329 -82.939632) (xy 210.141326 -83.005746)
			(xy 209.981396 -83.064428) (xy 209.818892 -83.115549) (xy 209.654171 -83.158997) (xy 209.487593 -83.194676)
			(xy 209.319527 -83.222508) (xy 209.150341 -83.242432) (xy 208.980407 -83.254404) (xy 208.810098 -83.258398)
			(xy 208.639789 -83.254404) (xy 208.469855 -83.242432) (xy 208.300669 -83.222508) (xy 208.132603 -83.194676)
			(xy 207.966025 -83.158997) (xy 207.801304 -83.115549) (xy 207.6388 -83.064428) (xy 207.47887 -83.005746)
			(xy 207.321867 -82.939632) (xy 207.168136 -82.866232) (xy 207.018013 -82.785707) (xy 206.871831 -82.698234)
			(xy 206.729909 -82.604005) (xy 206.592559 -82.503228) (xy 206.460084 -82.396123) (xy 206.332776 -82.282927)
			(xy 206.210912 -82.163888) (xy 206.094763 -82.039268) (xy 205.984582 -81.90934) (xy 205.880612 -81.774391)
			(xy 205.783082 -81.634717) (xy 205.692206 -81.490625) (xy 205.608184 -81.342431) (xy 205.531201 -81.190463)
			(xy 205.461425 -81.035053) (xy 205.39901 -80.876543) (xy 205.344093 -80.715282) (xy 205.296796 -80.551624)
			(xy 205.257221 -80.385929) (xy 205.225457 -80.218561) (xy 205.201572 -80.049889) (xy 205.18562 -79.880282)
			(xy 205.177635 -79.710114) (xy 153.093375 -79.710114) (xy 153.087511 -79.754625) (xy 153.070284 -79.818875)
			(xy 153.044815 -79.880326) (xy 153.011539 -79.937924) (xy 152.971026 -79.990683) (xy 152.947878 -80.014572)
			(xy 151.866346 -81.096104) (xy 151.842467 -81.119262) (xy 151.789704 -81.159771) (xy 151.732104 -81.193043)
			(xy 151.670652 -81.218509) (xy 151.6064 -81.235732) (xy 151.54045 -81.244417) (xy 151.50719 -81.244948)
			(xy 149.65172 -81.244948) (xy 149.618459 -81.244428) (xy 149.552507 -81.235744) (xy 149.488253 -81.218521)
			(xy 149.426799 -81.193056) (xy 149.369197 -81.159784) (xy 149.316432 -81.119274) (xy 149.292564 -81.096104)
			(xy 148.764752 -80.568292) (xy 148.741593 -80.544413) (xy 148.701083 -80.491651) (xy 148.667808 -80.43405)
			(xy 148.642339 -80.372598) (xy 148.625112 -80.308347) (xy 148.616421 -80.242396) (xy 148.615908 -80.209136)
			(xy 148.615908 -75.67549) (xy 148.61643 -75.64223) (xy 148.625119 -75.576281) (xy 148.642345 -75.512031)
			(xy 148.667815 -75.450581) (xy 148.701092 -75.392983) (xy 148.741607 -75.340225) (xy 148.764752 -75.316334)
			(xy 150.195026 -73.88606) (xy 150.201069 -73.879595) (xy 150.208602 -73.863593) (xy 150.209758 -73.854818)
			(xy 150.210012 -73.852278) (xy 150.210012 -72.829928) (xy 150.209883 -72.824283) (xy 150.207438 -72.813262)
			(xy 150.205186 -72.808084) (xy 150.20036 -72.798178) (xy 150.191978 -72.791066) (xy 150.19147 -72.790558)
			(xy 150.132034 -72.741028) (xy 150.123906 -72.73417) (xy 150.114254 -72.731376) (xy 150.109364 -72.729992)
			(xy 150.099255 -72.728959) (xy 150.094188 -72.729344) (xy 150.090632 -72.729852) (xy 150.0886 -72.730106)
			(xy 150.08733 -72.73036) (xy 150.04972 -72.7365) (xy 149.973797 -72.743112) (xy 149.935692 -72.743568)
			(xy 149.89459 -72.743107) (xy 149.812736 -72.735522) (xy 149.731931 -72.720416) (xy 149.652865 -72.697918)
			(xy 149.576212 -72.668221) (xy 149.502627 -72.631578) (xy 149.432736 -72.588301) (xy 149.367136 -72.53876)
			(xy 149.306388 -72.483378) (xy 149.251009 -72.422627) (xy 149.201472 -72.357024) (xy 149.158199 -72.287131)
			(xy 149.12156 -72.213544) (xy 149.091867 -72.136889) (xy 149.069373 -72.057822) (xy 149.054272 -71.977016)
			(xy 149.04669 -71.895162) (xy 149.046184 -71.85406) (xy 149.046701 -71.81176) (xy 149.054766 -71.727546)
			(xy 149.07079 -71.644478) (xy 149.094629 -71.563306) (xy 149.126066 -71.484765) (xy 149.16482 -71.409563)
			(xy 149.210538 -71.338381) (xy 149.262808 -71.27186) (xy 149.321157 -71.210603) (xy 149.352762 -71.182484)
			(xy 149.35454 -71.180706) (xy 149.358604 -71.17715) (xy 149.364954 -71.168768) (xy 149.36724 -71.163942)
			(xy 149.369402 -71.158877) (xy 149.371712 -71.148112) (xy 149.371812 -71.142606) (xy 149.371812 -71.065136)
			(xy 149.371651 -71.05976) (xy 149.369349 -71.049255) (xy 149.36724 -71.044308) (xy 149.362922 -71.034656)
			(xy 149.35454 -71.02729) (xy 149.352762 -71.025512) (xy 149.321133 -70.997418) (xy 149.262773 -70.936167)
			(xy 149.210495 -70.869648) (xy 149.164774 -70.798464) (xy 149.126023 -70.723258) (xy 149.094592 -70.64471)
			(xy 149.070765 -70.563532) (xy 149.054759 -70.480457) (xy 149.046718 -70.396237) (xy 149.046184 -70.353936)
			(xy 149.046643 -70.312832) (xy 149.054225 -70.230973) (xy 149.069327 -70.150164) (xy 149.091822 -70.071093)
			(xy 149.121517 -69.994434) (xy 149.158158 -69.920843) (xy 149.201433 -69.850946) (xy 149.250973 -69.785341)
			(xy 149.306356 -69.724587) (xy 149.367107 -69.669202) (xy 149.43271 -69.619658) (xy 149.502604 -69.57638)
			(xy 149.576194 -69.539735) (xy 149.652851 -69.510036) (xy 149.731921 -69.487538) (xy 149.81273 -69.472431)
			(xy 149.894588 -69.464845) (xy 149.935692 -69.464428) (xy 149.973797 -69.464877) (xy 150.049721 -69.471493)
			(xy 150.08733 -69.477636) (xy 150.0886 -69.47789) (xy 150.090632 -69.478144) (xy 150.094188 -69.478652)
			(xy 150.099256 -69.479042) (xy 150.109369 -69.478025) (xy 150.114254 -69.47662) (xy 150.123906 -69.473826)
			(xy 150.132034 -69.466968) (xy 150.19147 -69.417438) (xy 150.191978 -69.41693) (xy 150.195986 -69.413319)
			(xy 150.202513 -69.404734) (xy 150.204932 -69.399912) (xy 150.205186 -69.399912) (xy 150.207441 -69.394736)
			(xy 150.209867 -69.383712) (xy 150.210012 -69.378068) (xy 150.210012 -68.742052) (xy 150.209876 -68.737161)
			(xy 150.207959 -68.727568) (xy 150.206202 -68.723002) (xy 150.202392 -68.71335) (xy 150.195026 -68.706238)
			(xy 149.3266 -67.837812) (xy 149.321012 -67.832986) (xy 149.314273 -67.828311) (xy 149.298727 -67.823117)
			(xy 149.290532 -67.822826) (xy 147.28317 -67.822826) (xy 147.276052 -67.823095) (xy 147.262382 -67.827083)
			(xy 147.256246 -67.8307) (xy 147.234402 -67.844416) (xy 147.22475 -67.85229) (xy 147.21967 -67.857624)
			(xy 147.216622 -67.863974) (xy 147.196912 -67.901808) (xy 147.15128 -67.973894) (xy 147.098958 -68.041282)
			(xy 147.040427 -68.103353) (xy 146.976224 -68.159537) (xy 146.906939 -68.209319) (xy 146.833207 -68.252241)
			(xy 146.755706 -68.28791) (xy 146.675147 -68.315998) (xy 146.59227 -68.336247) (xy 146.507835 -68.348471)
			(xy 146.422618 -68.352558) (xy 146.337401 -68.348471) (xy 146.252966 -68.336247) (xy 146.170089 -68.315998)
			(xy 146.08953 -68.28791) (xy 146.012029 -68.252241) (xy 145.938297 -68.209319) (xy 145.869012 -68.159537)
			(xy 145.804809 -68.103353) (xy 145.746278 -68.041282) (xy 145.693956 -67.973894) (xy 145.648324 -67.901808)
			(xy 145.628614 -67.863974) (xy 145.625566 -67.857624) (xy 145.620486 -67.85229) (xy 145.610834 -67.844416)
			(xy 145.58899 -67.8307) (xy 145.582849 -67.82709) (xy 145.569184 -67.823085) (xy 145.562066 -67.822826)
			(xy 143.881094 -67.822826) (xy 143.869396 -67.823417) (xy 143.848422 -67.833783) (xy 143.834209 -67.852368)
			(xy 143.83131 -67.86372) (xy 143.822475 -67.905714) (xy 143.797778 -67.987905) (xy 143.76527 -68.067331)
			(xy 143.745712 -68.105528) (xy 143.742918 -68.110862) (xy 143.73987 -68.122292) (xy 143.738446 -68.128564)
			(xy 143.738444 -68.141421) (xy 143.73987 -68.147692) (xy 143.742918 -68.159122) (xy 143.745712 -68.164456)
			(xy 143.76546 -68.202935) (xy 143.798258 -68.28297) (xy 143.823141 -68.365808) (xy 143.839874 -68.450669)
			(xy 143.8483 -68.536753) (xy 143.848836 -68.58) (xy 143.848836 -68.580508) (xy 143.848319 -68.623585)
			(xy 143.839966 -68.709334) (xy 143.82336 -68.793873) (xy 143.798655 -68.876409) (xy 143.766084 -68.95617)
			(xy 143.746474 -68.994528) (xy 143.743426 -69.000116) (xy 143.740632 -69.011546) (xy 143.739108 -69.017896)
			(xy 143.739108 -69.030342) (xy 143.74368 -69.047868) (xy 143.746474 -69.053202) (xy 143.766183 -69.091665)
			(xy 143.798911 -69.171661) (xy 143.823737 -69.25445) (xy 143.84043 -69.339254) (xy 143.84883 -69.425276)
			(xy 143.849344 -69.468492) (xy 143.849344 -69.469) (xy 143.848788 -69.51276) (xy 143.840171 -69.599855)
			(xy 143.823059 -69.685686) (xy 143.797617 -69.769426) (xy 143.76409 -69.85027) (xy 143.743934 -69.889116)
			(xy 143.740886 -69.894704) (xy 143.737838 -69.906642) (xy 143.737838 -69.920358) (xy 143.740886 -69.932296)
			(xy 143.743934 -69.937884) (xy 143.764135 -69.976709) (xy 143.797683 -70.057551) (xy 143.823132 -70.141295)
			(xy 143.840235 -70.227134) (xy 143.848829 -70.314237) (xy 143.849344 -70.358) (xy 143.84884 -70.400397)
			(xy 143.84078 -70.484807) (xy 143.824732 -70.568068) (xy 143.800843 -70.649427) (xy 143.769328 -70.728147)
			(xy 143.730474 -70.803515) (xy 143.684631 -70.874848) (xy 143.632215 -70.9415) (xy 143.5737 -71.002868)
			(xy 143.509618 -71.058396) (xy 143.440547 -71.107581) (xy 143.367113 -71.149978) (xy 143.289982 -71.185203)
			(xy 143.209852 -71.212936) (xy 143.127448 -71.232927) (xy 143.043518 -71.244994) (xy 142.95882 -71.249029)
			(xy 142.874122 -71.244994) (xy 142.790192 -71.232927) (xy 142.707788 -71.212936) (xy 142.627658 -71.185203)
			(xy 142.550527 -71.149978) (xy 142.477093 -71.107581) (xy 142.408022 -71.058396) (xy 142.34394 -71.002868)
			(xy 142.285425 -70.9415) (xy 142.233009 -70.874848) (xy 142.187166 -70.803515) (xy 142.148312 -70.728147)
			(xy 142.116797 -70.649427) (xy 142.092908 -70.568068) (xy 142.07686 -70.484807) (xy 142.0688 -70.400397)
			(xy 142.068296 -70.358) (xy 142.068852 -70.31424) (xy 142.07747 -70.227146) (xy 142.094582 -70.141315)
			(xy 142.120025 -70.057575) (xy 142.153554 -69.976732) (xy 142.173706 -69.937884) (xy 142.176754 -69.932296)
			(xy 142.179802 -69.920358) (xy 142.179802 -69.906642) (xy 142.176754 -69.894704) (xy 142.173706 -69.889116)
			(xy 142.153504 -69.850291) (xy 142.119955 -69.76945) (xy 142.094505 -69.685705) (xy 142.077401 -69.599866)
			(xy 142.068807 -69.512763) (xy 142.068296 -69.469) (xy 142.068296 -69.468492) (xy 142.068817 -69.425276)
			(xy 142.07721 -69.339252) (xy 142.093895 -69.254446) (xy 142.118717 -69.171655) (xy 142.151442 -69.091658)
			(xy 142.171166 -69.053202) (xy 142.17396 -69.047868) (xy 142.178532 -69.030342) (xy 142.178532 -69.017896)
			(xy 142.177008 -69.011546) (xy 142.174214 -69.000116) (xy 142.171166 -68.994528) (xy 142.151561 -68.956169)
			(xy 142.11901 -68.876403) (xy 142.094316 -68.793866) (xy 142.077711 -68.709329) (xy 142.069349 -68.623584)
			(xy 142.068804 -68.580508) (xy 142.068804 -68.58) (xy 142.069328 -68.536752) (xy 142.077743 -68.450665)
			(xy 142.094473 -68.365802) (xy 142.119361 -68.282964) (xy 142.152172 -68.202931) (xy 142.171928 -68.164456)
			(xy 142.174722 -68.159122) (xy 142.17777 -68.147692) (xy 142.179193 -68.14142) (xy 142.179191 -68.128564)
			(xy 142.17777 -68.122292) (xy 142.174722 -68.110862) (xy 142.171928 -68.105528) (xy 142.152388 -68.067323)
			(xy 142.119889 -67.987895) (xy 142.095183 -67.905709) (xy 142.08633 -67.86372) (xy 142.084276 -67.855092)
			(xy 142.075195 -67.839873) (xy 142.06855 -67.834002) (xy 142.061946 -67.828668) (xy 142.04569 -67.822826)
			(xy 140.923772 -67.822826) (xy 140.916653 -67.823094) (xy 140.902984 -67.827082) (xy 140.896848 -67.8307)
			(xy 140.875004 -67.844416) (xy 140.865352 -67.85229) (xy 140.860272 -67.857624) (xy 140.857224 -67.863974)
			(xy 140.837514 -67.901808) (xy 140.791882 -67.973894) (xy 140.73956 -68.041282) (xy 140.681029 -68.103353)
			(xy 140.616826 -68.159537) (xy 140.547541 -68.209319) (xy 140.473809 -68.252241) (xy 140.396308 -68.28791)
			(xy 140.315749 -68.315998) (xy 140.232872 -68.336247) (xy 140.148437 -68.348471) (xy 140.06322 -68.352558)
			(xy 139.978003 -68.348471) (xy 139.893568 -68.336247) (xy 139.810691 -68.315998) (xy 139.730132 -68.28791)
			(xy 139.652631 -68.252241) (xy 139.578899 -68.209319) (xy 139.509614 -68.159537) (xy 139.445411 -68.103353)
			(xy 139.38688 -68.041282) (xy 139.334558 -67.973894) (xy 139.288926 -67.901808) (xy 139.269216 -67.863974)
			(xy 139.266168 -67.857624) (xy 139.261088 -67.85229) (xy 139.251436 -67.844416) (xy 139.229592 -67.8307)
			(xy 139.223451 -67.827089) (xy 139.209786 -67.823084) (xy 139.202668 -67.822826) (xy 138.086846 -67.822826)
			(xy 138.081955 -67.822963) (xy 138.072363 -67.824882) (xy 138.067796 -67.826636) (xy 138.058144 -67.830446)
			(xy 138.051032 -67.837812) (xy 137.389616 -68.499228) (xy 137.38479 -68.504816) (xy 137.380119 -68.511555)
			(xy 137.374932 -68.527102) (xy 137.37463 -68.535296) (xy 137.37463 -74.360278) (xy 144.227042 -74.360278)
			(xy 144.227574 -74.317154) (xy 144.235931 -74.231312) (xy 144.252553 -74.146681) (xy 144.277287 -74.064056)
			(xy 144.309898 -73.984211) (xy 144.350081 -73.907896) (xy 144.373346 -73.871582) (xy 144.377929 -73.863989)
			(xy 144.382028 -73.846746) (xy 144.380005 -73.829138) (xy 144.376394 -73.821036) (xy 144.35832 -73.783865)
			(xy 144.328314 -73.706846) (xy 144.305579 -73.627376) (xy 144.290308 -73.54614) (xy 144.282635 -73.463839)
			(xy 144.28216 -73.42251) (xy 144.282664 -73.380162) (xy 144.290715 -73.295848) (xy 144.306744 -73.212682)
			(xy 144.330605 -73.131415) (xy 144.362084 -73.052785) (xy 144.400895 -72.977504) (xy 144.446685 -72.906252)
			(xy 144.499041 -72.839676) (xy 144.557489 -72.778378) (xy 144.621499 -72.722913) (xy 144.690491 -72.673784)
			(xy 144.763841 -72.631435) (xy 144.840884 -72.596251) (xy 144.920923 -72.568549) (xy 145.003232 -72.548581)
			(xy 145.087067 -72.536528) (xy 145.171668 -72.532498) (xy 145.256269 -72.536528) (xy 145.340104 -72.548581)
			(xy 145.422413 -72.568549) (xy 145.502452 -72.596251) (xy 145.579495 -72.631435) (xy 145.652845 -72.673784)
			(xy 145.721837 -72.722913) (xy 145.785847 -72.778378) (xy 145.844295 -72.839676) (xy 145.896651 -72.906252)
			(xy 145.942441 -72.977504) (xy 145.981252 -73.052785) (xy 146.012731 -73.131415) (xy 146.036592 -73.212682)
			(xy 146.052621 -73.295848) (xy 146.060672 -73.380162) (xy 146.061176 -73.42251) (xy 146.060651 -73.465634)
			(xy 146.052295 -73.551477) (xy 146.035672 -73.636108) (xy 146.010937 -73.718734) (xy 145.978324 -73.798579)
			(xy 145.938138 -73.874893) (xy 145.914872 -73.911206) (xy 145.9103 -73.918803) (xy 145.906204 -73.936044)
			(xy 145.90822 -73.953649) (xy 145.911824 -73.961752) (xy 145.929895 -73.998924) (xy 145.959901 -74.075943)
			(xy 145.982637 -74.155413) (xy 145.997908 -74.236648) (xy 146.005582 -74.318949) (xy 146.006058 -74.360278)
			(xy 146.005554 -74.402626) (xy 145.997503 -74.48694) (xy 145.981474 -74.570106) (xy 145.957613 -74.651373)
			(xy 145.926134 -74.730003) (xy 145.887323 -74.805284) (xy 145.841533 -74.876536) (xy 145.789177 -74.943112)
			(xy 145.730729 -75.00441) (xy 145.666719 -75.059875) (xy 145.597727 -75.109004) (xy 145.524377 -75.151353)
			(xy 145.447334 -75.186537) (xy 145.367295 -75.214239) (xy 145.284986 -75.234207) (xy 145.201151 -75.24626)
			(xy 145.11655 -75.250291) (xy 145.031949 -75.24626) (xy 144.948114 -75.234207) (xy 144.865805 -75.214239)
			(xy 144.785766 -75.186537) (xy 144.708723 -75.151353) (xy 144.635373 -75.109004) (xy 144.566381 -75.059875)
			(xy 144.502371 -75.00441) (xy 144.443923 -74.943112) (xy 144.391567 -74.876536) (xy 144.345777 -74.805284)
			(xy 144.306966 -74.730003) (xy 144.275487 -74.651373) (xy 144.251626 -74.570106) (xy 144.235597 -74.48694)
			(xy 144.227546 -74.402626) (xy 144.227042 -74.360278) (xy 137.37463 -74.360278) (xy 137.37463 -76.8584)
			(xy 142.64304 -76.8584) (xy 142.64707 -76.773794) (xy 142.659125 -76.689953) (xy 142.679094 -76.607639)
			(xy 142.706798 -76.527595) (xy 142.741985 -76.450547) (xy 142.784337 -76.377193) (xy 142.833469 -76.308197)
			(xy 142.888938 -76.244183) (xy 142.95024 -76.185733) (xy 143.016821 -76.133374) (xy 143.088078 -76.087581)
			(xy 143.163365 -76.048769) (xy 143.242 -76.017289) (xy 143.323272 -75.993427) (xy 143.406444 -75.977398)
			(xy 143.490763 -75.969347) (xy 143.533114 -75.96886) (xy 143.576292 -75.969355) (xy 143.662241 -75.977727)
			(xy 143.746974 -75.994392) (xy 143.829693 -76.019192) (xy 143.909618 -76.051894) (xy 143.985996 -76.092189)
			(xy 144.058109 -76.139699) (xy 144.125276 -76.193975) (xy 144.15643 -76.223876) (xy 144.156684 -76.22413)
			(xy 144.163767 -76.230435) (xy 144.181257 -76.237736) (xy 144.19072 -76.238354) (xy 144.27073 -76.239878)
			(xy 144.28851 -76.233274) (xy 144.295876 -76.22667) (xy 144.326488 -76.199565) (xy 144.391905 -76.150502)
			(xy 144.461549 -76.107652) (xy 144.534833 -76.071377) (xy 144.611137 -76.041982) (xy 144.689818 -76.019717)
			(xy 144.770211 -76.004769) (xy 144.851637 -75.997264) (xy 144.892522 -75.9968) (xy 144.93487 -75.997289)
			(xy 145.019183 -76.005341) (xy 145.102348 -76.021372) (xy 145.183614 -76.045236) (xy 145.262242 -76.076716)
			(xy 145.337523 -76.115527) (xy 145.408773 -76.161318) (xy 145.475349 -76.213675) (xy 145.536645 -76.272123)
			(xy 145.592109 -76.336133) (xy 145.641237 -76.405125) (xy 145.683585 -76.478475) (xy 145.718768 -76.555518)
			(xy 145.74647 -76.635556) (xy 145.766437 -76.717865) (xy 145.778491 -76.8017) (xy 145.782521 -76.8863)
			(xy 145.778491 -76.9709) (xy 145.766437 -77.054735) (xy 145.74647 -77.137044) (xy 145.718768 -77.217082)
			(xy 145.683585 -77.294125) (xy 145.641237 -77.367475) (xy 145.592109 -77.436467) (xy 145.536645 -77.500477)
			(xy 145.475349 -77.558925) (xy 145.408773 -77.611282) (xy 145.337523 -77.657073) (xy 145.262242 -77.695884)
			(xy 145.183614 -77.727364) (xy 145.102348 -77.751228) (xy 145.019183 -77.767259) (xy 144.93487 -77.775311)
			(xy 144.892522 -77.775816) (xy 144.849344 -77.775305) (xy 144.763395 -77.766935) (xy 144.678663 -77.750274)
			(xy 144.595944 -77.725476) (xy 144.516019 -77.692777) (xy 144.43964 -77.652483) (xy 144.367528 -77.604975)
			(xy 144.30036 -77.5507) (xy 144.269206 -77.5208) (xy 144.268952 -77.520546) (xy 144.26186 -77.514253)
			(xy 144.244377 -77.506946) (xy 144.234916 -77.506322) (xy 144.154906 -77.504798) (xy 144.137126 -77.511402)
			(xy 144.12976 -77.518006) (xy 144.099129 -77.54509) (xy 144.033716 -77.594154) (xy 143.964075 -77.637007)
			(xy 143.890794 -77.673285) (xy 143.814492 -77.702683) (xy 143.735813 -77.724951) (xy 143.655423 -77.739902)
			(xy 143.573999 -77.747411) (xy 143.533114 -77.747876) (xy 143.490763 -77.747453) (xy 143.406444 -77.739402)
			(xy 143.323272 -77.723373) (xy 143.242 -77.699511) (xy 143.163365 -77.668031) (xy 143.088078 -77.629219)
			(xy 143.016821 -77.583426) (xy 142.95024 -77.531067) (xy 142.888938 -77.472617) (xy 142.833469 -77.408603)
			(xy 142.784337 -77.339607) (xy 142.741985 -77.266253) (xy 142.706798 -77.189205) (xy 142.679094 -77.109161)
			(xy 142.659125 -77.026847) (xy 142.64707 -76.943006) (xy 142.64304 -76.8584) (xy 137.37463 -76.8584)
			(xy 137.37463 -79.89062) (xy 137.374107 -79.92388) (xy 137.365418 -79.989829) (xy 137.348191 -80.054079)
			(xy 137.322722 -80.115529) (xy 137.289446 -80.173127) (xy 137.248933 -80.225887) (xy 137.225786 -80.249776)
			(xy 136.598406 -80.877156) (xy 136.574527 -80.900315) (xy 136.521765 -80.940827) (xy 136.464165 -80.974102)
			(xy 136.402713 -80.999573) (xy 136.338461 -81.016801) (xy 136.272511 -81.025493) (xy 136.23925 -81.026)
			(xy 123.4694 -81.026) (xy 123.448826 -81.025492) (xy 123.438412 -81.024984) (xy 123.428506 -81.028794)
			(xy 123.423882 -81.030711) (xy 123.415441 -81.036089) (xy 123.411742 -81.039462) (xy 123.358148 -81.090262)
			(xy 123.351034 -81.097688) (xy 123.342923 -81.116566) (xy 123.3424 -81.126838) (xy 123.3424 -82.3041)
			(xy 175.3616 -82.3041) (xy 175.36563 -82.219499) (xy 175.377684 -82.135664) (xy 175.397652 -82.053355)
			(xy 175.425354 -81.973317) (xy 175.460539 -81.896274) (xy 175.502888 -81.822925) (xy 175.552017 -81.753933)
			(xy 175.607482 -81.689924) (xy 175.668781 -81.631477) (xy 175.735357 -81.579122) (xy 175.806609 -81.533332)
			(xy 175.881891 -81.494523) (xy 175.960521 -81.463045) (xy 176.041788 -81.439185) (xy 176.124954 -81.423157)
			(xy 176.209268 -81.415107) (xy 176.251616 -81.41462) (xy 176.252378 -81.41462) (xy 176.293924 -81.415132)
			(xy 176.37665 -81.422912) (xy 176.458292 -81.438368) (xy 176.538137 -81.461365) (xy 176.57699 -81.476088)
			(xy 176.586068 -81.479207) (xy 176.60525 -81.479207) (xy 176.614328 -81.476088) (xy 176.653174 -81.461346)
			(xy 176.733019 -81.438336) (xy 176.814663 -81.422879) (xy 176.897393 -81.415109) (xy 176.93894 -81.41462)
			(xy 176.939702 -81.41462) (xy 176.982052 -81.415068) (xy 177.066368 -81.423119) (xy 177.149537 -81.439149)
			(xy 177.230805 -81.463012) (xy 177.309438 -81.494491) (xy 177.384721 -81.533303) (xy 177.455975 -81.579095)
			(xy 177.522553 -81.631453) (xy 177.583853 -81.689902) (xy 177.63932 -81.753914) (xy 177.68845 -81.822908)
			(xy 177.7308 -81.89626) (xy 177.765985 -81.973306) (xy 177.793688 -82.053347) (xy 177.813656 -82.135659)
			(xy 177.82571 -82.219496) (xy 177.829741 -82.3041) (xy 177.82571 -82.388704) (xy 177.813656 -82.472541)
			(xy 177.793688 -82.554853) (xy 177.765985 -82.634894) (xy 177.7308 -82.71194) (xy 177.68845 -82.785292)
			(xy 177.63932 -82.854286) (xy 177.583853 -82.918298) (xy 177.522553 -82.976747) (xy 177.455975 -83.029105)
			(xy 177.384721 -83.074897) (xy 177.309438 -83.113709) (xy 177.230805 -83.145188) (xy 177.149537 -83.169051)
			(xy 177.066368 -83.185081) (xy 176.982052 -83.193132) (xy 176.939702 -83.193636) (xy 176.93894 -83.193636)
			(xy 176.897394 -83.193153) (xy 176.814666 -83.185365) (xy 176.733025 -83.169901) (xy 176.65318 -83.146895)
			(xy 176.614328 -83.132168) (xy 176.605259 -83.128992) (xy 176.586059 -83.128992) (xy 176.57699 -83.132168)
			(xy 176.538143 -83.146908) (xy 176.458298 -83.169917) (xy 176.376655 -83.185375) (xy 176.293925 -83.193146)
			(xy 176.252378 -83.193636) (xy 176.251616 -83.193636) (xy 176.209268 -83.193093) (xy 176.124954 -83.185043)
			(xy 176.041788 -83.169015) (xy 175.960521 -83.145155) (xy 175.881891 -83.113677) (xy 175.806609 -83.074868)
			(xy 175.735357 -83.029078) (xy 175.668781 -82.976723) (xy 175.607482 -82.918276) (xy 175.552017 -82.854267)
			(xy 175.502888 -82.785275) (xy 175.460539 -82.711926) (xy 175.425354 -82.634883) (xy 175.397652 -82.554845)
			(xy 175.377684 -82.472536) (xy 175.36563 -82.388701) (xy 175.3616 -82.3041) (xy 123.3424 -82.3041)
			(xy 123.3424 -82.55) (xy 123.341937 -82.5807) (xy 123.334536 -82.641653) (xy 123.319842 -82.70127)
			(xy 123.298069 -82.75868) (xy 123.269534 -82.813048) (xy 123.234655 -82.86358) (xy 123.193939 -82.909539)
			(xy 123.14798 -82.950255) (xy 123.097448 -82.985134) (xy 123.04308 -83.013669) (xy 122.98567 -83.035442)
			(xy 122.926053 -83.050136) (xy 122.8651 -83.057537) (xy 122.8344 -83.058) (xy 115.266216 -83.058)
			(xy 115.253658 -83.058638) (xy 115.231515 -83.070488) (xy 115.224052 -83.080606) (xy 115.177062 -83.151472)
			(xy 115.173765 -83.156672) (xy 115.169538 -83.168234) (xy 115.16868 -83.174332) (xy 115.16741 -83.187032)
			(xy 115.17249 -83.19897) (xy 115.17249 -83.199478) (xy 115.185382 -83.231035) (xy 115.203559 -83.296736)
			(xy 115.212793 -83.364277) (xy 115.213384 -83.39836) (xy 115.213384 -83.608361) (xy 127.713228 -83.608361)
			(xy 127.713228 -83.523639) (xy 127.721281 -83.439302) (xy 127.737315 -83.356112) (xy 127.761183 -83.274822)
			(xy 127.792671 -83.19617) (xy 127.831493 -83.120867) (xy 127.877296 -83.049595) (xy 127.929667 -82.982999)
			(xy 127.988132 -82.921684) (xy 128.05216 -82.866203) (xy 128.121172 -82.81706) (xy 128.194542 -82.7747)
			(xy 128.271607 -82.739505) (xy 128.351669 -82.711796) (xy 128.434002 -82.691822) (xy 128.517861 -82.679765)
			(xy 128.602486 -82.675734) (xy 128.687111 -82.679765) (xy 128.77097 -82.691822) (xy 128.853303 -82.711796)
			(xy 128.933365 -82.739505) (xy 129.01043 -82.7747) (xy 129.0838 -82.81706) (xy 129.152812 -82.866203)
			(xy 129.21684 -82.921684) (xy 129.275305 -82.982999) (xy 129.327676 -83.049595) (xy 129.373479 -83.120867)
			(xy 129.412301 -83.19617) (xy 129.443789 -83.274822) (xy 129.467657 -83.356112) (xy 129.483691 -83.439302)
			(xy 129.491744 -83.523639) (xy 129.492248 -83.566) (xy 129.491744 -83.608361) (xy 130.532882 -83.608361)
			(xy 130.532882 -83.523639) (xy 130.540935 -83.439302) (xy 130.556969 -83.356112) (xy 130.580837 -83.274822)
			(xy 130.612325 -83.19617) (xy 130.651147 -83.120867) (xy 130.69695 -83.049595) (xy 130.749321 -82.982999)
			(xy 130.807786 -82.921684) (xy 130.871814 -82.866203) (xy 130.940826 -82.81706) (xy 131.014196 -82.7747)
			(xy 131.091261 -82.739505) (xy 131.171323 -82.711796) (xy 131.253656 -82.691822) (xy 131.337515 -82.679765)
			(xy 131.42214 -82.675734) (xy 131.506765 -82.679765) (xy 131.590624 -82.691822) (xy 131.672957 -82.711796)
			(xy 131.753019 -82.739505) (xy 131.830084 -82.7747) (xy 131.903454 -82.81706) (xy 131.972466 -82.866203)
			(xy 132.036494 -82.921684) (xy 132.094959 -82.982999) (xy 132.14733 -83.049595) (xy 132.193133 -83.120867)
			(xy 132.231955 -83.19617) (xy 132.263443 -83.274822) (xy 132.287311 -83.356112) (xy 132.303345 -83.439302)
			(xy 132.311398 -83.523639) (xy 132.311902 -83.566) (xy 132.311398 -83.608361) (xy 132.303345 -83.692698)
			(xy 132.287311 -83.775888) (xy 132.263443 -83.857178) (xy 132.231955 -83.93583) (xy 132.193133 -84.011133)
			(xy 132.14733 -84.082405) (xy 132.094959 -84.149001) (xy 132.036494 -84.210316) (xy 131.972466 -84.265797)
			(xy 131.903454 -84.31494) (xy 131.830084 -84.3573) (xy 131.753019 -84.392495) (xy 131.672957 -84.420204)
			(xy 131.590624 -84.440178) (xy 131.506765 -84.452235) (xy 131.42214 -84.456267) (xy 131.337515 -84.452235)
			(xy 131.253656 -84.440178) (xy 131.171323 -84.420204) (xy 131.091261 -84.392495) (xy 131.014196 -84.3573)
			(xy 130.940826 -84.31494) (xy 130.871814 -84.265797) (xy 130.807786 -84.210316) (xy 130.749321 -84.149001)
			(xy 130.69695 -84.082405) (xy 130.651147 -84.011133) (xy 130.612325 -83.93583) (xy 130.580837 -83.857178)
			(xy 130.556969 -83.775888) (xy 130.540935 -83.692698) (xy 130.532882 -83.608361) (xy 129.491744 -83.608361)
			(xy 129.483691 -83.692698) (xy 129.467657 -83.775888) (xy 129.443789 -83.857178) (xy 129.412301 -83.93583)
			(xy 129.373479 -84.011133) (xy 129.327676 -84.082405) (xy 129.275305 -84.149001) (xy 129.21684 -84.210316)
			(xy 129.152812 -84.265797) (xy 129.0838 -84.31494) (xy 129.01043 -84.3573) (xy 128.933365 -84.392495)
			(xy 128.853303 -84.420204) (xy 128.77097 -84.440178) (xy 128.687111 -84.452235) (xy 128.602486 -84.456267)
			(xy 128.517861 -84.452235) (xy 128.434002 -84.440178) (xy 128.351669 -84.420204) (xy 128.271607 -84.392495)
			(xy 128.194542 -84.3573) (xy 128.121172 -84.31494) (xy 128.05216 -84.265797) (xy 127.988132 -84.210316)
			(xy 127.929667 -84.149001) (xy 127.877296 -84.082405) (xy 127.831493 -84.011133) (xy 127.792671 -83.93583)
			(xy 127.761183 -83.857178) (xy 127.737315 -83.775888) (xy 127.721281 -83.692698) (xy 127.713228 -83.608361)
			(xy 115.213384 -83.608361) (xy 115.213384 -85.048344) (xy 115.213716 -85.057237) (xy 115.219798 -85.073949)
			(xy 115.231243 -85.087561) (xy 115.238784 -85.092286) (xy 115.312952 -85.134958) (xy 115.321792 -85.139585)
			(xy 115.34156 -85.142186) (xy 115.351306 -85.140038) (xy 115.365784 -85.136228) (xy 115.371372 -85.13318)
			(xy 115.411566 -85.111034) (xy 115.495628 -85.074206) (xy 115.583035 -85.046229) (xy 115.672858 -85.027401)
			(xy 115.764143 -85.017923) (xy 115.81003 -85.017356) (xy 115.810538 -85.017356) (xy 115.856902 -85.017952)
			(xy 115.949128 -85.027597) (xy 116.039848 -85.04679) (xy 116.128078 -85.075321) (xy 116.17071 -85.093556)
			(xy 116.170964 -85.093556) (xy 116.180616 -85.095588) (xy 116.185904 -85.096588) (xy 116.196664 -85.096588)
			(xy 116.201952 -85.095588) (xy 116.211604 -85.093556) (xy 116.211858 -85.093556) (xy 116.254463 -85.075341)
			(xy 116.342632 -85.046828) (xy 116.433286 -85.027632) (xy 116.525444 -85.017959) (xy 116.571776 -85.017356)
			(xy 116.572284 -85.017356) (xy 116.613523 -85.017821) (xy 116.695648 -85.025452) (xy 116.776715 -85.04065)
			(xy 116.856027 -85.063285) (xy 116.932904 -85.093162) (xy 117.006687 -85.130025) (xy 117.076742 -85.173557)
			(xy 117.142468 -85.223385) (xy 117.203301 -85.279082) (xy 117.258718 -85.340169) (xy 117.308245 -85.406123)
			(xy 117.351456 -85.476376) (xy 117.370098 -85.513164) (xy 117.373654 -85.520276) (xy 117.378988 -85.525864)
			(xy 117.381747 -85.528701) (xy 117.388001 -85.533548) (xy 117.391434 -85.535516) (xy 117.397122 -85.538367)
			(xy 117.409458 -85.541459) (xy 117.415818 -85.541612) (xy 117.50675 -85.541612) (xy 117.513188 -85.541421)
			(xy 117.525657 -85.538204) (xy 117.531388 -85.535262) (xy 117.538246 -85.531452) (xy 117.548914 -85.520276)
			(xy 117.55247 -85.513164) (xy 117.571147 -85.476395) (xy 117.614353 -85.406142) (xy 117.663875 -85.340189)
			(xy 117.719289 -85.279103) (xy 117.780118 -85.223407) (xy 117.845841 -85.17358) (xy 117.915893 -85.130049)
			(xy 117.989674 -85.093189) (xy 118.066549 -85.063316) (xy 118.145859 -85.040685) (xy 118.226924 -85.025492)
			(xy 118.309046 -85.017866) (xy 118.350284 -85.017356) (xy 118.350792 -85.017356) (xy 118.397092 -85.017977)
			(xy 118.489186 -85.027652) (xy 118.579776 -85.046847) (xy 118.66788 -85.075353) (xy 118.710456 -85.093556)
			(xy 118.710964 -85.093556) (xy 118.716999 -85.096015) (xy 118.729863 -85.098075) (xy 118.736364 -85.09762)
			(xy 118.744746 -85.096858) (xy 118.788141 -85.077828) (xy 118.878086 -85.048006) (xy 118.97069 -85.027907)
			(xy 119.064905 -85.017756) (xy 119.112284 -85.017102) (xy 119.158653 -85.017743) (xy 119.250881 -85.027469)
			(xy 119.3416 -85.046723) (xy 119.429828 -85.075298) (xy 119.472456 -85.093556) (xy 119.482362 -85.097874)
			(xy 119.504206 -85.097874) (xy 119.514112 -85.093556) (xy 119.556736 -85.075285) (xy 119.644957 -85.046681)
			(xy 119.735679 -85.027425) (xy 119.827913 -85.017728) (xy 119.874284 -85.017102) (xy 119.917781 -85.017628)
			(xy 120.004359 -85.02612) (xy 120.089694 -85.043025) (xy 120.17297 -85.068181) (xy 120.253393 -85.101347)
			(xy 120.330194 -85.142207) (xy 120.402638 -85.19037) (xy 120.470033 -85.245376) (xy 120.531736 -85.306699)
			(xy 120.587157 -85.373754) (xy 120.6119 -85.409532) (xy 120.615202 -85.414358) (xy 120.625362 -85.423756)
			(xy 120.630592 -85.428187) (xy 120.642821 -85.43437) (xy 120.649492 -85.435948) (xy 120.659652 -85.436964)
			(xy 120.742202 -85.436964) (xy 120.754757 -85.43632) (xy 120.776886 -85.424461) (xy 120.784366 -85.414358)
			(xy 120.809039 -85.378199) (xy 120.86444 -85.310416) (xy 120.92623 -85.248402) (xy 120.993813 -85.192756)
			(xy 121.066534 -85.144018) (xy 121.14369 -85.102658) (xy 121.224536 -85.069075) (xy 121.308289 -85.043596)
			(xy 121.39414 -85.026466) (xy 121.481259 -85.017851) (xy 121.52503 -85.017356) (xy 121.525538 -85.017356)
			(xy 121.571902 -85.017952) (xy 121.664128 -85.027597) (xy 121.754848 -85.04679) (xy 121.843078 -85.075321)
			(xy 121.88571 -85.093556) (xy 121.885964 -85.093556) (xy 121.895616 -85.095588) (xy 121.900904 -85.096588)
			(xy 121.911664 -85.096588) (xy 121.916952 -85.095588) (xy 121.926604 -85.093556) (xy 121.926858 -85.093556)
			(xy 121.969493 -85.075328) (xy 122.057723 -85.046799) (xy 122.148442 -85.0276) (xy 122.240666 -85.017939)
			(xy 122.28703 -85.017356) (xy 122.287538 -85.017356) (xy 122.333902 -85.017952) (xy 122.426128 -85.027597)
			(xy 122.516848 -85.04679) (xy 122.605078 -85.075321) (xy 122.64771 -85.093556) (xy 122.647964 -85.093556)
			(xy 122.657616 -85.095588) (xy 122.662904 -85.096588) (xy 122.673664 -85.096588) (xy 122.678952 -85.095588)
			(xy 122.688604 -85.093556) (xy 122.688858 -85.093556) (xy 122.731463 -85.075341) (xy 122.819632 -85.046828)
			(xy 122.910286 -85.027632) (xy 123.002444 -85.017959) (xy 123.048776 -85.017356) (xy 123.049284 -85.017356)
			(xy 123.090388 -85.01783) (xy 123.172244 -85.025413) (xy 123.253052 -85.040517) (xy 123.332121 -85.063013)
			(xy 123.408778 -85.092707) (xy 123.482368 -85.129349) (xy 123.552263 -85.172623) (xy 123.617867 -85.222162)
			(xy 123.67862 -85.277543) (xy 123.734004 -85.338293) (xy 123.783547 -85.403894) (xy 123.826826 -85.473787)
			(xy 123.863472 -85.547375) (xy 123.893171 -85.624029) (xy 123.915671 -85.703097) (xy 123.930779 -85.783904)
			(xy 123.938368 -85.86576) (xy 123.938792 -85.906864) (xy 123.938792 -85.907372) (xy 123.938172 -85.953672)
			(xy 123.928498 -86.045767) (xy 123.911227 -86.127279) (xy 159.685986 -86.127279) (xy 159.685986 -86.042557)
			(xy 159.694039 -85.95822) (xy 159.710073 -85.87503) (xy 159.733941 -85.79374) (xy 159.765429 -85.715088)
			(xy 159.804251 -85.639785) (xy 159.850054 -85.568513) (xy 159.902425 -85.501917) (xy 159.96089 -85.440602)
			(xy 160.024918 -85.385121) (xy 160.09393 -85.335978) (xy 160.1673 -85.293618) (xy 160.244365 -85.258423)
			(xy 160.324427 -85.230714) (xy 160.40676 -85.21074) (xy 160.490619 -85.198683) (xy 160.575244 -85.194652)
			(xy 160.659869 -85.198683) (xy 160.743728 -85.21074) (xy 160.826061 -85.230714) (xy 160.906123 -85.258423)
			(xy 160.983188 -85.293618) (xy 161.056558 -85.335978) (xy 161.12557 -85.385121) (xy 161.189598 -85.440602)
			(xy 161.248063 -85.501917) (xy 161.300434 -85.568513) (xy 161.346237 -85.639785) (xy 161.385059 -85.715088)
			(xy 161.416547 -85.79374) (xy 161.440415 -85.87503) (xy 161.456449 -85.95822) (xy 161.464502 -86.042557)
			(xy 161.465006 -86.084918) (xy 161.464502 -86.127279) (xy 161.456449 -86.211616) (xy 161.440415 -86.294806)
			(xy 161.416547 -86.376096) (xy 161.385059 -86.454748) (xy 161.346237 -86.530051) (xy 161.300434 -86.601323)
			(xy 161.248063 -86.667919) (xy 161.189598 -86.729234) (xy 161.12557 -86.784715) (xy 161.056558 -86.833858)
			(xy 160.983188 -86.876218) (xy 160.906123 -86.911413) (xy 160.826061 -86.939122) (xy 160.743728 -86.959096)
			(xy 160.659869 -86.971153) (xy 160.575244 -86.975185) (xy 160.490619 -86.971153) (xy 160.40676 -86.959096)
			(xy 160.324427 -86.939122) (xy 160.244365 -86.911413) (xy 160.1673 -86.876218) (xy 160.09393 -86.833858)
			(xy 160.024918 -86.784715) (xy 159.96089 -86.729234) (xy 159.902425 -86.667919) (xy 159.850054 -86.601323)
			(xy 159.804251 -86.530051) (xy 159.765429 -86.454748) (xy 159.733941 -86.376096) (xy 159.710073 -86.294806)
			(xy 159.694039 -86.211616) (xy 159.685986 -86.127279) (xy 123.911227 -86.127279) (xy 123.909304 -86.136357)
			(xy 123.880799 -86.224461) (xy 123.862592 -86.267036) (xy 123.862592 -86.267544) (xy 123.86056 -86.277196)
			(xy 123.859557 -86.282484) (xy 123.859549 -86.293246) (xy 123.86056 -86.298532) (xy 123.862592 -86.308184)
			(xy 123.862592 -86.308692) (xy 123.880795 -86.351268) (xy 123.909293 -86.439374) (xy 123.928486 -86.529964)
			(xy 123.938169 -86.622056) (xy 123.938792 -86.668356) (xy 123.938792 -86.668864) (xy 123.938333 -86.709968)
			(xy 123.930751 -86.791825) (xy 123.915648 -86.872634) (xy 123.893153 -86.951704) (xy 123.863459 -87.028362)
			(xy 123.826817 -87.101952) (xy 123.783542 -87.171848) (xy 123.734001 -87.237452) (xy 123.678619 -87.298205)
			(xy 123.617867 -87.353589) (xy 123.552264 -87.40313) (xy 123.48237 -87.446407) (xy 123.40878 -87.483051)
			(xy 123.332123 -87.512747) (xy 123.253054 -87.535244) (xy 123.172245 -87.550349) (xy 123.090388 -87.557933)
			(xy 123.049284 -87.558372) (xy 123.048776 -87.558372) (xy 123.002444 -87.557763) (xy 122.910284 -87.548103)
			(xy 122.819629 -87.52891) (xy 122.731461 -87.500393) (xy 122.688858 -87.482172) (xy 122.678916 -87.478366)
			(xy 122.657652 -87.478366) (xy 122.64771 -87.482172) (xy 122.605075 -87.500398) (xy 122.516844 -87.528923)
			(xy 122.426125 -87.548118) (xy 122.333902 -87.557775) (xy 122.287538 -87.558372) (xy 122.28703 -87.558372)
			(xy 122.240666 -87.557775) (xy 122.148442 -87.548126) (xy 122.057722 -87.528931) (xy 121.969494 -87.500398)
			(xy 121.926858 -87.482172) (xy 121.926604 -87.482172) (xy 121.916952 -87.48014) (xy 121.911664 -87.47914)
			(xy 121.900904 -87.47914) (xy 121.895616 -87.48014) (xy 121.885964 -87.482172) (xy 121.88571 -87.482172)
			(xy 121.843075 -87.500398) (xy 121.754844 -87.528923) (xy 121.664125 -87.548118) (xy 121.571902 -87.557775)
			(xy 121.525538 -87.558372) (xy 121.52503 -87.558372) (xy 121.481555 -87.557829) (xy 121.395024 -87.549313)
			(xy 121.309735 -87.532399) (xy 121.226503 -87.507248) (xy 121.14612 -87.4741) (xy 121.069353 -87.43327)
			(xy 120.996933 -87.385149) (xy 120.929552 -87.330194) (xy 120.867852 -87.26893) (xy 120.81242 -87.20194)
			(xy 120.787668 -87.166196) (xy 120.784366 -87.16137) (xy 120.774206 -87.151972) (xy 120.768975 -87.147542)
			(xy 120.756745 -87.141364) (xy 120.750076 -87.13978) (xy 120.739916 -87.138764) (xy 120.657366 -87.138764)
			(xy 120.644816 -87.139416) (xy 120.622704 -87.151287) (xy 120.615202 -87.16137) (xy 120.590528 -87.197527)
			(xy 120.535125 -87.265306) (xy 120.473334 -87.327316) (xy 120.40575 -87.382957) (xy 120.333029 -87.431692)
			(xy 120.255872 -87.473048) (xy 120.175027 -87.506626) (xy 120.091275 -87.532101) (xy 120.005425 -87.549228)
			(xy 119.918308 -87.557839) (xy 119.874538 -87.558372) (xy 119.87403 -87.558372) (xy 119.827666 -87.557775)
			(xy 119.735442 -87.548126) (xy 119.644722 -87.528931) (xy 119.556494 -87.500398) (xy 119.513858 -87.482172)
			(xy 119.503916 -87.478366) (xy 119.482652 -87.478366) (xy 119.47271 -87.482172) (xy 119.430055 -87.500452)
			(xy 119.34177 -87.529068) (xy 119.250985 -87.54833) (xy 119.158687 -87.558029) (xy 119.112284 -87.558626)
			(xy 119.065915 -87.557983) (xy 118.973688 -87.548253) (xy 118.882971 -87.528995) (xy 118.794746 -87.500416)
			(xy 118.752112 -87.482172) (xy 118.742206 -87.477854) (xy 118.720362 -87.477854) (xy 118.710456 -87.482172)
			(xy 118.667832 -87.500446) (xy 118.579612 -87.529056) (xy 118.48889 -87.548318) (xy 118.396656 -87.558021)
			(xy 118.350284 -87.558626) (xy 118.309038 -87.558159) (xy 118.2269 -87.55052) (xy 118.145822 -87.535311)
			(xy 118.0665 -87.512661) (xy 117.989616 -87.482764) (xy 117.915829 -87.445879) (xy 117.845774 -87.402321)
			(xy 117.780053 -87.352464) (xy 117.719229 -87.296738) (xy 117.663825 -87.23562) (xy 117.614317 -87.169635)
			(xy 117.571131 -87.09935) (xy 117.55247 -87.062564) (xy 117.547981 -87.05423) (xy 117.534079 -87.041403)
			(xy 117.516462 -87.034517) (xy 117.507004 -87.034116) (xy 117.415818 -87.034116) (xy 117.409382 -87.034327)
			(xy 117.39692 -87.037546) (xy 117.39118 -87.040466) (xy 117.384322 -87.044276) (xy 117.373654 -87.055452)
			(xy 117.370098 -87.062564) (xy 117.351421 -87.099334) (xy 117.308215 -87.169589) (xy 117.258693 -87.235544)
			(xy 117.20328 -87.296633) (xy 117.142451 -87.352331) (xy 117.076728 -87.402162) (xy 117.006676 -87.445696)
			(xy 116.932896 -87.48256) (xy 116.856021 -87.512438) (xy 116.776711 -87.535074) (xy 116.695646 -87.550272)
			(xy 116.613523 -87.557904) (xy 116.572284 -87.558372) (xy 116.571776 -87.558372) (xy 116.525444 -87.557763)
			(xy 116.433284 -87.548103) (xy 116.342629 -87.52891) (xy 116.254461 -87.500393) (xy 116.211858 -87.482172)
			(xy 116.201916 -87.478366) (xy 116.180652 -87.478366) (xy 116.17071 -87.482172) (xy 116.128075 -87.500398)
			(xy 116.039844 -87.528923) (xy 115.949125 -87.548118) (xy 115.856902 -87.557775) (xy 115.810538 -87.558372)
			(xy 115.81003 -87.558372) (xy 115.764143 -87.557785) (xy 115.67286 -87.548309) (xy 115.583038 -87.529484)
			(xy 115.495631 -87.501511) (xy 115.411568 -87.464688) (xy 115.371372 -87.442548) (xy 115.365784 -87.4395)
			(xy 115.351306 -87.43569) (xy 115.341558 -87.433607) (xy 115.321816 -87.436214) (xy 115.312952 -87.44077)
			(xy 115.238784 -87.483442) (xy 115.231292 -87.488222) (xy 115.21988 -87.501826) (xy 115.213789 -87.518506)
			(xy 115.213384 -87.527384) (xy 115.213384 -96.308361) (xy 157.479742 -96.308361) (xy 157.479742 -96.223639)
			(xy 157.487795 -96.139302) (xy 157.503829 -96.056112) (xy 157.527697 -95.974822) (xy 157.559185 -95.89617)
			(xy 157.598007 -95.820867) (xy 157.64381 -95.749595) (xy 157.696181 -95.682999) (xy 157.754646 -95.621684)
			(xy 157.818674 -95.566203) (xy 157.887686 -95.51706) (xy 157.961056 -95.4747) (xy 158.038121 -95.439505)
			(xy 158.118183 -95.411796) (xy 158.200516 -95.391822) (xy 158.284375 -95.379765) (xy 158.369 -95.375734)
			(xy 158.453625 -95.379765) (xy 158.537484 -95.391822) (xy 158.619817 -95.411796) (xy 158.699879 -95.439505)
			(xy 158.776944 -95.4747) (xy 158.850314 -95.51706) (xy 158.919326 -95.566203) (xy 158.983354 -95.621684)
			(xy 159.041819 -95.682999) (xy 159.09419 -95.749595) (xy 159.139993 -95.820867) (xy 159.178815 -95.89617)
			(xy 159.210303 -95.974822) (xy 159.234171 -96.056112) (xy 159.250205 -96.139302) (xy 159.258258 -96.223639)
			(xy 159.258762 -96.266) (xy 159.258258 -96.308361) (xy 159.250205 -96.392698) (xy 159.234171 -96.475888)
			(xy 159.210303 -96.557178) (xy 159.178815 -96.63583) (xy 159.139993 -96.711133) (xy 159.09419 -96.782405)
			(xy 159.041819 -96.849001) (xy 158.983354 -96.910316) (xy 158.919326 -96.965797) (xy 158.850314 -97.01494)
			(xy 158.776944 -97.0573) (xy 158.699879 -97.092495) (xy 158.619817 -97.120204) (xy 158.537484 -97.140178)
			(xy 158.453625 -97.152235) (xy 158.369 -97.156267) (xy 158.284375 -97.152235) (xy 158.200516 -97.140178)
			(xy 158.118183 -97.120204) (xy 158.038121 -97.092495) (xy 157.961056 -97.0573) (xy 157.887686 -97.01494)
			(xy 157.818674 -96.965797) (xy 157.754646 -96.910316) (xy 157.696181 -96.849001) (xy 157.64381 -96.782405)
			(xy 157.598007 -96.711133) (xy 157.559185 -96.63583) (xy 157.527697 -96.557178) (xy 157.503829 -96.475888)
			(xy 157.487795 -96.392698) (xy 157.479742 -96.308361) (xy 115.213384 -96.308361) (xy 115.213384 -101.933248)
			(xy 115.21388 -101.94325) (xy 115.221547 -101.961729) (xy 115.235698 -101.975871) (xy 115.254181 -101.983526)
			(xy 115.264184 -101.984048)
		)
		(stroke
			(width 0)
			(type solid)
		)
		(fill yes)
		(layer "In5.Cu")
		(net "GND")
	)
	(gr_poly
		(pts
			(xy 472.437206 -77.089) (xy 472.447084 -77.088542) (xy 472.465386 -77.081102) (xy 472.472766 -77.074522)
			(xy 472.47302 -77.074268) (xy 472.780614 -76.766674) (xy 472.781122 -76.766166) (xy 472.787711 -76.758787)
			(xy 472.795173 -76.740488) (xy 472.7956 -76.730606) (xy 472.7956 -68.303394) (xy 472.795176 -68.293324)
			(xy 472.78746 -68.274721) (xy 472.780614 -68.267326) (xy 472.473274 -67.959986) (xy 472.466162 -67.95262)
			(xy 472.447366 -67.945) (xy 468.0458 -67.945) (xy 468.01254 -67.944479) (xy 467.94659 -67.935791)
			(xy 467.882339 -67.918566) (xy 467.820888 -67.893097) (xy 467.763289 -67.859821) (xy 467.710529 -67.819308)
			(xy 467.686644 -67.796156) (xy 466.619844 -66.729356) (xy 466.596688 -66.705476) (xy 466.556182 -66.652712)
			(xy 466.522911 -66.595111) (xy 466.497447 -66.53366) (xy 466.480225 -66.469409) (xy 466.471539 -66.403459)
			(xy 466.471 -66.3702) (xy 466.471 -41.658794) (xy 466.470576 -41.648724) (xy 466.46286 -41.630121)
			(xy 466.456014 -41.622726) (xy 460.306674 -35.473386) (xy 460.299562 -35.46602) (xy 460.280766 -35.4584)
			(xy 452.923148 -35.4584) (xy 452.889887 -35.457882) (xy 452.823933 -35.4492) (xy 452.759679 -35.431979)
			(xy 452.698223 -35.406515) (xy 452.64062 -35.373242) (xy 452.587856 -35.332731) (xy 452.563992 -35.309556)
			(xy 450.931534 -33.677352) (xy 450.898768 -33.672272) (xy 450.883782 -33.680146) (xy 450.845449 -33.69975)
			(xy 450.765736 -33.732302) (xy 450.68325 -33.756999) (xy 450.598764 -33.77361) (xy 450.513068 -33.78198)
			(xy 450.470016 -33.782508) (xy 450.469 -33.782508) (xy 450.427898 -33.782033) (xy 450.346043 -33.774448)
			(xy 450.265238 -33.759343) (xy 450.186171 -33.736847) (xy 450.109517 -33.707151) (xy 450.03593 -33.670509)
			(xy 449.966038 -33.627234) (xy 449.900437 -33.577694) (xy 449.839687 -33.522313) (xy 449.784306 -33.461563)
			(xy 449.734766 -33.395962) (xy 449.691491 -33.32607) (xy 449.654849 -33.252483) (xy 449.625153 -33.175829)
			(xy 449.602657 -33.096762) (xy 449.587552 -33.015957) (xy 449.579967 -32.934102) (xy 449.579492 -32.893)
			(xy 449.579492 -32.891984) (xy 449.580022 -32.848933) (xy 449.588392 -32.763237) (xy 449.605003 -32.678751)
			(xy 449.6297 -32.596265) (xy 449.662252 -32.516552) (xy 449.681854 -32.478218) (xy 449.689728 -32.463232)
			(xy 449.684648 -32.430466) (xy 448.440048 -31.185866) (xy 448.410838 -31.179516) (xy 448.396614 -31.18485)
			(xy 448.349878 -31.201106) (xy 448.339972 -31.204408) (xy 448.324478 -31.217616) (xy 448.287902 -31.29153)
			(xy 448.284595 -31.298802) (xy 448.282269 -31.3146) (xy 448.28333 -31.322518) (xy 448.284854 -31.331916)
			(xy 448.286124 -31.33598) (xy 448.298072 -31.371331) (xy 448.316699 -31.443597) (xy 448.329209 -31.517168)
			(xy 448.335514 -31.591529) (xy 448.335908 -31.628842) (xy 448.335908 -31.629096) (xy 448.335404 -31.671444)
			(xy 448.327353 -31.755758) (xy 448.311324 -31.838924) (xy 448.287463 -31.920191) (xy 448.255984 -31.998821)
			(xy 448.217173 -32.074102) (xy 448.171383 -32.145354) (xy 448.119027 -32.21193) (xy 448.060579 -32.273228)
			(xy 447.996569 -32.328693) (xy 447.927577 -32.377822) (xy 447.854227 -32.420171) (xy 447.777184 -32.455355)
			(xy 447.697145 -32.483057) (xy 447.614836 -32.503025) (xy 447.531001 -32.515078) (xy 447.4464 -32.519109)
			(xy 447.361799 -32.515078) (xy 447.277964 -32.503025) (xy 447.195655 -32.483057) (xy 447.115616 -32.455355)
			(xy 447.038573 -32.420171) (xy 446.965223 -32.377822) (xy 446.896231 -32.328693) (xy 446.832221 -32.273228)
			(xy 446.773773 -32.21193) (xy 446.721417 -32.145354) (xy 446.675627 -32.074102) (xy 446.636816 -31.998821)
			(xy 446.605337 -31.920191) (xy 446.581476 -31.838924) (xy 446.565447 -31.755758) (xy 446.557396 -31.671444)
			(xy 446.556892 -31.629096) (xy 446.557412 -31.585836) (xy 446.565821 -31.499726) (xy 446.582549 -31.414839)
			(xy 446.607438 -31.331977) (xy 446.640252 -31.251922) (xy 446.680683 -31.17543) (xy 446.728349 -31.103224)
			(xy 446.782798 -31.035987) (xy 446.843517 -30.974352) (xy 446.909932 -30.918902) (xy 446.981416 -30.870162)
			(xy 447.057294 -30.82859) (xy 447.136849 -30.794581) (xy 447.177922 -30.78099) (xy 447.187828 -30.777688)
			(xy 447.203322 -30.76448) (xy 447.239898 -30.690566) (xy 447.243204 -30.683294) (xy 447.245529 -30.667497)
			(xy 447.24447 -30.659578) (xy 447.242946 -30.65018) (xy 447.241676 -30.646116) (xy 447.229729 -30.610765)
			(xy 447.211101 -30.538499) (xy 447.198592 -30.464928) (xy 447.192287 -30.390567) (xy 447.191892 -30.353254)
			(xy 447.191892 -30.352492) (xy 447.192338 -30.312241) (xy 447.199611 -30.232067) (xy 447.214105 -30.15288)
			(xy 447.235702 -30.075329) (xy 447.24955 -30.037532) (xy 447.254884 -30.023562) (xy 447.249042 -29.995114)
			(xy 447.238628 -29.984192) (xy 447.237866 -29.98343) (xy 447.226436 -29.972) (xy 447.225928 -29.971492)
			(xy 447.212466 -29.958284) (xy 447.205088 -29.951695) (xy 447.186788 -29.944232) (xy 447.176906 -29.943806)
			(xy 447.162682 -29.943806) (xy 447.156586 -29.94533) (xy 447.120912 -29.953966) (xy 447.048509 -29.966042)
			(xy 446.975356 -29.972111) (xy 446.938654 -29.972508) (xy 446.9384 -29.972508) (xy 446.897298 -29.972033)
			(xy 446.815443 -29.964448) (xy 446.734638 -29.949343) (xy 446.655571 -29.926847) (xy 446.578917 -29.897151)
			(xy 446.50533 -29.860509) (xy 446.435438 -29.817234) (xy 446.369837 -29.767694) (xy 446.309087 -29.712313)
			(xy 446.253706 -29.651563) (xy 446.204166 -29.585962) (xy 446.160891 -29.51607) (xy 446.124249 -29.442483)
			(xy 446.094553 -29.365829) (xy 446.072057 -29.286762) (xy 446.056952 -29.205957) (xy 446.049367 -29.124102)
			(xy 446.048892 -29.083) (xy 446.048892 -29.082746) (xy 446.049288 -29.045037) (xy 446.055699 -28.969891)
			(xy 446.068462 -28.895561) (xy 446.077594 -28.858972) (xy 446.08115 -28.845764) (xy 446.074038 -28.819856)
			(xy 435.040278 -17.785842) (xy 435.033166 -17.778476) (xy 435.01437 -17.770856) (xy 428.285656 -17.770856)
			(xy 428.252397 -17.770332) (xy 428.186449 -17.76164) (xy 428.1222 -17.744412) (xy 428.060751 -17.718941)
			(xy 428.003154 -17.685665) (xy 427.950395 -17.645153) (xy 427.9265 -17.622012) (xy 422.315386 -12.010898)
			(xy 422.292226 -11.98702) (xy 422.251712 -11.934258) (xy 422.218434 -11.876658) (xy 422.192963 -11.815206)
			(xy 422.175734 -11.750954) (xy 422.167042 -11.685003) (xy 422.166542 -11.651742) (xy 422.166542 -2.091944)
			(xy 422.166448 -2.086783) (xy 422.164398 -2.076669) (xy 422.162478 -2.071878) (xy 422.150794 -2.045208)
			(xy 422.143682 -2.038096) (xy 422.135808 -2.030222) (xy 421.136318 -1.030986) (xy 421.129206 -1.02362)
			(xy 421.11041 -1.016) (xy 419.582092 -1.016) (xy 419.55593 -1.034796) (xy 419.550596 -1.05029) (xy 419.536394 -1.090337)
			(xy 419.501383 -1.167764) (xy 419.459148 -1.2415) (xy 419.410073 -1.310871) (xy 419.354606 -1.375247)
			(xy 419.293253 -1.434039) (xy 419.226572 -1.486713) (xy 419.155173 -1.532787) (xy 419.079704 -1.571843)
			(xy 419.000856 -1.603523) (xy 418.919345 -1.627539) (xy 418.835915 -1.643673) (xy 418.751328 -1.651777)
			(xy 418.666352 -1.651777) (xy 418.581765 -1.643673) (xy 418.498335 -1.627539) (xy 418.416824 -1.603523)
			(xy 418.337976 -1.571843) (xy 418.262507 -1.532787) (xy 418.191108 -1.486713) (xy 418.124427 -1.434039)
			(xy 418.063074 -1.375247) (xy 418.007607 -1.310871) (xy 417.958532 -1.2415) (xy 417.916297 -1.167764)
			(xy 417.881286 -1.090337) (xy 417.867084 -1.05029) (xy 417.86175 -1.034796) (xy 417.835588 -1.016)
			(xy 414.502092 -1.016) (xy 414.47593 -1.034796) (xy 414.470596 -1.05029) (xy 414.456394 -1.090337)
			(xy 414.421383 -1.167764) (xy 414.379148 -1.2415) (xy 414.330073 -1.310871) (xy 414.274606 -1.375247)
			(xy 414.213253 -1.434039) (xy 414.146572 -1.486713) (xy 414.075173 -1.532787) (xy 413.999704 -1.571843)
			(xy 413.920856 -1.603523) (xy 413.839345 -1.627539) (xy 413.755915 -1.643673) (xy 413.671328 -1.651777)
			(xy 413.586352 -1.651777) (xy 413.501765 -1.643673) (xy 413.418335 -1.627539) (xy 413.336824 -1.603523)
			(xy 413.257976 -1.571843) (xy 413.182507 -1.532787) (xy 413.111108 -1.486713) (xy 413.044427 -1.434039)
			(xy 412.983074 -1.375247) (xy 412.927607 -1.310871) (xy 412.878532 -1.2415) (xy 412.836297 -1.167764)
			(xy 412.801286 -1.090337) (xy 412.787084 -1.05029) (xy 412.78175 -1.034796) (xy 412.755588 -1.016)
			(xy 409.422092 -1.016) (xy 409.39593 -1.034796) (xy 409.390596 -1.05029) (xy 409.376394 -1.090337)
			(xy 409.341383 -1.167764) (xy 409.299148 -1.2415) (xy 409.250073 -1.310871) (xy 409.194606 -1.375247)
			(xy 409.133253 -1.434039) (xy 409.066572 -1.486713) (xy 408.995173 -1.532787) (xy 408.919704 -1.571843)
			(xy 408.840856 -1.603523) (xy 408.759345 -1.627539) (xy 408.675915 -1.643673) (xy 408.591328 -1.651777)
			(xy 408.506352 -1.651777) (xy 408.421765 -1.643673) (xy 408.338335 -1.627539) (xy 408.256824 -1.603523)
			(xy 408.177976 -1.571843) (xy 408.102507 -1.532787) (xy 408.031108 -1.486713) (xy 407.964427 -1.434039)
			(xy 407.903074 -1.375247) (xy 407.847607 -1.310871) (xy 407.798532 -1.2415) (xy 407.756297 -1.167764)
			(xy 407.721286 -1.090337) (xy 407.707084 -1.05029) (xy 407.70175 -1.034796) (xy 407.675588 -1.016)
			(xy 404.342092 -1.016) (xy 404.31593 -1.034796) (xy 404.310596 -1.05029) (xy 404.296394 -1.090337)
			(xy 404.261383 -1.167764) (xy 404.219148 -1.2415) (xy 404.170073 -1.310871) (xy 404.114606 -1.375247)
			(xy 404.053253 -1.434039) (xy 403.986572 -1.486713) (xy 403.915173 -1.532787) (xy 403.839704 -1.571843)
			(xy 403.760856 -1.603523) (xy 403.679345 -1.627539) (xy 403.595915 -1.643673) (xy 403.511328 -1.651777)
			(xy 403.426352 -1.651777) (xy 403.341765 -1.643673) (xy 403.258335 -1.627539) (xy 403.176824 -1.603523)
			(xy 403.097976 -1.571843) (xy 403.022507 -1.532787) (xy 402.951108 -1.486713) (xy 402.884427 -1.434039)
			(xy 402.823074 -1.375247) (xy 402.767607 -1.310871) (xy 402.718532 -1.2415) (xy 402.676297 -1.167764)
			(xy 402.641286 -1.090337) (xy 402.627084 -1.05029) (xy 402.62175 -1.034796) (xy 402.595588 -1.016)
			(xy 399.262092 -1.016) (xy 399.23593 -1.034796) (xy 399.230596 -1.05029) (xy 399.216394 -1.090337)
			(xy 399.181383 -1.167764) (xy 399.139148 -1.2415) (xy 399.090073 -1.310871) (xy 399.034606 -1.375247)
			(xy 398.973253 -1.434039) (xy 398.906572 -1.486713) (xy 398.835173 -1.532787) (xy 398.759704 -1.571843)
			(xy 398.680856 -1.603523) (xy 398.599345 -1.627539) (xy 398.515915 -1.643673) (xy 398.431328 -1.651777)
			(xy 398.346352 -1.651777) (xy 398.261765 -1.643673) (xy 398.178335 -1.627539) (xy 398.096824 -1.603523)
			(xy 398.017976 -1.571843) (xy 397.942507 -1.532787) (xy 397.871108 -1.486713) (xy 397.804427 -1.434039)
			(xy 397.743074 -1.375247) (xy 397.687607 -1.310871) (xy 397.638532 -1.2415) (xy 397.596297 -1.167764)
			(xy 397.561286 -1.090337) (xy 397.547084 -1.05029) (xy 397.54175 -1.034796) (xy 397.515588 -1.016)
			(xy 394.182092 -1.016) (xy 394.15593 -1.034796) (xy 394.150596 -1.05029) (xy 394.136394 -1.090337)
			(xy 394.101383 -1.167764) (xy 394.059148 -1.2415) (xy 394.010073 -1.310871) (xy 393.954606 -1.375247)
			(xy 393.893253 -1.434039) (xy 393.826572 -1.486713) (xy 393.755173 -1.532787) (xy 393.679704 -1.571843)
			(xy 393.600856 -1.603523) (xy 393.519345 -1.627539) (xy 393.435915 -1.643673) (xy 393.351328 -1.651777)
			(xy 393.266352 -1.651777) (xy 393.181765 -1.643673) (xy 393.098335 -1.627539) (xy 393.016824 -1.603523)
			(xy 392.937976 -1.571843) (xy 392.862507 -1.532787) (xy 392.791108 -1.486713) (xy 392.724427 -1.434039)
			(xy 392.663074 -1.375247) (xy 392.607607 -1.310871) (xy 392.558532 -1.2415) (xy 392.516297 -1.167764)
			(xy 392.481286 -1.090337) (xy 392.467084 -1.05029) (xy 392.46175 -1.034796) (xy 392.435588 -1.016)
			(xy 389.102092 -1.016) (xy 389.07593 -1.034796) (xy 389.070596 -1.05029) (xy 389.056394 -1.090337)
			(xy 389.021383 -1.167764) (xy 388.979148 -1.2415) (xy 388.930073 -1.310871) (xy 388.874606 -1.375247)
			(xy 388.813253 -1.434039) (xy 388.746572 -1.486713) (xy 388.675173 -1.532787) (xy 388.599704 -1.571843)
			(xy 388.520856 -1.603523) (xy 388.439345 -1.627539) (xy 388.355915 -1.643673) (xy 388.271328 -1.651777)
			(xy 388.186352 -1.651777) (xy 388.101765 -1.643673) (xy 388.018335 -1.627539) (xy 387.936824 -1.603523)
			(xy 387.857976 -1.571843) (xy 387.782507 -1.532787) (xy 387.711108 -1.486713) (xy 387.644427 -1.434039)
			(xy 387.583074 -1.375247) (xy 387.527607 -1.310871) (xy 387.478532 -1.2415) (xy 387.436297 -1.167764)
			(xy 387.401286 -1.090337) (xy 387.387084 -1.05029) (xy 387.38175 -1.034796) (xy 387.355588 -1.016)
			(xy 384.022092 -1.016) (xy 383.99593 -1.034796) (xy 383.990596 -1.05029) (xy 383.976394 -1.090337)
			(xy 383.941383 -1.167764) (xy 383.899148 -1.2415) (xy 383.850073 -1.310871) (xy 383.794606 -1.375247)
			(xy 383.733253 -1.434039) (xy 383.666572 -1.486713) (xy 383.595173 -1.532787) (xy 383.519704 -1.571843)
			(xy 383.440856 -1.603523) (xy 383.359345 -1.627539) (xy 383.275915 -1.643673) (xy 383.191328 -1.651777)
			(xy 383.106352 -1.651777) (xy 383.021765 -1.643673) (xy 382.938335 -1.627539) (xy 382.856824 -1.603523)
			(xy 382.777976 -1.571843) (xy 382.702507 -1.532787) (xy 382.631108 -1.486713) (xy 382.564427 -1.434039)
			(xy 382.503074 -1.375247) (xy 382.447607 -1.310871) (xy 382.398532 -1.2415) (xy 382.356297 -1.167764)
			(xy 382.321286 -1.090337) (xy 382.307084 -1.05029) (xy 382.30175 -1.034796) (xy 382.275588 -1.016)
			(xy 380.150878 -1.016) (xy 380.142392 -1.01631) (xy 380.126356 -1.021866) (xy 380.113038 -1.032385)
			(xy 380.108206 -1.039368) (xy 380.101348 -1.050036) (xy 380.099316 -1.075944) (xy 380.110492 -1.100328)
			(xy 380.116842 -1.10871) (xy 380.120906 -1.112266) (xy 380.168811 -1.155144) (xy 380.25956 -1.246231)
			(xy 380.344173 -1.343046) (xy 380.422288 -1.445176) (xy 380.493573 -1.552185) (xy 380.557724 -1.663617)
			(xy 380.614467 -1.778997) (xy 380.66356 -1.897835) (xy 380.704794 -2.019622) (xy 380.737995 -2.14384)
			(xy 380.763019 -2.26996) (xy 380.77976 -2.397444) (xy 380.788147 -2.525749) (xy 380.788672 -2.590038)
			(xy 380.788185 -2.651893) (xy 380.780415 -2.775358) (xy 380.764908 -2.898092) (xy 380.741725 -3.01961)
			(xy 380.710958 -3.139432) (xy 380.672728 -3.257087) (xy 380.627186 -3.372108) (xy 380.574512 -3.484043)
			(xy 380.514913 -3.59245) (xy 380.448626 -3.696901) (xy 380.37591 -3.796984) (xy 380.297054 -3.892303)
			(xy 380.212369 -3.982483) (xy 380.122188 -4.067167) (xy 380.026868 -4.146022) (xy 379.926784 -4.218737)
			(xy 379.822333 -4.285024) (xy 379.713925 -4.344621) (xy 379.60199 -4.397294) (xy 379.486968 -4.442835)
			(xy 379.369313 -4.481064) (xy 379.24949 -4.51183) (xy 379.127972 -4.535011) (xy 379.005238 -4.550517)
			(xy 378.881773 -4.558286) (xy 378.819918 -4.558792) (xy 378.755106 -4.558265) (xy 378.625764 -4.54974)
			(xy 378.497262 -4.532727) (xy 378.370158 -4.507299) (xy 378.245001 -4.473566) (xy 378.122334 -4.431675)
			(xy 378.002688 -4.381806) (xy 377.88658 -4.324176) (xy 377.774515 -4.259034) (xy 377.666977 -4.186662)
			(xy 377.564432 -4.107374) (xy 377.467323 -4.021513) (xy 377.376072 -3.929451) (xy 377.291074 -3.831586)
			(xy 377.251468 -3.780282) (xy 377.24334 -3.76936) (xy 377.218956 -3.758946) (xy 377.10491 -3.772154)
			(xy 377.083574 -3.787648) (xy 377.077986 -3.800348) (xy 377.05741 -3.845183) (xy 377.009983 -3.931692)
			(xy 376.955688 -4.014063) (xy 376.894883 -4.091754) (xy 376.827969 -4.16425) (xy 376.755389 -4.231072)
			(xy 376.677622 -4.291779) (xy 376.595182 -4.345971) (xy 376.508614 -4.393288) (xy 376.418488 -4.43342)
			(xy 376.325401 -4.466099) (xy 376.229968 -4.491111) (xy 376.132819 -4.50829) (xy 376.034596 -4.517524)
			(xy 375.985278 -4.51866) (xy 375.975118 -4.51866) (xy 375.957084 -4.52628) (xy 375.94413 -4.539234)
			(xy 375.937456 -4.546645) (xy 375.929876 -4.565072) (xy 375.92989 -4.584996) (xy 375.937494 -4.603412)
			(xy 375.94413 -4.610862) (xy 375.957084 -4.623816) (xy 375.975118 -4.631436) (xy 375.985278 -4.631436)
			(xy 376.034332 -4.632539) (xy 376.132033 -4.641692) (xy 376.228676 -4.658703) (xy 376.32363 -4.68346)
			(xy 376.416276 -4.715802) (xy 376.506008 -4.755519) (xy 376.59224 -4.80235) (xy 376.67441 -4.855991)
			(xy 376.751982 -4.91609) (xy 376.824448 -4.982256) (xy 376.891336 -5.054056) (xy 376.952208 -5.131022)
			(xy 377.006668 -5.212651) (xy 377.054361 -5.29841) (xy 377.094974 -5.38774) (xy 377.128242 -5.480057)
			(xy 377.153949 -5.574759) (xy 377.171926 -5.671226) (xy 377.182056 -5.768831) (xy 377.184273 -5.866934)
			(xy 377.178563 -5.964897) (xy 377.164962 -6.062078) (xy 377.14356 -6.157844) (xy 377.114496 -6.25157)
			(xy 377.07796 -6.342644) (xy 377.034191 -6.43047) (xy 376.983474 -6.514476) (xy 376.926141 -6.594113)
			(xy 376.862565 -6.668862) (xy 376.793162 -6.738234) (xy 376.718385 -6.801776) (xy 376.638722 -6.859074)
			(xy 376.554693 -6.909753) (xy 376.466847 -6.953483) (xy 376.375758 -6.989978) (xy 376.282019 -7.019)
			(xy 376.186243 -7.040359) (xy 376.089055 -7.053916) (xy 375.991091 -7.059582) (xy 375.892988 -7.057321)
			(xy 375.795388 -7.047148) (xy 375.698928 -7.029127) (xy 375.604238 -7.003378) (xy 375.511936 -6.970069)
			(xy 375.422625 -6.929416) (xy 375.336887 -6.881685) (xy 375.255282 -6.827188) (xy 375.178343 -6.766281)
			(xy 375.106573 -6.699361) (xy 375.04044 -6.626866) (xy 374.980375 -6.549267) (xy 374.926772 -6.467073)
			(xy 374.879979 -6.38082) (xy 374.840303 -6.29107) (xy 374.808002 -6.19841) (xy 374.783287 -6.103445)
			(xy 374.76632 -6.006794) (xy 374.757211 -5.909089) (xy 374.756172 -5.860034) (xy 374.756172 -5.849874)
			(xy 374.748552 -5.83184) (xy 374.705372 -5.78866) (xy 374.694704 -5.78866) (xy 374.651524 -5.83184)
			(xy 374.643904 -5.849874) (xy 374.643904 -5.860034) (xy 374.642787 -5.909818) (xy 374.633403 -6.008963)
			(xy 374.615928 -6.107006) (xy 374.590478 -6.203287) (xy 374.557225 -6.29716) (xy 374.516393 -6.387992)
			(xy 374.468257 -6.475174) (xy 374.413139 -6.558119) (xy 374.35141 -6.636269) (xy 374.283487 -6.709098)
			(xy 374.209824 -6.776118) (xy 374.130918 -6.836877) (xy 374.047299 -6.890967) (xy 373.95953 -6.938024)
			(xy 373.868201 -6.977731) (xy 373.773925 -7.009823) (xy 373.677336 -7.034082) (xy 373.579085 -7.050346)
			(xy 373.479832 -7.058505) (xy 373.380244 -7.058505) (xy 373.280991 -7.050346) (xy 373.18274 -7.034082)
			(xy 373.086151 -7.009823) (xy 372.991875 -6.977731) (xy 372.900546 -6.938024) (xy 372.812777 -6.890967)
			(xy 372.729158 -6.836877) (xy 372.650252 -6.776118) (xy 372.576589 -6.709098) (xy 372.508666 -6.636269)
			(xy 372.446937 -6.558119) (xy 372.391819 -6.475174) (xy 372.343683 -6.387992) (xy 372.302851 -6.29716)
			(xy 372.269598 -6.203287) (xy 372.244148 -6.107006) (xy 372.226673 -6.008963) (xy 372.217289 -5.909818)
			(xy 372.216172 -5.860034) (xy 372.216172 -5.849874) (xy 372.208552 -5.83184) (xy 372.172992 -5.79628)
			(xy 372.154958 -5.78866) (xy 372.144798 -5.78866) (xy 372.095028 -5.787535) (xy 371.995913 -5.778136)
			(xy 371.897901 -5.76065) (xy 371.801651 -5.735193) (xy 371.707809 -5.701936) (xy 371.617008 -5.661104)
			(xy 371.529857 -5.61297) (xy 371.446942 -5.557858) (xy 371.368821 -5.496139) (xy 371.296018 -5.428228)
			(xy 371.229024 -5.35458) (xy 371.168288 -5.275692) (xy 371.114219 -5.192094) (xy 371.067181 -5.104347)
			(xy 371.027489 -5.013041) (xy 370.99541 -4.918791) (xy 370.97116 -4.822229) (xy 370.954903 -4.724006)
			(xy 370.946747 -4.624781) (xy 370.946747 -4.525221) (xy 370.954903 -4.425995) (xy 370.97116 -4.327772)
			(xy 370.99541 -4.23121) (xy 371.027488 -4.13696) (xy 371.06718 -4.045654) (xy 371.114219 -3.957907)
			(xy 371.168288 -3.874309) (xy 371.229023 -3.79542) (xy 371.296018 -3.721773) (xy 371.36882 -3.653862)
			(xy 371.446941 -3.592142) (xy 371.529856 -3.537031) (xy 371.617007 -3.488897) (xy 371.707808 -3.448064)
			(xy 371.801649 -3.414807) (xy 371.8979 -3.38935) (xy 371.995912 -3.371864) (xy 372.095027 -3.362465)
			(xy 372.144798 -3.361436) (xy 372.154958 -3.361436) (xy 372.172992 -3.353816) (xy 372.185946 -3.340862)
			(xy 372.192642 -3.333451) (xy 372.20026 -3.31501) (xy 372.200273 -3.295058) (xy 372.19268 -3.276606)
			(xy 372.185946 -3.269234) (xy 372.172992 -3.25628) (xy 372.154958 -3.24866) (xy 372.144798 -3.24866)
			(xy 372.095029 -3.247535) (xy 371.995917 -3.238137) (xy 371.897907 -3.220651) (xy 371.801659 -3.195195)
			(xy 371.70782 -3.16194) (xy 371.61702 -3.12111) (xy 371.529871 -3.072978) (xy 371.446957 -3.017869)
			(xy 371.368837 -2.956153) (xy 371.296035 -2.888245) (xy 371.229041 -2.814601) (xy 371.168305 -2.735716)
			(xy 371.114235 -2.652121) (xy 371.067195 -2.564377) (xy 371.027502 -2.473075) (xy 370.995421 -2.378828)
			(xy 370.971169 -2.28227) (xy 370.954908 -2.184049) (xy 370.946749 -2.084827) (xy 370.946172 -2.035048)
			(xy 370.946629 -1.988194) (xy 370.953874 -1.894767) (xy 370.968301 -1.802177) (xy 370.989825 -1.710975)
			(xy 371.018317 -1.621704) (xy 371.053607 -1.534896) (xy 371.095486 -1.451067) (xy 371.143704 -1.370717)
			(xy 371.197974 -1.294325) (xy 371.257973 -1.222344) (xy 371.290342 -1.188466) (xy 371.30101 -1.177544)
			(xy 371.306598 -1.147572) (xy 371.264434 -1.047242) (xy 371.260985 -1.039611) (xy 371.249959 -1.027019)
			(xy 371.242844 -1.022604) (xy 371.230906 -1.016) (xy 77.750924 -1.016) (xy 77.742434 -1.016303) (xy 77.726387 -1.021848)
			(xy 77.713057 -1.032364) (xy 77.708252 -1.039368) (xy 77.701394 -1.050036) (xy 77.699362 -1.075944)
			(xy 77.710538 -1.100328) (xy 77.716888 -1.10871) (xy 77.720952 -1.112266) (xy 77.768858 -1.155143)
			(xy 77.85961 -1.246229) (xy 77.944225 -1.343043) (xy 78.022342 -1.445172) (xy 78.093629 -1.552181)
			(xy 78.157781 -1.663613) (xy 78.214526 -1.778994) (xy 78.26362 -1.897831) (xy 78.304856 -2.019619)
			(xy 78.338057 -2.143838) (xy 78.363082 -2.269958) (xy 78.379824 -2.397443) (xy 78.388211 -2.525748)
			(xy 78.388718 -2.590038) (xy 78.388231 -2.651892) (xy 78.380461 -2.775356) (xy 78.364954 -2.898089)
			(xy 78.341771 -3.019605) (xy 78.311004 -3.139427) (xy 78.272773 -3.257079) (xy 78.227231 -3.3721)
			(xy 78.174557 -3.484033) (xy 78.114958 -3.592439) (xy 78.048669 -3.696888) (xy 77.975954 -3.796968)
			(xy 77.897097 -3.892286) (xy 77.832663 -3.960899) (xy 361.610479 -3.960899) (xy 361.613141 -3.835526)
			(xy 361.623776 -3.710577) (xy 361.642341 -3.586557) (xy 361.668761 -3.463971) (xy 361.702929 -3.343314)
			(xy 361.744705 -3.225076) (xy 361.793922 -3.109736) (xy 361.850378 -2.997762) (xy 361.913847 -2.889608)
			(xy 361.984069 -2.785713) (xy 362.060761 -2.686496) (xy 362.143611 -2.592362) (xy 362.232283 -2.50369)
			(xy 362.326419 -2.420841) (xy 362.425637 -2.344151) (xy 362.529534 -2.273931) (xy 362.637689 -2.210464)
			(xy 362.749663 -2.154009) (xy 362.865004 -2.104794) (xy 362.983242 -2.063019) (xy 363.1039 -2.028854)
			(xy 363.226487 -2.002436) (xy 363.350507 -1.983872) (xy 363.475456 -1.973239) (xy 363.600829 -1.970579)
			(xy 363.726118 -1.975903) (xy 363.850813 -1.989189) (xy 363.97441 -2.010384) (xy 364.096408 -2.039401)
			(xy 364.216312 -2.076123) (xy 364.333636 -2.120402) (xy 364.447905 -2.172057) (xy 364.558654 -2.230879)
			(xy 364.665436 -2.296629) (xy 364.767817 -2.369042) (xy 364.865383 -2.447823) (xy 364.957737 -2.532654)
			(xy 365.044505 -2.62319) (xy 365.125336 -2.719064) (xy 365.199902 -2.819888) (xy 365.2679 -2.925253)
			(xy 365.329055 -3.034731) (xy 365.38312 -3.147879) (xy 365.429874 -3.264239) (xy 365.469128 -3.383338)
			(xy 365.500724 -3.504694) (xy 365.524533 -3.627814) (xy 365.540458 -3.7522) (xy 365.548435 -3.877347)
			(xy 365.548926 -3.940048) (xy 365.548617 -3.98941) (xy 365.543662 -4.088008) (xy 365.53902 -4.137152)
			(xy 365.538484 -4.14788) (xy 365.545289 -4.168231) (xy 365.559804 -4.184035) (xy 365.579505 -4.192542)
			(xy 365.600961 -4.192272) (xy 365.610902 -4.188206) (xy 365.65882 -4.166657) (xy 365.757652 -4.130978)
			(xy 365.859199 -4.103978) (xy 365.9627 -4.08586) (xy 366.067381 -4.076759) (xy 366.119918 -4.076192)
			(xy 366.168813 -4.076769) (xy 366.266286 -4.084639) (xy 366.36281 -4.100327) (xy 366.457758 -4.123731)
			(xy 366.550516 -4.154699) (xy 366.64048 -4.193031) (xy 366.727069 -4.238477) (xy 366.80972 -4.290743)
			(xy 366.887897 -4.349491) (xy 366.961093 -4.414338) (xy 367.028834 -4.484865) (xy 367.090681 -4.560615)
			(xy 367.146232 -4.641095) (xy 367.195126 -4.725784) (xy 367.237048 -4.814133) (xy 367.271725 -4.905568)
			(xy 367.298931 -4.999498) (xy 367.318492 -5.095312) (xy 367.330279 -5.192389) (xy 367.334215 -5.290058)
			(xy 367.445547 -5.290058) (xy 367.449587 -5.191075) (xy 367.461682 -5.092752) (xy 367.481752 -4.995741)
			(xy 367.509662 -4.900689) (xy 367.545226 -4.808228) (xy 367.588209 -4.718973) (xy 367.638324 -4.633519)
			(xy 367.695237 -4.552434) (xy 367.75857 -4.476258) (xy 367.827901 -4.405498) (xy 367.90277 -4.340624)
			(xy 367.982677 -4.282069) (xy 368.067091 -4.230221) (xy 368.15545 -4.185427) (xy 368.247166 -4.147984)
			(xy 368.341629 -4.118141) (xy 368.43821 -4.096097) (xy 368.536267 -4.081998) (xy 368.635147 -4.075939)
			(xy 368.734191 -4.07796) (xy 368.832741 -4.088047) (xy 368.930141 -4.106133) (xy 369.025743 -4.132098)
			(xy 369.11891 -4.16577) (xy 369.209023 -4.206923) (xy 369.295481 -4.255284) (xy 369.37771 -4.310531)
			(xy 369.455162 -4.372297) (xy 369.527322 -4.440171) (xy 369.59371 -4.5137) (xy 369.653883 -4.592396)
			(xy 369.707441 -4.675735) (xy 369.754029 -4.763162) (xy 369.793335 -4.854095) (xy 369.825099 -4.94793)
			(xy 369.849108 -5.044041) (xy 369.865204 -5.14179) (xy 369.873279 -5.240526) (xy 369.873784 -5.290058)
			(xy 369.873279 -5.33959) (xy 369.865204 -5.438326) (xy 369.849108 -5.536075) (xy 369.825099 -5.632186)
			(xy 369.793335 -5.726021) (xy 369.754029 -5.816954) (xy 369.707441 -5.904381) (xy 369.653883 -5.98772)
			(xy 369.59371 -6.066416) (xy 369.527322 -6.139945) (xy 369.455162 -6.207819) (xy 369.37771 -6.269585)
			(xy 369.295481 -6.324832) (xy 369.209023 -6.373193) (xy 369.11891 -6.414346) (xy 369.025743 -6.448018)
			(xy 368.930141 -6.473983) (xy 368.832741 -6.492069) (xy 368.734191 -6.502156) (xy 368.635147 -6.504177)
			(xy 368.536267 -6.498118) (xy 368.43821 -6.484019) (xy 368.341629 -6.461975) (xy 368.247166 -6.432132)
			(xy 368.15545 -6.394689) (xy 368.067091 -6.349895) (xy 367.982677 -6.298047) (xy 367.90277 -6.239492)
			(xy 367.827901 -6.174618) (xy 367.75857 -6.103858) (xy 367.695237 -6.027682) (xy 367.638324 -5.946597)
			(xy 367.588209 -5.861143) (xy 367.545226 -5.771888) (xy 367.509662 -5.679427) (xy 367.481752 -5.584375)
			(xy 367.461682 -5.487364) (xy 367.449587 -5.389041) (xy 367.445547 -5.290058) (xy 367.334215 -5.290058)
			(xy 367.334217 -5.2901) (xy 367.330279 -5.387811) (xy 367.318492 -5.484888) (xy 367.298931 -5.580702)
			(xy 367.271725 -5.674632) (xy 367.237048 -5.766067) (xy 367.195126 -5.854416) (xy 367.146232 -5.939105)
			(xy 367.090681 -6.019585) (xy 367.028834 -6.095335) (xy 366.961093 -6.165862) (xy 366.887897 -6.230709)
			(xy 366.80972 -6.289457) (xy 366.727069 -6.341723) (xy 366.64048 -6.387169) (xy 366.550516 -6.425501)
			(xy 366.457758 -6.456469) (xy 366.36281 -6.479873) (xy 366.266286 -6.495561) (xy 366.168813 -6.503431)
			(xy 366.119918 -6.503924) (xy 366.06958 -6.503389) (xy 365.969249 -6.495043) (xy 365.869955 -6.478416)
			(xy 365.772379 -6.453621) (xy 365.677192 -6.42083) (xy 365.585048 -6.380267) (xy 365.496581 -6.332211)
			(xy 365.412398 -6.276992) (xy 365.333078 -6.214991) (xy 365.259166 -6.146633) (xy 365.19117 -6.072387)
			(xy 365.129557 -5.992765) (xy 365.074751 -5.908312) (xy 365.027129 -5.819611) (xy 364.987017 -5.72727)
			(xy 364.954692 -5.631924) (xy 364.930375 -5.534227) (xy 364.9218 -5.484622) (xy 364.919547 -5.474131)
			(xy 364.907728 -5.456246) (xy 364.889642 -5.444737) (xy 364.868435 -5.441607) (xy 364.847796 -5.447401)
			(xy 364.83925 -5.453888) (xy 364.791204 -5.493253) (xy 364.690882 -5.566511) (xy 364.58614 -5.633297)
			(xy 364.477396 -5.693346) (xy 364.365083 -5.74642) (xy 364.249646 -5.792307) (xy 364.131546 -5.830824)
			(xy 364.011252 -5.861819) (xy 363.889244 -5.885167) (xy 363.766006 -5.900776) (xy 363.642029 -5.908584)
			(xy 363.579918 -5.909056) (xy 363.517217 -5.908534) (xy 363.39207 -5.900555) (xy 363.267684 -5.884628)
			(xy 363.144564 -5.860817) (xy 363.023209 -5.82922) (xy 362.904111 -5.789964) (xy 362.787752 -5.743208)
			(xy 362.674604 -5.689141) (xy 362.565127 -5.627985) (xy 362.459763 -5.559985) (xy 362.358941 -5.485417)
			(xy 362.263068 -5.404585) (xy 362.172533 -5.317815) (xy 362.087704 -5.22546) (xy 362.008924 -5.127893)
			(xy 361.936513 -5.025511) (xy 361.870764 -4.918728) (xy 361.811943 -4.807978) (xy 361.76029 -4.693709)
			(xy 361.716014 -4.576384) (xy 361.679293 -4.456479) (xy 361.650278 -4.334481) (xy 361.629085 -4.210883)
			(xy 361.615801 -4.086188) (xy 361.610479 -3.960899) (xy 77.832663 -3.960899) (xy 77.812411 -3.982464)
			(xy 77.72223 -4.067146) (xy 77.62691 -4.145999) (xy 77.526826 -4.218711) (xy 77.422375 -4.284995)
			(xy 77.313967 -4.34459) (xy 77.202032 -4.397261) (xy 77.08701 -4.442799) (xy 76.969355 -4.481024)
			(xy 76.849533 -4.511787) (xy 76.728016 -4.534965) (xy 76.605282 -4.550468) (xy 76.481818 -4.558233)
			(xy 76.419964 -4.558792) (xy 76.355152 -4.558266) (xy 76.225808 -4.549745) (xy 76.097305 -4.532734)
			(xy 75.970198 -4.507309) (xy 75.845039 -4.473578) (xy 75.72237 -4.431689) (xy 75.602722 -4.381822)
			(xy 75.486612 -4.324193) (xy 75.374545 -4.259052) (xy 75.267004 -4.186682) (xy 75.164457 -4.107394)
			(xy 75.067346 -4.021534) (xy 74.976093 -3.929473) (xy 74.891092 -3.831609) (xy 74.851514 -3.780282)
			(xy 74.843386 -3.76936) (xy 74.819002 -3.758946) (xy 74.704956 -3.772154) (xy 74.68362 -3.787648)
			(xy 74.678032 -3.800348) (xy 74.657456 -3.845184) (xy 74.61003 -3.931695) (xy 74.555736 -4.014069)
			(xy 74.494931 -4.091761) (xy 74.428018 -4.16426) (xy 74.355439 -4.231085) (xy 74.277672 -4.291795)
			(xy 74.195232 -4.34599) (xy 74.108664 -4.39331) (xy 74.018538 -4.433445) (xy 73.925451 -4.466128)
			(xy 73.830018 -4.491143) (xy 73.732868 -4.508326) (xy 73.634643 -4.517563) (xy 73.585324 -4.51866)
			(xy 73.575164 -4.51866) (xy 73.55713 -4.52628) (xy 73.513696 -4.569714) (xy 73.513696 -4.580382)
			(xy 73.55713 -4.623816) (xy 73.575164 -4.631436) (xy 73.585324 -4.631436) (xy 73.635092 -4.632558)
			(xy 73.734203 -4.641951) (xy 73.832212 -4.659432) (xy 73.928459 -4.684885) (xy 74.022296 -4.718138)
			(xy 74.113094 -4.758968) (xy 74.200242 -4.807099) (xy 74.283153 -4.862209) (xy 74.36127 -4.923926)
			(xy 74.434067 -4.991837) (xy 74.501056 -5.065483) (xy 74.561786 -5.14437) (xy 74.615848 -5.227968)
			(xy 74.662878 -5.315715) (xy 74.702562 -5.407019) (xy 74.734631 -5.501268) (xy 74.758871 -5.597827)
			(xy 74.775118 -5.696048) (xy 74.783262 -5.79527) (xy 74.783696 -5.845048) (xy 74.783176 -5.89522)
			(xy 74.774886 -5.995222) (xy 74.758366 -6.094198) (xy 74.733729 -6.191471) (xy 74.701144 -6.286378)
			(xy 74.660833 -6.37827) (xy 74.613071 -6.466519) (xy 74.558185 -6.550523) (xy 74.49655 -6.629707)
			(xy 74.428586 -6.703532) (xy 74.354758 -6.771491) (xy 74.275571 -6.833123) (xy 74.191564 -6.888004)
			(xy 74.103312 -6.935761) (xy 74.011419 -6.976067) (xy 73.91651 -7.008647) (xy 73.819235 -7.033279)
			(xy 73.720259 -7.049794) (xy 73.620256 -7.058079) (xy 73.570084 -7.05866) (xy 73.520312 -7.058154)
			(xy 73.421103 -7.049991) (xy 73.322895 -7.033729) (xy 73.22635 -7.009478) (xy 73.132116 -6.9774)
			(xy 73.040826 -6.937711) (xy 72.953093 -6.890678) (xy 72.869508 -6.836617) (xy 72.790631 -6.775892)
			(xy 72.716994 -6.70891) (xy 72.64909 -6.636121) (xy 72.587377 -6.558015) (xy 72.532269 -6.475116)
			(xy 72.484136 -6.387982) (xy 72.443302 -6.297198) (xy 72.410041 -6.203375) (xy 72.384577 -6.107142)
			(xy 72.367081 -6.009148) (xy 72.35767 -5.910049) (xy 72.356472 -5.860288) (xy 72.356472 -5.850128)
			(xy 72.348852 -5.832094) (xy 72.305418 -5.78866) (xy 72.29475 -5.78866) (xy 72.251316 -5.832094)
			(xy 72.243696 -5.850128) (xy 72.243696 -5.860288) (xy 72.242569 -5.910055) (xy 72.233169 -6.009164)
			(xy 72.21568 -6.10717) (xy 72.190222 -6.203414) (xy 72.156965 -6.297248) (xy 72.116133 -6.388043)
			(xy 72.068 -6.475188) (xy 72.01289 -6.558097) (xy 71.951173 -6.636213) (xy 71.883264 -6.70901) (xy 71.80962 -6.775999)
			(xy 71.730736 -6.83673) (xy 71.647142 -6.890795) (xy 71.5594 -6.93783) (xy 71.468099 -6.977518) (xy 71.373854 -7.009595)
			(xy 71.277298 -7.033842) (xy 71.17908 -7.050098) (xy 71.079861 -7.058254) (xy 70.980307 -7.058254)
			(xy 70.881088 -7.050098) (xy 70.78287 -7.033842) (xy 70.686314 -7.009595) (xy 70.592069 -6.977518)
			(xy 70.500768 -6.93783) (xy 70.413026 -6.890795) (xy 70.329432 -6.83673) (xy 70.250548 -6.775999)
			(xy 70.176904 -6.70901) (xy 70.108995 -6.636213) (xy 70.047278 -6.558097) (xy 69.992168 -6.475188)
			(xy 69.944035 -6.388043) (xy 69.903203 -6.297248) (xy 69.869946 -6.203414) (xy 69.844488 -6.10717)
			(xy 69.826999 -6.009164) (xy 69.817599 -5.910055) (xy 69.816472 -5.860288) (xy 69.816472 -5.850128)
			(xy 69.808852 -5.832094) (xy 69.773038 -5.79628) (xy 69.755004 -5.78866) (xy 69.744844 -5.78866)
			(xy 69.695077 -5.787533) (xy 69.595968 -5.778133) (xy 69.497962 -5.760645) (xy 69.401718 -5.735187)
			(xy 69.307883 -5.70193) (xy 69.217088 -5.661098) (xy 69.129943 -5.612966) (xy 69.047034 -5.557856)
			(xy 68.968918 -5.496139) (xy 68.896121 -5.42823) (xy 68.829132 -5.354586) (xy 68.768401 -5.275702)
			(xy 68.714336 -5.192108) (xy 68.667301 -5.104366) (xy 68.627612 -5.013065) (xy 68.595536 -4.91882)
			(xy 68.571288 -4.822264) (xy 68.555032 -4.724046) (xy 68.546876 -4.624827) (xy 68.546876 -4.525273)
			(xy 68.555032 -4.426054) (xy 68.571288 -4.327836) (xy 68.595536 -4.23128) (xy 68.627612 -4.137035)
			(xy 68.667301 -4.045734) (xy 68.714336 -3.957992) (xy 68.768401 -3.874398) (xy 68.829132 -3.795513)
			(xy 68.896121 -3.72187) (xy 68.968919 -3.653961) (xy 69.047034 -3.592244) (xy 69.129943 -3.537134)
			(xy 69.217088 -3.489002) (xy 69.307883 -3.44817) (xy 69.401718 -3.414913) (xy 69.497962 -3.389455)
			(xy 69.595968 -3.371967) (xy 69.695077 -3.362567) (xy 69.744844 -3.361436) (xy 69.755004 -3.361436)
			(xy 69.773038 -3.353816) (xy 69.816472 -3.310382) (xy 69.816472 -3.299714) (xy 69.773038 -3.25628)
			(xy 69.755004 -3.24866) (xy 69.744844 -3.24866) (xy 69.695077 -3.247537) (xy 69.595968 -3.238142)
			(xy 69.497961 -3.220658) (xy 69.401717 -3.195203) (xy 69.307881 -3.161949) (xy 69.217086 -3.121119)
			(xy 69.129941 -3.072986) (xy 69.047032 -3.017876) (xy 68.968918 -2.956158) (xy 68.896123 -2.888248)
			(xy 68.829136 -2.814602) (xy 68.768409 -2.735715) (xy 68.714349 -2.652118) (xy 68.667319 -2.564373)
			(xy 68.627637 -2.47307) (xy 68.595569 -2.378822) (xy 68.571331 -2.282264) (xy 68.555085 -2.184045)
			(xy 68.546941 -2.084825) (xy 68.546472 -2.035048) (xy 68.546921 -1.9882) (xy 68.554148 -1.894783)
			(xy 68.568555 -1.802201) (xy 68.590057 -1.711005) (xy 68.618525 -1.621739) (xy 68.65379 -1.534932)
			(xy 68.695643 -1.451103) (xy 68.743833 -1.37075) (xy 68.798074 -1.29435) (xy 68.858044 -1.22236)
			(xy 68.890388 -1.188466) (xy 68.901056 -1.177544) (xy 68.906644 -1.147572) (xy 68.86448 -1.047242)
			(xy 68.861028 -1.039615) (xy 68.849996 -1.027032) (xy 68.84289 -1.022604) (xy 68.830952 -1.016) (xy 60.070238 -1.016)
			(xy 60.060173 -1.016435) (xy 60.041585 -1.024165) (xy 60.03417 -1.030986) (xy 59.33948 -1.725676)
			(xy 59.332114 -1.732788) (xy 59.324494 -1.751584) (xy 59.324494 -3.033268) (xy 59.325051 -3.04438)
			(xy 59.334427 -3.064528) (xy 59.351436 -3.078829) (xy 59.372895 -3.084606) (xy 59.394785 -3.080777)
			(xy 59.40425 -3.074924) (xy 59.409398 -3.07115) (xy 59.417754 -3.061505) (xy 59.42076 -3.055874)
			(xy 59.449952 -2.998914) (xy 59.514728 -2.888509) (xy 59.586541 -2.782546) (xy 59.665086 -2.681472)
			(xy 59.750032 -2.585715) (xy 59.84102 -2.495678) (xy 59.937665 -2.411744) (xy 60.039558 -2.334265)
			(xy 60.146271 -2.263571) (xy 60.257351 -2.199958) (xy 60.372329 -2.143697) (xy 60.490719 -2.095024)
			(xy 60.612021 -2.054146) (xy 60.735723 -2.021235) (xy 60.861302 -1.996431) (xy 60.988227 -1.979838)
			(xy 61.115961 -1.971525) (xy 61.179964 -1.97104) (xy 61.241828 -1.971515) (xy 61.365311 -1.979282)
			(xy 61.488064 -1.994787) (xy 61.6096 -2.01797) (xy 61.729441 -2.048738) (xy 61.847113 -2.086971)
			(xy 61.962152 -2.132517) (xy 62.074105 -2.185197) (xy 62.182528 -2.244803) (xy 62.286995 -2.311099)
			(xy 62.387093 -2.383824) (xy 62.482427 -2.462691) (xy 62.57262 -2.547389) (xy 62.657317 -2.637582)
			(xy 62.736183 -2.732917) (xy 62.808908 -2.833015) (xy 62.875203 -2.937482) (xy 62.934808 -3.045906)
			(xy 62.987488 -3.157859) (xy 63.033033 -3.272898) (xy 63.071265 -3.390571) (xy 63.102033 -3.510412)
			(xy 63.125215 -3.631948) (xy 63.14072 -3.754701) (xy 63.148486 -3.878184) (xy 63.148972 -3.940048)
			(xy 63.148693 -3.989089) (xy 63.143865 -4.087051) (xy 63.13932 -4.135882) (xy 63.138304 -4.143756)
			(xy 63.140082 -4.151884) (xy 63.142664 -4.161594) (xy 63.154183 -4.178037) (xy 63.171124 -4.188812)
			(xy 63.1909 -4.192273) (xy 63.200788 -4.190492) (xy 63.210948 -4.188206) (xy 63.215774 -4.18592)
			(xy 63.263304 -4.164808) (xy 63.361258 -4.129838) (xy 63.461847 -4.103384) (xy 63.564332 -4.085642)
			(xy 63.667959 -4.076741) (xy 63.719964 -4.076192) (xy 63.769128 -4.076681) (xy 63.867134 -4.084635)
			(xy 63.964174 -4.100493) (xy 64.059613 -4.124152) (xy 64.152825 -4.155457) (xy 64.243198 -4.194202)
			(xy 64.330139 -4.240132) (xy 64.413078 -4.292948) (xy 64.491471 -4.352301) (xy 64.564805 -4.417804)
			(xy 64.632597 -4.489026) (xy 64.694403 -4.565501) (xy 64.749819 -4.646726) (xy 64.79848 -4.732169)
			(xy 64.840067 -4.821269) (xy 64.874308 -4.913443) (xy 64.900978 -5.008085) (xy 64.919901 -5.104574)
			(xy 64.930955 -5.202279) (xy 64.933734 -5.290058) (xy 65.045593 -5.290058) (xy 65.049633 -5.191075)
			(xy 65.061728 -5.092752) (xy 65.081798 -4.995741) (xy 65.109708 -4.900689) (xy 65.145272 -4.808228)
			(xy 65.188255 -4.718973) (xy 65.23837 -4.633519) (xy 65.295283 -4.552434) (xy 65.358616 -4.476258)
			(xy 65.427947 -4.405498) (xy 65.502816 -4.340624) (xy 65.582723 -4.282069) (xy 65.667137 -4.230221)
			(xy 65.755496 -4.185427) (xy 65.847212 -4.147984) (xy 65.941675 -4.118141) (xy 66.038256 -4.096097)
			(xy 66.136313 -4.081998) (xy 66.235193 -4.075939) (xy 66.334237 -4.07796) (xy 66.432787 -4.088047)
			(xy 66.530187 -4.106133) (xy 66.625789 -4.132098) (xy 66.718956 -4.16577) (xy 66.809069 -4.206923)
			(xy 66.895527 -4.255284) (xy 66.977756 -4.310531) (xy 67.055208 -4.372297) (xy 67.127368 -4.440171)
			(xy 67.193756 -4.5137) (xy 67.253929 -4.592396) (xy 67.307487 -4.675735) (xy 67.354075 -4.763162)
			(xy 67.393381 -4.854095) (xy 67.425145 -4.94793) (xy 67.449154 -5.044041) (xy 67.46525 -5.14179)
			(xy 67.473325 -5.240526) (xy 67.47383 -5.290058) (xy 67.473325 -5.33959) (xy 67.46525 -5.438326)
			(xy 67.449154 -5.536075) (xy 67.425145 -5.632186) (xy 67.393381 -5.726021) (xy 67.354075 -5.816954)
			(xy 67.307487 -5.904381) (xy 67.253929 -5.98772) (xy 67.193756 -6.066416) (xy 67.127368 -6.139945)
			(xy 67.055208 -6.207819) (xy 66.977756 -6.269585) (xy 66.895527 -6.324832) (xy 66.809069 -6.373193)
			(xy 66.718956 -6.414346) (xy 66.625789 -6.448018) (xy 66.530187 -6.473983) (xy 66.432787 -6.492069)
			(xy 66.334237 -6.502156) (xy 66.235193 -6.504177) (xy 66.136313 -6.498118) (xy 66.038256 -6.484019)
			(xy 65.941675 -6.461975) (xy 65.847212 -6.432132) (xy 65.755496 -6.394689) (xy 65.667137 -6.349895)
			(xy 65.582723 -6.298047) (xy 65.502816 -6.239492) (xy 65.427947 -6.174618) (xy 65.358616 -6.103858)
			(xy 65.295283 -6.027682) (xy 65.23837 -5.946597) (xy 65.188255 -5.861143) (xy 65.145272 -5.771888)
			(xy 65.109708 -5.679427) (xy 65.081798 -5.584375) (xy 65.061728 -5.487364) (xy 65.049633 -5.389041)
			(xy 65.045593 -5.290058) (xy 64.933734 -5.290058) (xy 64.934066 -5.300558) (xy 64.929214 -5.398766)
			(xy 64.916431 -5.496259) (xy 64.8958 -5.592399) (xy 64.867457 -5.686553) (xy 64.831589 -5.778105)
			(xy 64.788429 -5.866455) (xy 64.738262 -5.951022) (xy 64.681416 -6.031252) (xy 64.618264 -6.106619)
			(xy 64.54922 -6.176629) (xy 64.474737 -6.240822) (xy 64.395305 -6.298777) (xy 64.311443 -6.350115)
			(xy 64.223701 -6.394498) (xy 64.132656 -6.431635) (xy 64.038904 -6.461283) (xy 63.943061 -6.483247)
			(xy 63.845755 -6.497383) (xy 63.747623 -6.503599) (xy 63.649311 -6.501854) (xy 63.551462 -6.492159)
			(xy 63.454719 -6.474577) (xy 63.359715 -6.449225) (xy 63.267075 -6.416268) (xy 63.177406 -6.375923)
			(xy 63.091295 -6.328454) (xy 63.009308 -6.274172) (xy 62.931982 -6.213434) (xy 62.859825 -6.146638)
			(xy 62.79331 -6.074221) (xy 62.732873 -5.99666) (xy 62.67891 -5.914463) (xy 62.631776 -5.828168)
			(xy 62.59178 -5.738342) (xy 62.559183 -5.645575) (xy 62.5342 -5.550474) (xy 62.525148 -5.502148)
			(xy 62.523624 -5.493512) (xy 62.514734 -5.478272) (xy 62.481206 -5.449824) (xy 62.44463 -5.44957)
			(xy 62.430406 -5.461254) (xy 62.382519 -5.49998) (xy 62.282651 -5.572069) (xy 62.178473 -5.637778)
			(xy 62.070393 -5.696848) (xy 61.958833 -5.749049) (xy 61.84423 -5.794178) (xy 61.72703 -5.832058)
			(xy 61.607693 -5.86254) (xy 61.486684 -5.885506) (xy 61.364477 -5.900866) (xy 61.241548 -5.90856)
			(xy 61.179964 -5.909056) (xy 61.115963 -5.908542) (xy 60.988231 -5.900224) (xy 60.861309 -5.883627)
			(xy 60.735733 -5.858819) (xy 60.612035 -5.825906) (xy 60.490735 -5.785027) (xy 60.372348 -5.736354)
			(xy 60.257372 -5.680093) (xy 60.146294 -5.616483) (xy 60.039583 -5.54579) (xy 59.93769 -5.468315)
			(xy 59.841044 -5.384385) (xy 59.750056 -5.294353) (xy 59.665108 -5.198601) (xy 59.586559 -5.097532)
			(xy 59.514743 -4.991575) (xy 59.449961 -4.881176) (xy 59.42076 -4.824222) (xy 59.417721 -4.818613)
			(xy 59.409375 -4.80897) (xy 59.40425 -4.805172) (xy 59.394807 -4.799302) (xy 59.372922 -4.795515)
			(xy 59.351481 -4.801307) (xy 59.33448 -4.815598) (xy 59.325089 -4.835724) (xy 59.324494 -4.846828)
			(xy 59.324494 -18.236946) (xy 59.324821 -18.24546) (xy 59.33041 -18.261546) (xy 59.335416 -18.268442)
			(xy 59.341004 -18.275554) (xy 59.355228 -18.284444) (xy 59.36361 -18.286476) (xy 59.430146 -18.302606)
			(xy 59.561393 -18.341619) (xy 59.690145 -18.388208) (xy 59.815966 -18.442217) (xy 59.93118 -18.499836)
			(xy 65.86474 -18.499836) (xy 65.86474 -13.499846) (xy 65.865235 -13.399005) (xy 65.873153 -13.197478)
			(xy 65.888977 -12.996418) (xy 65.912682 -12.796134) (xy 65.944232 -12.596935) (xy 65.983578 -12.399128)
			(xy 66.03066 -12.203019) (xy 66.085405 -12.008909) (xy 66.147728 -11.817098) (xy 66.217533 -11.627881)
			(xy 66.294714 -11.441552) (xy 66.37915 -11.258395) (xy 66.470712 -11.078695) (xy 66.569258 -10.902729)
			(xy 66.674636 -10.730766) (xy 66.786685 -10.563074) (xy 66.905231 -10.39991) (xy 67.030091 -10.241525)
			(xy 67.161073 -10.088165) (xy 67.297975 -9.940065) (xy 67.440585 -9.797455) (xy 67.588685 -9.660553)
			(xy 67.742045 -9.529571) (xy 67.90043 -9.404711) (xy 68.063594 -9.286165) (xy 68.231286 -9.174116)
			(xy 68.403249 -9.068738) (xy 68.579215 -8.970192) (xy 68.758915 -8.87863) (xy 68.942072 -8.794194)
			(xy 69.128401 -8.717013) (xy 69.317618 -8.647208) (xy 69.509429 -8.584885) (xy 69.703539 -8.53014)
			(xy 69.899648 -8.483058) (xy 70.097455 -8.443712) (xy 70.296654 -8.412162) (xy 70.496938 -8.388457)
			(xy 70.697998 -8.372633) (xy 70.899525 -8.364715) (xy 71.101207 -8.364715) (xy 71.302734 -8.372633)
			(xy 71.503794 -8.388457) (xy 71.704078 -8.412162) (xy 71.903277 -8.443712) (xy 72.101084 -8.483058)
			(xy 72.297193 -8.53014) (xy 72.491303 -8.584885) (xy 72.683114 -8.647208) (xy 72.872331 -8.717013)
			(xy 73.05866 -8.794194) (xy 73.241817 -8.87863) (xy 73.421517 -8.970192) (xy 73.597483 -9.068738)
			(xy 73.769446 -9.174116) (xy 73.937138 -9.286165) (xy 74.100302 -9.404711) (xy 74.258687 -9.529571)
			(xy 74.412047 -9.660553) (xy 74.560147 -9.797455) (xy 74.702757 -9.940065) (xy 74.720815 -9.9596)
			(xy 79.060327 -9.9596) (xy 79.064359 -9.874976) (xy 79.076415 -9.791119) (xy 79.096388 -9.708788)
			(xy 79.124096 -9.628727) (xy 79.159289 -9.551663) (xy 79.201648 -9.478293) (xy 79.250789 -9.409282)
			(xy 79.306267 -9.345254) (xy 79.367581 -9.28679) (xy 79.434174 -9.234418) (xy 79.505443 -9.188613)
			(xy 79.580744 -9.149791) (xy 79.659394 -9.118301) (xy 79.740681 -9.09443) (xy 79.823869 -9.078394)
			(xy 79.908204 -9.070338) (xy 79.950564 -9.069832) (xy 79.996967 -9.07044) (xy 80.089264 -9.080136)
			(xy 80.18005 -9.099395) (xy 80.268334 -9.128008) (xy 80.31099 -9.146286) (xy 80.320932 -9.150092)
			(xy 80.342196 -9.150092) (xy 80.352138 -9.146286) (xy 80.394802 -9.128033) (xy 80.483089 -9.099438)
			(xy 80.573871 -9.080178) (xy 80.666163 -9.070463) (xy 80.712564 -9.069832) (xy 80.758967 -9.07044)
			(xy 80.851264 -9.080136) (xy 80.94205 -9.099395) (xy 81.030334 -9.128008) (xy 81.07299 -9.146286)
			(xy 81.082932 -9.150092) (xy 81.104196 -9.150092) (xy 81.114138 -9.146286) (xy 81.156802 -9.128033)
			(xy 81.245089 -9.099438) (xy 81.335871 -9.080178) (xy 81.428163 -9.070463) (xy 81.474564 -9.069832)
			(xy 81.520967 -9.07044) (xy 81.613264 -9.080136) (xy 81.70405 -9.099395) (xy 81.792334 -9.128008)
			(xy 81.83499 -9.146286) (xy 81.844932 -9.150092) (xy 81.866196 -9.150092) (xy 81.876138 -9.146286)
			(xy 81.918802 -9.128033) (xy 82.007089 -9.099438) (xy 82.097871 -9.080178) (xy 82.190163 -9.070463)
			(xy 82.236564 -9.069832) (xy 82.278926 -9.070331) (xy 82.363267 -9.078381) (xy 82.446461 -9.094412)
			(xy 82.527754 -9.118279) (xy 82.60641 -9.149766) (xy 82.681717 -9.188586) (xy 82.752993 -9.23439)
			(xy 82.819592 -9.286761) (xy 82.880911 -9.345227) (xy 82.936395 -9.409256) (xy 82.985541 -9.478269)
			(xy 83.027904 -9.551642) (xy 83.0631 -9.62871) (xy 83.090812 -9.708774) (xy 83.110787 -9.79111) (xy 83.122845 -9.874972)
			(xy 83.126876 -9.9596) (xy 83.122845 -10.044228) (xy 83.110787 -10.12809) (xy 83.090812 -10.210426)
			(xy 83.0631 -10.29049) (xy 83.027904 -10.367558) (xy 82.985541 -10.440931) (xy 82.936395 -10.509944)
			(xy 82.880911 -10.573973) (xy 82.819592 -10.632439) (xy 82.752993 -10.68481) (xy 82.681717 -10.730614)
			(xy 82.60641 -10.769434) (xy 82.527754 -10.800921) (xy 82.446461 -10.824788) (xy 82.363267 -10.840819)
			(xy 82.278926 -10.848869) (xy 82.236564 -10.849356) (xy 82.190162 -10.848739) (xy 82.097864 -10.839046)
			(xy 82.007079 -10.819789) (xy 81.918794 -10.791179) (xy 81.876138 -10.772902) (xy 81.866196 -10.769096)
			(xy 81.844932 -10.769096) (xy 81.83499 -10.772902) (xy 81.792335 -10.791178) (xy 81.704045 -10.819767)
			(xy 81.61326 -10.83902) (xy 81.520965 -10.848729) (xy 81.474564 -10.849356) (xy 81.428162 -10.848739)
			(xy 81.335864 -10.839046) (xy 81.245079 -10.819789) (xy 81.156794 -10.791179) (xy 81.114138 -10.772902)
			(xy 81.104196 -10.769096) (xy 81.082932 -10.769096) (xy 81.07299 -10.772902) (xy 81.030335 -10.791178)
			(xy 80.942045 -10.819767) (xy 80.85126 -10.83902) (xy 80.758965 -10.848729) (xy 80.712564 -10.849356)
			(xy 80.666162 -10.848739) (xy 80.573864 -10.839046) (xy 80.483079 -10.819789) (xy 80.394794 -10.791179)
			(xy 80.352138 -10.772902) (xy 80.342196 -10.769096) (xy 80.320932 -10.769096) (xy 80.31099 -10.772902)
			(xy 80.268335 -10.791178) (xy 80.180045 -10.819767) (xy 80.08926 -10.83902) (xy 79.996965 -10.848729)
			(xy 79.950564 -10.849356) (xy 79.908204 -10.848862) (xy 79.823869 -10.840806) (xy 79.740681 -10.82477)
			(xy 79.659394 -10.800899) (xy 79.580744 -10.769409) (xy 79.505443 -10.730587) (xy 79.434174 -10.684782)
			(xy 79.367581 -10.63241) (xy 79.306267 -10.573946) (xy 79.250789 -10.509918) (xy 79.201648 -10.440907)
			(xy 79.159289 -10.367537) (xy 79.124096 -10.290473) (xy 79.096388 -10.210412) (xy 79.076415 -10.128081)
			(xy 79.064359 -10.044224) (xy 79.060327 -9.9596) (xy 74.720815 -9.9596) (xy 74.839659 -10.088165)
			(xy 74.970641 -10.241525) (xy 75.095501 -10.39991) (xy 75.214047 -10.563074) (xy 75.326096 -10.730766)
			(xy 75.431474 -10.902729) (xy 75.53002 -11.078695) (xy 75.621582 -11.258395) (xy 75.706018 -11.441552)
			(xy 75.783199 -11.627881) (xy 75.853004 -11.817098) (xy 75.915327 -12.008909) (xy 75.970072 -12.203019)
			(xy 76.017154 -12.399128) (xy 76.0565 -12.596935) (xy 76.08805 -12.796134) (xy 76.111755 -12.996418)
			(xy 76.127579 -13.197478) (xy 76.135497 -13.399005) (xy 76.135992 -13.499846) (xy 76.135992 -16.383)
			(xy 79.628492 -16.383) (xy 79.628492 -16.382746) (xy 79.628984 -16.338974) (xy 79.637598 -16.251856)
			(xy 79.654727 -16.166004) (xy 79.680206 -16.08225) (xy 79.713788 -16.001404) (xy 79.755149 -15.924247)
			(xy 79.803888 -15.851526) (xy 79.859534 -15.783944) (xy 79.92155 -15.722154) (xy 79.989335 -15.666755)
			(xy 80.025494 -15.642082) (xy 80.035908 -15.63497) (xy 80.0481 -15.612618) (xy 80.0481 -15.502382)
			(xy 80.035908 -15.48003) (xy 80.025494 -15.472918) (xy 79.989334 -15.448245) (xy 79.921543 -15.392853)
			(xy 79.859522 -15.331068) (xy 79.803872 -15.263488) (xy 79.755132 -15.190767) (xy 79.713774 -15.113608)
			(xy 79.680197 -15.032759) (xy 79.654728 -14.949002) (xy 79.637611 -14.863147) (xy 79.629013 -14.776026)
			(xy 79.628492 -14.732254) (xy 79.628492 -14.732) (xy 79.628996 -14.689652) (xy 79.637047 -14.605338)
			(xy 79.653076 -14.522172) (xy 79.676937 -14.440905) (xy 79.708416 -14.362275) (xy 79.747227 -14.286994)
			(xy 79.793017 -14.215742) (xy 79.845373 -14.149166) (xy 79.903821 -14.087868) (xy 79.967831 -14.032403)
			(xy 80.036823 -13.983274) (xy 80.110173 -13.940925) (xy 80.187216 -13.905741) (xy 80.267255 -13.878039)
			(xy 80.349564 -13.858071) (xy 80.433399 -13.846018) (xy 80.518 -13.841988) (xy 80.602601 -13.846018)
			(xy 80.686436 -13.858071) (xy 80.768745 -13.878039) (xy 80.848784 -13.905741) (xy 80.925827 -13.940925)
			(xy 80.999177 -13.983274) (xy 81.068169 -14.032403) (xy 81.132179 -14.087868) (xy 81.190627 -14.149166)
			(xy 81.242983 -14.215742) (xy 81.288773 -14.286994) (xy 81.327584 -14.362275) (xy 81.359063 -14.440905)
			(xy 81.382924 -14.522172) (xy 81.398953 -14.605338) (xy 81.407004 -14.689652) (xy 81.407508 -14.732)
			(xy 81.407508 -14.73327) (xy 81.406985 -14.775684) (xy 81.39886 -14.860123) (xy 81.382718 -14.943402)
			(xy 81.371186 -14.984222) (xy 81.36763 -14.99616) (xy 81.372202 -15.020544) (xy 81.440274 -15.105126)
			(xy 81.46288 -15.115032) (xy 81.475326 -15.11427) (xy 81.534 -15.112492) (xy 81.575796 -15.112999)
			(xy 81.659019 -15.120839) (xy 81.741139 -15.13645) (xy 81.821434 -15.159694) (xy 81.899195 -15.190366)
			(xy 81.973736 -15.228197) (xy 82.0444 -15.272851) (xy 82.110565 -15.323937) (xy 82.171647 -15.381003)
			(xy 82.199734 -15.411958) (xy 82.206925 -15.41932) (xy 82.225537 -15.428067) (xy 82.246085 -15.428874)
			(xy 82.255868 -15.425674) (xy 82.294054 -15.411496) (xy 82.372448 -15.389352) (xy 82.452538 -15.37447)
			(xy 82.533654 -15.366973) (xy 82.574384 -15.366492) (xy 82.5754 -15.366492) (xy 82.617748 -15.366996)
			(xy 82.702062 -15.375047) (xy 82.785228 -15.391076) (xy 82.866495 -15.414937) (xy 82.945125 -15.446416)
			(xy 83.020406 -15.485227) (xy 83.091658 -15.531017) (xy 83.158234 -15.583373) (xy 83.219532 -15.641821)
			(xy 83.274997 -15.705831) (xy 83.324126 -15.774823) (xy 83.366475 -15.848173) (xy 83.401659 -15.925216)
			(xy 83.429361 -16.005255) (xy 83.449329 -16.087564) (xy 83.454073 -16.120561) (xy 83.565742 -16.120561)
			(xy 83.565742 -16.035839) (xy 83.573795 -15.951502) (xy 83.589829 -15.868312) (xy 83.613697 -15.787022)
			(xy 83.645185 -15.70837) (xy 83.684007 -15.633067) (xy 83.72981 -15.561795) (xy 83.782181 -15.495199)
			(xy 83.840646 -15.433884) (xy 83.904674 -15.378403) (xy 83.973686 -15.32926) (xy 84.047056 -15.2869)
			(xy 84.124121 -15.251705) (xy 84.204183 -15.223996) (xy 84.286516 -15.204022) (xy 84.370375 -15.191965)
			(xy 84.455 -15.187934) (xy 84.539625 -15.191965) (xy 84.623484 -15.204022) (xy 84.705817 -15.223996)
			(xy 84.785879 -15.251705) (xy 84.862944 -15.2869) (xy 84.936314 -15.32926) (xy 85.005326 -15.378403)
			(xy 85.069354 -15.433884) (xy 85.127819 -15.495199) (xy 85.18019 -15.561795) (xy 85.225993 -15.633067)
			(xy 85.264815 -15.70837) (xy 85.296303 -15.787022) (xy 85.320171 -15.868312) (xy 85.336205 -15.951502)
			(xy 85.344258 -16.035839) (xy 85.344762 -16.0782) (xy 85.344258 -16.120561) (xy 85.336205 -16.204898)
			(xy 85.320171 -16.288088) (xy 85.296303 -16.369378) (xy 85.264815 -16.44803) (xy 85.225993 -16.523333)
			(xy 85.18019 -16.594605) (xy 85.127819 -16.661201) (xy 85.069354 -16.722516) (xy 85.005326 -16.777997)
			(xy 84.936314 -16.82714) (xy 84.862944 -16.8695) (xy 84.785879 -16.904695) (xy 84.705817 -16.932404)
			(xy 84.623484 -16.952378) (xy 84.539625 -16.964435) (xy 84.455 -16.968467) (xy 84.370375 -16.964435)
			(xy 84.286516 -16.952378) (xy 84.204183 -16.932404) (xy 84.124121 -16.904695) (xy 84.047056 -16.8695)
			(xy 83.973686 -16.82714) (xy 83.904674 -16.777997) (xy 83.840646 -16.722516) (xy 83.782181 -16.661201)
			(xy 83.72981 -16.594605) (xy 83.684007 -16.523333) (xy 83.645185 -16.44803) (xy 83.613697 -16.369378)
			(xy 83.589829 -16.288088) (xy 83.573795 -16.204898) (xy 83.565742 -16.120561) (xy 83.454073 -16.120561)
			(xy 83.461382 -16.171399) (xy 83.465413 -16.256) (xy 83.461382 -16.340601) (xy 83.449329 -16.424436)
			(xy 83.429361 -16.506745) (xy 83.401659 -16.586784) (xy 83.366475 -16.663827) (xy 83.324126 -16.737177)
			(xy 83.274997 -16.806169) (xy 83.219532 -16.870179) (xy 83.158234 -16.928627) (xy 83.091658 -16.980983)
			(xy 83.020406 -17.026773) (xy 82.945125 -17.065584) (xy 82.866495 -17.097063) (xy 82.785228 -17.120924)
			(xy 82.702062 -17.136953) (xy 82.617748 -17.145004) (xy 82.5754 -17.145508) (xy 82.551778 -17.145254)
			(xy 82.541009 -17.145479) (xy 82.521167 -17.153813) (xy 82.50646 -17.169526) (xy 82.502502 -17.179544)
			(xy 82.488271 -17.21954) (xy 82.453203 -17.29686) (xy 82.410929 -17.370486) (xy 82.361831 -17.43975)
			(xy 82.306357 -17.50402) (xy 82.245012 -17.562712) (xy 82.178353 -17.615292) (xy 82.106988 -17.661282)
			(xy 82.031566 -17.700262) (xy 81.952772 -17.731879) (xy 81.871325 -17.755844) (xy 81.787965 -17.77194)
			(xy 81.70345 -17.78002) (xy 81.661 -17.780508) (xy 81.618522 -17.779969) (xy 81.533953 -17.771871)
			(xy 81.450542 -17.755749) (xy 81.369046 -17.731751) (xy 81.290209 -17.700093) (xy 81.214749 -17.661066)
			(xy 81.143352 -17.615023) (xy 81.076669 -17.562385) (xy 81.015306 -17.50363) (xy 80.959824 -17.439294)
			(xy 80.910726 -17.369962) (xy 80.86846 -17.296267) (xy 80.850486 -17.257776) (xy 80.846331 -17.249478)
			(xy 80.833181 -17.236403) (xy 80.816233 -17.228878) (xy 80.797715 -17.227892) (xy 80.788764 -17.230344)
			(xy 80.744944 -17.243758) (xy 80.655239 -17.26252) (xy 80.564077 -17.271943) (xy 80.518254 -17.272508)
			(xy 80.518 -17.272508) (xy 80.476898 -17.272033) (xy 80.395043 -17.264448) (xy 80.314238 -17.249343)
			(xy 80.235171 -17.226847) (xy 80.158517 -17.197151) (xy 80.08493 -17.160509) (xy 80.015038 -17.117234)
			(xy 79.949437 -17.067694) (xy 79.888687 -17.012313) (xy 79.833306 -16.951563) (xy 79.783766 -16.885962)
			(xy 79.740491 -16.81607) (xy 79.703849 -16.742483) (xy 79.674153 -16.665829) (xy 79.651657 -16.586762)
			(xy 79.636552 -16.505957) (xy 79.628967 -16.424102) (xy 79.628492 -16.383) (xy 76.135992 -16.383)
			(xy 76.135992 -18.499836) (xy 76.135497 -18.600677) (xy 76.127579 -18.802204) (xy 76.118576 -18.9166)
			(xy 79.627784 -18.9166) (xy 79.631814 -18.83198) (xy 79.643871 -18.748125) (xy 79.663844 -18.665797)
			(xy 79.691552 -18.58574) (xy 79.726744 -18.508679) (xy 79.769102 -18.435313) (xy 79.818243 -18.366305)
			(xy 79.87372 -18.30228) (xy 79.935032 -18.243819) (xy 80.001624 -18.191451) (xy 80.072892 -18.14565)
			(xy 80.148191 -18.106831) (xy 80.226839 -18.075345) (xy 80.308124 -18.051477) (xy 80.391309 -18.035445)
			(xy 80.475642 -18.027392) (xy 80.518 -18.026888) (xy 80.559512 -18.02738) (xy 80.642172 -18.035148)
			(xy 80.723748 -18.050588) (xy 80.803529 -18.073566) (xy 80.880821 -18.103881) (xy 80.95495 -18.14127)
			(xy 81.02527 -18.185407) (xy 81.058512 -18.210276) (xy 81.067711 -18.216619) (xy 81.0895 -18.22145)
			(xy 81.111289 -18.216619) (xy 81.120488 -18.210276) (xy 81.153746 -18.185432) (xy 81.224072 -18.14131)
			(xy 81.298201 -18.103931) (xy 81.37549 -18.073618) (xy 81.455266 -18.050635) (xy 81.536836 -18.035183)
			(xy 81.61949 -18.027395) (xy 81.661 -18.026888) (xy 81.702547 -18.027384) (xy 81.785278 -18.035131)
			(xy 81.866928 -18.050558) (xy 81.946783 -18.073529) (xy 82.024148 -18.103846) (xy 82.098351 -18.141243)
			(xy 82.168743 -18.185396) (xy 82.20202 -18.210276) (xy 82.211199 -18.21654) (xy 82.232881 -18.221297)
			(xy 82.254563 -18.21654) (xy 82.263742 -18.210276) (xy 82.296989 -18.185466) (xy 82.367298 -18.141428)
			(xy 82.441403 -18.104129) (xy 82.518659 -18.073894) (xy 82.598395 -18.050984) (xy 82.679918 -18.0356)
			(xy 82.762519 -18.027874) (xy 82.804 -18.027396) (xy 82.845505 -18.027868) (xy 82.928151 -18.035625)
			(xy 83.009716 -18.051045) (xy 83.089491 -18.073992) (xy 83.166783 -18.104267) (xy 83.24092 -18.141608)
			(xy 83.311258 -18.18569) (xy 83.344512 -18.21053) (xy 83.353711 -18.216873) (xy 83.3755 -18.221704)
			(xy 83.397289 -18.216873) (xy 83.406488 -18.21053) (xy 83.439722 -18.18569) (xy 83.510017 -18.141604)
			(xy 83.584115 -18.104261) (xy 83.661371 -18.073986) (xy 83.741112 -18.051042) (xy 83.822644 -18.03563)
			(xy 83.905258 -18.027882) (xy 83.946746 -18.027396) (xy 83.947 -18.027396) (xy 83.989349 -18.027892)
			(xy 84.073663 -18.035943) (xy 84.156829 -18.051972) (xy 84.238096 -18.075834) (xy 84.316726 -18.107313)
			(xy 84.392008 -18.146123) (xy 84.46326 -18.191914) (xy 84.529837 -18.24427) (xy 84.591135 -18.302718)
			(xy 84.6466 -18.366728) (xy 84.69573 -18.435721) (xy 84.738078 -18.509071) (xy 84.773263 -18.586114)
			(xy 84.800965 -18.666153) (xy 84.820933 -18.748463) (xy 84.832986 -18.832299) (xy 84.837017 -18.9169)
			(xy 84.832986 -19.001501) (xy 84.820933 -19.085337) (xy 84.800965 -19.167647) (xy 84.773263 -19.247686)
			(xy 84.738078 -19.324729) (xy 84.69573 -19.398079) (xy 84.6466 -19.467072) (xy 84.591135 -19.531082)
			(xy 84.529837 -19.58953) (xy 84.46326 -19.641886) (xy 84.392008 -19.687677) (xy 84.316726 -19.726487)
			(xy 84.238096 -19.757966) (xy 84.156829 -19.781828) (xy 84.073663 -19.797857) (xy 83.989349 -19.805908)
			(xy 83.947 -19.806412) (xy 83.946746 -19.806412) (xy 83.90526 -19.805927) (xy 83.822651 -19.798153)
			(xy 83.741125 -19.782724) (xy 83.661389 -19.759774) (xy 83.584134 -19.729503) (xy 83.510033 -19.692173)
			(xy 83.439728 -19.648108) (xy 83.406488 -19.623278) (xy 83.397289 -19.616935) (xy 83.3755 -19.612104)
			(xy 83.353711 -19.616935) (xy 83.344512 -19.623278) (xy 83.308449 -19.650238) (xy 83.231848 -19.697573)
			(xy 83.191604 -19.717766) (xy 83.181507 -19.723256) (xy 83.167223 -19.741231) (xy 83.164172 -19.75231)
			(xy 83.154228 -19.794062) (xy 83.127492 -19.875624) (xy 83.093025 -19.954232) (xy 83.051147 -20.029155)
			(xy 83.002247 -20.099696) (xy 82.946781 -20.165199) (xy 82.885264 -20.225055) (xy 82.818267 -20.278709)
			(xy 82.746415 -20.325659) (xy 82.670374 -20.365472) (xy 82.590852 -20.397775) (xy 82.508589 -20.422269)
			(xy 82.424349 -20.438726) (xy 82.338916 -20.446993) (xy 82.296 -20.447508) (xy 82.254987 -20.44704)
			(xy 82.173311 -20.439473) (xy 82.092678 -20.424422) (xy 82.013773 -20.402015) (xy 81.937264 -20.372441)
			(xy 81.863801 -20.335953) (xy 81.794008 -20.292858) (xy 81.728476 -20.243524) (xy 81.667763 -20.188369)
			(xy 81.612383 -20.12786) (xy 81.562807 -20.062512) (xy 81.519454 -19.992879) (xy 81.482694 -19.919552)
			(xy 81.452837 -19.843153) (xy 81.441036 -19.803872) (xy 81.43843 -19.795746) (xy 81.428677 -19.781756)
			(xy 81.414834 -19.771796) (xy 81.406746 -19.769074) (xy 81.36817 -19.757065) (xy 81.293165 -19.727026)
			(xy 81.221192 -19.690309) (xy 81.152844 -19.647218) (xy 81.120488 -19.623024) (xy 81.111289 -19.616681)
			(xy 81.0895 -19.61185) (xy 81.067711 -19.616681) (xy 81.058512 -19.623024) (xy 81.025254 -19.647868)
			(xy 80.954928 -19.69199) (xy 80.880799 -19.729369) (xy 80.80351 -19.759682) (xy 80.723734 -19.782665)
			(xy 80.642164 -19.798117) (xy 80.55951 -19.805905) (xy 80.518 -19.806412) (xy 80.475642 -19.805808)
			(xy 80.391309 -19.797755) (xy 80.308124 -19.781723) (xy 80.226839 -19.757855) (xy 80.148191 -19.726369)
			(xy 80.072892 -19.68755) (xy 80.001624 -19.641749) (xy 79.935032 -19.589381) (xy 79.87372 -19.53092)
			(xy 79.818243 -19.466895) (xy 79.769102 -19.397887) (xy 79.726744 -19.324521) (xy 79.691552 -19.24746)
			(xy 79.663844 -19.167403) (xy 79.643871 -19.085075) (xy 79.631814 -19.00122) (xy 79.627784 -18.9166)
			(xy 76.118576 -18.9166) (xy 76.111755 -19.003264) (xy 76.08805 -19.203548) (xy 76.0565 -19.402747)
			(xy 76.017154 -19.600554) (xy 75.970072 -19.796663) (xy 75.915327 -19.990773) (xy 75.853004 -20.182584)
			(xy 75.783199 -20.371801) (xy 75.706018 -20.55813) (xy 75.621582 -20.741287) (xy 75.53002 -20.920987)
			(xy 75.431474 -21.096953) (xy 75.326096 -21.268916) (xy 75.214047 -21.436608) (xy 75.095501 -21.599772)
			(xy 74.970641 -21.758157) (xy 74.839659 -21.911517) (xy 74.702757 -22.059617) (xy 74.560147 -22.202227)
			(xy 74.412047 -22.339129) (xy 74.258687 -22.470111) (xy 74.100302 -22.594971) (xy 73.937138 -22.713517)
			(xy 73.769446 -22.825566) (xy 73.597483 -22.930944) (xy 73.421517 -23.02949) (xy 73.241817 -23.121052)
			(xy 73.05866 -23.205488) (xy 72.872331 -23.282669) (xy 72.683114 -23.352474) (xy 72.491303 -23.414797)
			(xy 72.297193 -23.469542) (xy 72.101084 -23.516624) (xy 71.903277 -23.55597) (xy 71.704078 -23.58752)
			(xy 71.503794 -23.611225) (xy 71.302734 -23.627049) (xy 71.101207 -23.634967) (xy 70.899525 -23.634967)
			(xy 70.697998 -23.627049) (xy 70.496938 -23.611225) (xy 70.296654 -23.58752) (xy 70.097455 -23.55597)
			(xy 69.899648 -23.516624) (xy 69.703539 -23.469542) (xy 69.509429 -23.414797) (xy 69.317618 -23.352474)
			(xy 69.128401 -23.282669) (xy 68.942072 -23.205488) (xy 68.758915 -23.121052) (xy 68.579215 -23.02949)
			(xy 68.403249 -22.930944) (xy 68.231286 -22.825566) (xy 68.063594 -22.713517) (xy 67.90043 -22.594971)
			(xy 67.742045 -22.470111) (xy 67.588685 -22.339129) (xy 67.440585 -22.202227) (xy 67.297975 -22.059617)
			(xy 67.161073 -21.911517) (xy 67.030091 -21.758157) (xy 66.905231 -21.599772) (xy 66.786685 -21.436608)
			(xy 66.674636 -21.268916) (xy 66.569258 -21.096953) (xy 66.470712 -20.920987) (xy 66.37915 -20.741287)
			(xy 66.294714 -20.55813) (xy 66.217533 -20.371801) (xy 66.147728 -20.182584) (xy 66.085405 -19.990773)
			(xy 66.03066 -19.796663) (xy 65.983578 -19.600554) (xy 65.944232 -19.402747) (xy 65.912682 -19.203548)
			(xy 65.888977 -19.003264) (xy 65.873153 -18.802204) (xy 65.865235 -18.600677) (xy 65.86474 -18.499836)
			(xy 59.93118 -18.499836) (xy 59.938429 -18.503461) (xy 60.057117 -18.571732) (xy 60.171627 -18.646799)
			(xy 60.281573 -18.728407) (xy 60.386579 -18.816279) (xy 60.48629 -18.910117) (xy 60.580367 -19.009602)
			(xy 60.668491 -19.114397) (xy 60.750363 -19.224145) (xy 60.825705 -19.338476) (xy 60.894261 -19.456999)
			(xy 60.955799 -19.579314) (xy 61.01011 -19.705005) (xy 61.057009 -19.833645) (xy 61.096337 -19.964798)
			(xy 61.127961 -20.098018) (xy 61.151773 -20.232854) (xy 61.167693 -20.368848) (xy 61.175667 -20.505539)
			(xy 61.176154 -20.574) (xy 61.175658 -20.642322) (xy 61.167718 -20.778734) (xy 61.151863 -20.914455)
			(xy 61.128148 -21.049025) (xy 61.096653 -21.181989) (xy 61.057484 -21.312899) (xy 61.010774 -21.44131)
			(xy 60.95668 -21.566791) (xy 60.895386 -21.688916) (xy 60.827098 -21.807272) (xy 60.752047 -21.92146)
			(xy 60.670488 -22.031094) (xy 60.582696 -22.135802) (xy 60.488966 -22.235232) (xy 60.389617 -22.329047)
			(xy 60.284984 -22.41693) (xy 60.230512 -22.458172) (xy 60.225432 -22.461728) (xy 60.21832 -22.470618)
			(xy 60.21197 -22.48281) (xy 60.207828 -22.491969) (xy 60.206348 -22.512) (xy 60.212653 -22.53107)
			(xy 60.22578 -22.546273) (xy 60.234576 -22.551136) (xy 60.24626 -22.556978) (xy 60.259468 -22.55647)
			(xy 60.297314 -22.555708) (xy 60.338428 -22.556184) (xy 60.420306 -22.563772) (xy 60.501134 -22.578882)
			(xy 60.580224 -22.601385) (xy 60.6569 -22.63109) (xy 60.730508 -22.667743) (xy 60.80042 -22.71103)
			(xy 60.86604 -22.760584) (xy 60.926808 -22.815981) (xy 60.982206 -22.876748) (xy 61.031761 -22.942367)
			(xy 61.07505 -23.012278) (xy 61.111703 -23.085886) (xy 61.141409 -23.162561) (xy 61.163914 -23.24165)
			(xy 61.179026 -23.322478) (xy 61.186616 -23.404356) (xy 61.187076 -23.44547) (xy 61.186584 -23.487343)
			(xy 61.178694 -23.570717) (xy 61.163009 -23.652982) (xy 61.139668 -23.73341) (xy 61.108876 -23.811291)
			(xy 61.090302 -23.848822) (xy 61.085222 -23.858728) (xy 61.08446 -23.877016) (xy 61.087508 -23.890224)
			(xy 61.091064 -23.896574) (xy 61.112458 -23.936246) (xy 61.148013 -24.019078) (xy 61.175006 -24.105081)
			(xy 61.193159 -24.193374) (xy 61.202286 -24.28305) (xy 61.202824 -24.32812) (xy 61.202333 -24.369661)
			(xy 61.194564 -24.452379) (xy 61.179113 -24.534013) (xy 61.156116 -24.613849) (xy 61.125773 -24.691192)
			(xy 61.088348 -24.765368) (xy 61.06668 -24.800814) (xy 61.063124 -24.806402) (xy 61.059314 -24.818086)
			(xy 61.058552 -24.831802) (xy 61.061346 -24.845772) (xy 61.064902 -24.852122) (xy 61.085266 -24.891062)
			(xy 61.119102 -24.972166) (xy 61.144782 -25.05621) (xy 61.162057 -25.142375) (xy 61.170758 -25.229823)
			(xy 61.171328 -25.273762) (xy 61.17084 -25.315007) (xy 61.163162 -25.39714) (xy 61.147914 -25.478209)
			(xy 61.125227 -25.557519) (xy 61.095297 -25.634388) (xy 61.05838 -25.708157) (xy 61.036962 -25.743408)
			(xy 61.033152 -25.749504) (xy 61.029342 -25.76322) (xy 61.029342 -25.777444) (xy 61.033152 -25.79116)
			(xy 61.036962 -25.797256) (xy 61.058355 -25.832498) (xy 61.095266 -25.906221) (xy 61.125194 -25.983045)
			(xy 61.147881 -26.062311) (xy 61.163132 -26.143336) (xy 61.170816 -26.225424) (xy 61.171328 -26.266648)
			(xy 61.170852 -26.307742) (xy 61.163266 -26.389579) (xy 61.148163 -26.470367) (xy 61.125672 -26.549418)
			(xy 61.095984 -26.626057) (xy 61.059354 -26.69963) (xy 61.016093 -26.769511) (xy 60.96657 -26.835103)
			(xy 60.911207 -26.895847) (xy 60.850477 -26.951225) (xy 60.784898 -27.000765) (xy 60.715028 -27.044044)
			(xy 60.641464 -27.080693) (xy 60.564832 -27.1104) (xy 60.485787 -27.132911) (xy 60.405003 -27.148034)
			(xy 60.323168 -27.155641) (xy 60.282074 -27.156156) (xy 60.281566 -27.156156) (xy 60.239252 -27.155653)
			(xy 60.155005 -27.147614) (xy 60.071903 -27.131611) (xy 59.990696 -27.107791) (xy 59.912117 -27.076367)
			(xy 59.836877 -27.037623) (xy 59.800998 -27.015186) (xy 59.794881 -27.011495) (xy 59.781212 -27.007362)
			(xy 59.774074 -27.007058) (xy 59.766681 -27.00727) (xy 59.752481 -27.011389) (xy 59.746134 -27.015186)
			(xy 59.71193 -27.036638) (xy 59.640336 -27.073969) (xy 59.565651 -27.104654) (xy 59.488491 -27.128441)
			(xy 59.409492 -27.145132) (xy 59.369452 -27.150314) (xy 59.369198 -27.150314) (xy 59.360059 -27.151814)
			(xy 59.343671 -27.16041) (xy 59.331421 -27.17428) (xy 59.324917 -27.191605) (xy 59.324494 -27.20086)
			(xy 59.324494 -32.85871) (xy 59.32424 -32.879538) (xy 59.323986 -32.889952) (xy 59.327796 -32.899604)
			(xy 59.329828 -32.904472) (xy 59.335595 -32.913303) (xy 59.339226 -32.91713) (xy 59.42711 -33.005014)
			(xy 59.427618 -33.005522) (xy 59.434996 -33.012113) (xy 59.453295 -33.019581) (xy 59.463178 -33.02)
			(xy 73.276206 -33.02) (xy 73.286084 -33.019542) (xy 73.304386 -33.012102) (xy 73.311766 -33.005522)
			(xy 73.31202 -33.005268) (xy 95.50527 -10.811764) (xy 95.511366 -10.804652) (xy 95.511366 -10.804398)
			(xy 95.516168 -10.796753) (xy 95.520573 -10.779256) (xy 95.518636 -10.761318) (xy 95.514922 -10.75309)
			(xy 95.46463 -10.652252) (xy 95.435928 -10.637012) (xy 95.419672 -10.639298) (xy 95.389598 -10.643204)
			(xy 95.329093 -10.647397) (xy 95.298768 -10.64768) (xy 95.252367 -10.647049) (xy 95.160075 -10.637334)
			(xy 95.069293 -10.618075) (xy 94.981006 -10.589481) (xy 94.938342 -10.571226) (xy 94.928436 -10.566908)
			(xy 94.9071 -10.566908) (xy 94.897194 -10.571226) (xy 94.854538 -10.589504) (xy 94.766254 -10.618117)
			(xy 94.675468 -10.637376) (xy 94.583171 -10.647072) (xy 94.536768 -10.64768) (xy 94.490367 -10.647049)
			(xy 94.398075 -10.637334) (xy 94.307293 -10.618075) (xy 94.219006 -10.589481) (xy 94.176342 -10.571226)
			(xy 94.166436 -10.566908) (xy 94.1451 -10.566908) (xy 94.135194 -10.571226) (xy 94.092538 -10.589504)
			(xy 94.004254 -10.618117) (xy 93.913468 -10.637376) (xy 93.821171 -10.647072) (xy 93.774768 -10.64768)
			(xy 93.732408 -10.647175) (xy 93.64807 -10.639119) (xy 93.564881 -10.623082) (xy 93.483593 -10.599211)
			(xy 93.404941 -10.567722) (xy 93.329639 -10.528898) (xy 93.258369 -10.483093) (xy 93.191774 -10.430721)
			(xy 93.13046 -10.372255) (xy 93.074981 -10.308227) (xy 93.025839 -10.239214) (xy 92.983479 -10.165843)
			(xy 92.948286 -10.088778) (xy 92.920577 -10.008717) (xy 92.900603 -9.926384) (xy 92.888547 -9.842525)
			(xy 92.884515 -9.7579) (xy 92.888547 -9.673275) (xy 92.900603 -9.589416) (xy 92.920577 -9.507083)
			(xy 92.948286 -9.427022) (xy 92.983479 -9.349957) (xy 93.025839 -9.276586) (xy 93.074981 -9.207573)
			(xy 93.13046 -9.143545) (xy 93.191774 -9.085079) (xy 93.258369 -9.032707) (xy 93.329639 -8.986902)
			(xy 93.404941 -8.948078) (xy 93.483593 -8.916589) (xy 93.564881 -8.892718) (xy 93.64807 -8.876681)
			(xy 93.732408 -8.868625) (xy 93.774768 -8.868156) (xy 93.821169 -8.868783) (xy 93.913464 -8.878492)
			(xy 94.004248 -8.897746) (xy 94.092538 -8.926336) (xy 94.135194 -8.94461) (xy 94.1451 -8.948928)
			(xy 94.166436 -8.948928) (xy 94.176342 -8.94461) (xy 94.218998 -8.926333) (xy 94.307283 -8.897723)
			(xy 94.398068 -8.878466) (xy 94.490366 -8.868773) (xy 94.536768 -8.868156) (xy 94.583169 -8.868783)
			(xy 94.675464 -8.878492) (xy 94.766248 -8.897746) (xy 94.854538 -8.926336) (xy 94.897194 -8.94461)
			(xy 94.9071 -8.948928) (xy 94.928436 -8.948928) (xy 94.938342 -8.94461) (xy 94.980998 -8.926333)
			(xy 95.069283 -8.897723) (xy 95.160068 -8.878466) (xy 95.252366 -8.868773) (xy 95.298768 -8.868156)
			(xy 95.345169 -8.868783) (xy 95.437464 -8.878492) (xy 95.528248 -8.897746) (xy 95.616538 -8.926336)
			(xy 95.659194 -8.94461) (xy 95.6691 -8.948928) (xy 95.690436 -8.948928) (xy 95.700342 -8.94461) (xy 95.742998 -8.926333)
			(xy 95.831283 -8.897723) (xy 95.922068 -8.878466) (xy 96.014366 -8.868773) (xy 96.060768 -8.868156)
			(xy 96.102891 -8.868647) (xy 96.18676 -8.87661) (xy 96.2695 -8.892466) (xy 96.350371 -8.916074) (xy 96.428647 -8.947222)
			(xy 96.503627 -8.985631) (xy 96.574641 -9.030958) (xy 96.64105 -9.082796) (xy 96.702261 -9.14068)
			(xy 96.757725 -9.204092) (xy 96.806945 -9.272464) (xy 96.82861 -9.308592) (xy 96.834706 -9.319006)
			(xy 96.85401 -9.331706) (xy 96.945704 -9.34339) (xy 96.957359 -9.344326) (xy 96.979453 -9.336762)
			(xy 96.988122 -9.328912) (xy 97.930462 -8.386826) (xy 97.954341 -8.363667) (xy 98.007102 -8.323157)
			(xy 98.064703 -8.289883) (xy 98.126155 -8.264417) (xy 98.190407 -8.247194) (xy 98.256358 -8.238509)
			(xy 98.289618 -8.237982) (xy 218.346274 -8.237982) (xy 218.351354 -8.237728) (xy 218.363305 -8.23584)
			(xy 218.383577 -8.222699) (xy 218.390216 -8.212582) (xy 218.392502 -8.208518) (xy 218.43746 -8.110982)
			(xy 218.433396 -8.081772) (xy 218.423744 -8.070342) (xy 218.395034 -8.03583) (xy 218.343936 -7.962011)
			(xy 218.300532 -7.883421) (xy 218.265266 -7.800859) (xy 218.238495 -7.715165) (xy 218.220491 -7.62721)
			(xy 218.211438 -7.537889) (xy 218.210892 -7.493) (xy 218.211367 -7.451898) (xy 218.218952 -7.370043)
			(xy 218.234057 -7.289238) (xy 218.256553 -7.210171) (xy 218.286249 -7.133517) (xy 218.322891 -7.05993)
			(xy 218.366166 -6.990038) (xy 218.415706 -6.924437) (xy 218.471087 -6.863687) (xy 218.531837 -6.808306)
			(xy 218.597438 -6.758766) (xy 218.66733 -6.715491) (xy 218.740917 -6.678849) (xy 218.817571 -6.649153)
			(xy 218.896638 -6.626657) (xy 218.977443 -6.611552) (xy 219.059298 -6.603967) (xy 219.1004 -6.603492)
			(xy 219.100908 -6.603492) (xy 219.141399 -6.603949) (xy 219.222044 -6.611334) (xy 219.301683 -6.626024)
			(xy 219.379655 -6.647896) (xy 219.417646 -6.661912) (xy 219.428314 -6.665976) (xy 219.450412 -6.664452)
			(xy 219.481146 -6.647434) (xy 219.490036 -6.638798) (xy 219.493338 -6.633464) (xy 219.515549 -6.599523)
			(xy 219.565254 -6.535414) (xy 219.620586 -6.476094) (xy 219.681086 -6.422055) (xy 219.746253 -6.373745)
			(xy 219.815545 -6.331565) (xy 219.888387 -6.295865) (xy 219.964176 -6.266941) (xy 220.042282 -6.245033)
			(xy 220.122057 -6.230323) (xy 220.20284 -6.222933) (xy 220.2434 -6.222492) (xy 220.286328 -6.223007)
			(xy 220.371784 -6.231276) (xy 220.456046 -6.247736) (xy 220.538331 -6.272235) (xy 220.617875 -6.304545)
			(xy 220.693937 -6.344365) (xy 220.765811 -6.391325) (xy 220.832828 -6.444989) (xy 220.894365 -6.504858)
			(xy 220.94985 -6.570375) (xy 220.998767 -6.640932) (xy 221.020132 -6.678168) (xy 221.025212 -6.687058)
			(xy 221.041468 -6.699758) (xy 221.094808 -6.713728) (xy 221.107762 -6.715506) (xy 221.154498 -6.715506)
			(xy 221.167198 -6.71195) (xy 221.173294 -6.708394) (xy 221.207441 -6.688873) (xy 221.278545 -6.655229)
			(xy 221.352343 -6.627996) (xy 221.428257 -6.607388) (xy 221.505695 -6.593564) (xy 221.584051 -6.586633)
			(xy 221.623382 -6.58622) (xy 221.66449 -6.586694) (xy 221.746354 -6.594277) (xy 221.82717 -6.609379)
			(xy 221.906249 -6.631873) (xy 221.982915 -6.661566) (xy 222.056515 -6.698205) (xy 222.12642 -6.741477)
			(xy 222.192036 -6.791013) (xy 222.252803 -6.846392) (xy 222.308201 -6.90714) (xy 222.357759 -6.97274)
			(xy 222.401054 -7.042632) (xy 222.437717 -7.11622) (xy 222.467435 -7.192876) (xy 222.489954 -7.271947)
			(xy 222.505083 -7.352758) (xy 222.512693 -7.434621) (xy 222.513144 -7.475728) (xy 222.512696 -7.515721)
			(xy 222.505494 -7.595384) (xy 222.491169 -7.674078) (xy 222.469837 -7.751168) (xy 222.44167 -7.826031)
			(xy 222.406894 -7.898063) (xy 222.365792 -7.966682) (xy 222.318696 -8.031334) (xy 222.292672 -8.061706)
			(xy 222.286576 -8.068564) (xy 222.278956 -8.08863) (xy 222.275871 -8.098088) (xy 222.276392 -8.117956)
			(xy 222.279972 -8.127238) (xy 222.31604 -8.207756) (xy 222.319245 -8.214398) (xy 222.328787 -8.225636)
			(xy 222.334836 -8.229854) (xy 222.347536 -8.237982) (xy 255.191006 -8.237982) (xy 255.199111 -8.23768)
			(xy 255.214513 -8.232621) (xy 255.221232 -8.228076) (xy 255.247597 -8.209158) (xy 255.304212 -8.177448)
			(xy 255.364403 -8.153203) (xy 255.427191 -8.136817) (xy 255.491555 -8.128557) (xy 255.556445 -8.128557)
			(xy 255.620809 -8.136817) (xy 255.683597 -8.153203) (xy 255.743788 -8.177448) (xy 255.800403 -8.209158)
			(xy 255.826768 -8.228076) (xy 255.833464 -8.232666) (xy 255.84888 -8.237727) (xy 255.856994 -8.237982)
			(xy 256.715006 -8.237982) (xy 256.723111 -8.23768) (xy 256.738513 -8.232621) (xy 256.745232 -8.228076)
			(xy 256.771593 -8.20915) (xy 256.828205 -8.177424) (xy 256.888395 -8.153166) (xy 256.951186 -8.136772)
			(xy 257.015552 -8.128507) (xy 257.048 -8.128) (xy 323.142356 -8.128) (xy 323.175617 -8.128519) (xy 323.24157 -8.137201)
			(xy 323.305825 -8.154422) (xy 323.36728 -8.179887) (xy 323.424882 -8.21316) (xy 323.477647 -8.253671)
			(xy 323.501512 -8.276844) (xy 324.971156 -9.746488) (xy 324.994315 -9.770367) (xy 324.997412 -9.7744)
			(xy 331.181015 -9.7744) (xy 331.185045 -9.689804) (xy 331.197098 -9.605974) (xy 331.217064 -9.523669)
			(xy 331.244764 -9.443634) (xy 331.279945 -9.366595) (xy 331.32229 -9.293249) (xy 331.371415 -9.22426)
			(xy 331.426876 -9.160253) (xy 331.488169 -9.101807) (xy 331.554741 -9.049453) (xy 331.625987 -9.003663)
			(xy 331.701263 -8.964853) (xy 331.779888 -8.933373) (xy 331.861149 -8.90951) (xy 331.94431 -8.893479)
			(xy 332.028618 -8.885425) (xy 332.070964 -8.88492) (xy 332.071472 -8.88492) (xy 332.117804 -8.885536)
			(xy 332.209961 -8.895204) (xy 332.300615 -8.914397) (xy 332.388784 -8.942906) (xy 332.43139 -8.96112)
			(xy 332.441332 -8.964926) (xy 332.462596 -8.964926) (xy 332.472538 -8.96112) (xy 332.515206 -8.942889)
			(xy 332.603496 -8.914341) (xy 332.694279 -8.895144) (xy 332.786568 -8.885507) (xy 332.832964 -8.88492)
			(xy 332.879359 -8.885513) (xy 332.971647 -8.895155) (xy 333.062431 -8.914348) (xy 333.150725 -8.942883)
			(xy 333.19339 -8.96112) (xy 333.203332 -8.964926) (xy 333.224596 -8.964926) (xy 333.234538 -8.96112)
			(xy 333.277206 -8.942889) (xy 333.365496 -8.914341) (xy 333.456279 -8.895144) (xy 333.548568 -8.885507)
			(xy 333.594964 -8.88492) (xy 333.641359 -8.885513) (xy 333.733647 -8.895155) (xy 333.824431 -8.914348)
			(xy 333.912725 -8.942883) (xy 333.95539 -8.96112) (xy 333.965332 -8.964926) (xy 333.986596 -8.964926)
			(xy 333.996538 -8.96112) (xy 334.039146 -8.942912) (xy 334.127312 -8.91439) (xy 334.217965 -8.895193)
			(xy 334.310124 -8.88553) (xy 334.356456 -8.88492) (xy 334.356964 -8.88492) (xy 334.399316 -8.88535)
			(xy 334.483636 -8.893399) (xy 334.566809 -8.909426) (xy 334.648082 -8.933287) (xy 334.726719 -8.964766)
			(xy 334.802007 -9.003577) (xy 334.873265 -9.049369) (xy 334.939848 -9.101728) (xy 335.001152 -9.160178)
			(xy 335.056622 -9.224192) (xy 335.105756 -9.293188) (xy 335.148108 -9.366543) (xy 335.183296 -9.443591)
			(xy 335.211001 -9.523636) (xy 335.230971 -9.605952) (xy 335.243026 -9.689793) (xy 335.247056 -9.7744)
			(xy 335.243026 -9.859007) (xy 335.24018 -9.8788) (xy 341.83444 -9.8788) (xy 341.838471 -9.794173)
			(xy 341.850529 -9.710312) (xy 341.870504 -9.627978) (xy 341.898215 -9.547915) (xy 341.933411 -9.470848)
			(xy 341.975773 -9.397477) (xy 342.024919 -9.328464) (xy 342.080402 -9.264436) (xy 342.14172 -9.205972)
			(xy 342.208318 -9.153602) (xy 342.279593 -9.107799) (xy 342.354899 -9.068979) (xy 342.433554 -9.037493)
			(xy 342.514846 -9.013627) (xy 342.598039 -8.997596) (xy 342.682378 -8.989547) (xy 342.72474 -8.98906)
			(xy 342.771142 -8.989674) (xy 342.86344 -8.999368) (xy 342.954225 -9.018625) (xy 343.04251 -9.047237)
			(xy 343.085166 -9.065514) (xy 343.095108 -9.06932) (xy 343.116372 -9.06932) (xy 343.126314 -9.065514)
			(xy 343.168969 -9.047237) (xy 343.257259 -9.018648) (xy 343.348044 -8.999395) (xy 343.440339 -8.989687)
			(xy 343.48674 -8.98906) (xy 343.533142 -8.989674) (xy 343.62544 -8.999368) (xy 343.716225 -9.018625)
			(xy 343.80451 -9.047237) (xy 343.847166 -9.065514) (xy 343.857108 -9.06932) (xy 343.878372 -9.06932)
			(xy 343.888314 -9.065514) (xy 343.930969 -9.047237) (xy 344.019259 -9.018648) (xy 344.110044 -8.999395)
			(xy 344.202339 -8.989687) (xy 344.24874 -8.98906) (xy 344.295142 -8.989674) (xy 344.38744 -8.999368)
			(xy 344.478225 -9.018625) (xy 344.56651 -9.047237) (xy 344.609166 -9.065514) (xy 344.619108 -9.06932)
			(xy 344.640372 -9.06932) (xy 344.650314 -9.065514) (xy 344.692969 -9.047237) (xy 344.781259 -9.018648)
			(xy 344.872044 -8.999395) (xy 344.964339 -8.989687) (xy 345.01074 -8.98906) (xy 345.0531 -8.989522)
			(xy 345.137437 -8.997579) (xy 345.220626 -9.013615) (xy 345.301915 -9.037487) (xy 345.380566 -9.068977)
			(xy 345.455867 -9.107801) (xy 345.527138 -9.153606) (xy 345.593731 -9.205979) (xy 345.655045 -9.264445)
			(xy 345.710525 -9.328474) (xy 345.759666 -9.397486) (xy 345.802026 -9.470857) (xy 345.837219 -9.547922)
			(xy 345.864928 -9.627984) (xy 345.884901 -9.710317) (xy 345.896957 -9.794175) (xy 345.900989 -9.8788)
			(xy 345.896957 -9.963425) (xy 345.884901 -10.047283) (xy 345.864928 -10.129616) (xy 345.837219 -10.209678)
			(xy 345.804101 -10.2822) (xy 358.852392 -10.2822) (xy 358.856424 -10.197568) (xy 358.868482 -10.113703)
			(xy 358.888458 -10.031364) (xy 358.91617 -9.951297) (xy 358.951368 -9.874226) (xy 358.993733 -9.800851)
			(xy 359.042881 -9.731835) (xy 359.098367 -9.667803) (xy 359.159689 -9.609336) (xy 359.22629 -9.556962)
			(xy 359.297569 -9.511157) (xy 359.372879 -9.472335) (xy 359.451539 -9.440848) (xy 359.532835 -9.41698)
			(xy 359.616032 -9.400949) (xy 359.700376 -9.392899) (xy 359.74274 -9.392412) (xy 359.789143 -9.393022)
			(xy 359.881441 -9.402716) (xy 359.972226 -9.421975) (xy 360.060511 -9.450588) (xy 360.103166 -9.468866)
			(xy 360.113108 -9.472672) (xy 360.134372 -9.472672) (xy 360.144314 -9.468866) (xy 360.186968 -9.450586)
			(xy 360.275259 -9.421999) (xy 360.366044 -9.402747) (xy 360.458338 -9.393039) (xy 360.50474 -9.392412)
			(xy 360.551143 -9.393022) (xy 360.643441 -9.402716) (xy 360.734226 -9.421975) (xy 360.822511 -9.450588)
			(xy 360.865166 -9.468866) (xy 360.875108 -9.472672) (xy 360.896372 -9.472672) (xy 360.906314 -9.468866)
			(xy 360.948968 -9.450586) (xy 361.037259 -9.421999) (xy 361.128044 -9.402747) (xy 361.220338 -9.393039)
			(xy 361.26674 -9.392412) (xy 361.313143 -9.393022) (xy 361.405441 -9.402716) (xy 361.496226 -9.421975)
			(xy 361.584511 -9.450588) (xy 361.627166 -9.468866) (xy 361.637108 -9.472672) (xy 361.658372 -9.472672)
			(xy 361.668314 -9.468866) (xy 361.710968 -9.450586) (xy 361.799259 -9.421999) (xy 361.890044 -9.402747)
			(xy 361.982338 -9.393039) (xy 362.02874 -9.392412) (xy 362.071098 -9.39297) (xy 362.15543 -9.401026)
			(xy 362.238615 -9.417062) (xy 362.319899 -9.440932) (xy 362.398546 -9.472421) (xy 362.473843 -9.511242)
			(xy 362.54511 -9.557046) (xy 362.6117 -9.609415) (xy 362.673011 -9.667878) (xy 362.728487 -9.731903)
			(xy 362.777626 -9.800912) (xy 362.819983 -9.874279) (xy 362.855174 -9.95134) (xy 362.882882 -10.031397)
			(xy 362.902854 -10.113726) (xy 362.91491 -10.19758) (xy 362.918941 -10.2822) (xy 362.91491 -10.36682)
			(xy 362.902854 -10.450674) (xy 362.882882 -10.533003) (xy 362.855174 -10.61306) (xy 362.819983 -10.690121)
			(xy 362.777626 -10.763488) (xy 362.728487 -10.832497) (xy 362.673011 -10.896522) (xy 362.6117 -10.954985)
			(xy 362.54511 -11.007354) (xy 362.473843 -11.053158) (xy 362.398546 -11.091979) (xy 362.319899 -11.123468)
			(xy 362.238615 -11.147338) (xy 362.15543 -11.163374) (xy 362.071098 -11.17143) (xy 362.02874 -11.171936)
			(xy 361.982337 -11.171329) (xy 361.890039 -11.161633) (xy 361.799254 -11.142374) (xy 361.710969 -11.11376)
			(xy 361.668314 -11.095482) (xy 361.658372 -11.091676) (xy 361.637108 -11.091676) (xy 361.627166 -11.095482)
			(xy 361.5845 -11.113732) (xy 361.496214 -11.142328) (xy 361.405433 -11.161589) (xy 361.313141 -11.171305)
			(xy 361.26674 -11.171936) (xy 361.220337 -11.171329) (xy 361.128039 -11.161633) (xy 361.037254 -11.142374)
			(xy 360.948969 -11.11376) (xy 360.906314 -11.095482) (xy 360.896372 -11.091676) (xy 360.875108 -11.091676)
			(xy 360.865166 -11.095482) (xy 360.8225 -11.113732) (xy 360.734214 -11.142328) (xy 360.643433 -11.161589)
			(xy 360.551141 -11.171305) (xy 360.50474 -11.171936) (xy 360.458337 -11.171329) (xy 360.366039 -11.161633)
			(xy 360.275254 -11.142374) (xy 360.186969 -11.11376) (xy 360.144314 -11.095482) (xy 360.134372 -11.091676)
			(xy 360.113108 -11.091676) (xy 360.103166 -11.095482) (xy 360.0605 -11.113732) (xy 359.972214 -11.142328)
			(xy 359.881433 -11.161589) (xy 359.789141 -11.171305) (xy 359.74274 -11.171936) (xy 359.700376 -11.171501)
			(xy 359.616032 -11.163451) (xy 359.532835 -11.14742) (xy 359.451539 -11.123552) (xy 359.372879 -11.092065)
			(xy 359.297569 -11.053243) (xy 359.22629 -11.007438) (xy 359.159689 -10.955064) (xy 359.098367 -10.896597)
			(xy 359.042881 -10.832565) (xy 358.993733 -10.763549) (xy 358.951368 -10.690174) (xy 358.91617 -10.613103)
			(xy 358.888458 -10.533036) (xy 358.868482 -10.450697) (xy 358.856424 -10.366832) (xy 358.852392 -10.2822)
			(xy 345.804101 -10.2822) (xy 345.802026 -10.286743) (xy 345.759666 -10.360114) (xy 345.710525 -10.429126)
			(xy 345.655045 -10.493155) (xy 345.593731 -10.551621) (xy 345.527138 -10.603994) (xy 345.455867 -10.649799)
			(xy 345.380566 -10.688623) (xy 345.301915 -10.720113) (xy 345.220626 -10.743985) (xy 345.137437 -10.760021)
			(xy 345.0531 -10.768078) (xy 345.01074 -10.768584) (xy 344.964337 -10.767982) (xy 344.872039 -10.758285)
			(xy 344.781254 -10.739024) (xy 344.692969 -10.710409) (xy 344.650314 -10.69213) (xy 344.640372 -10.688324)
			(xy 344.619108 -10.688324) (xy 344.609166 -10.69213) (xy 344.566501 -10.710383) (xy 344.478214 -10.738978)
			(xy 344.387433 -10.758237) (xy 344.295141 -10.767953) (xy 344.24874 -10.768584) (xy 344.202337 -10.767982)
			(xy 344.110039 -10.758285) (xy 344.019254 -10.739024) (xy 343.930969 -10.710409) (xy 343.888314 -10.69213)
			(xy 343.878372 -10.688324) (xy 343.857108 -10.688324) (xy 343.847166 -10.69213) (xy 343.804501 -10.710383)
			(xy 343.716214 -10.738978) (xy 343.625433 -10.758237) (xy 343.533141 -10.767953) (xy 343.48674 -10.768584)
			(xy 343.440337 -10.767982) (xy 343.348039 -10.758285) (xy 343.257254 -10.739024) (xy 343.168969 -10.710409)
			(xy 343.126314 -10.69213) (xy 343.116372 -10.688324) (xy 343.095108 -10.688324) (xy 343.085166 -10.69213)
			(xy 343.042501 -10.710383) (xy 342.954214 -10.738978) (xy 342.863433 -10.758237) (xy 342.771141 -10.767953)
			(xy 342.72474 -10.768584) (xy 342.682378 -10.768053) (xy 342.598039 -10.760004) (xy 342.514846 -10.743973)
			(xy 342.433554 -10.720107) (xy 342.354899 -10.688621) (xy 342.279593 -10.649801) (xy 342.208318 -10.603998)
			(xy 342.14172 -10.551628) (xy 342.080402 -10.493164) (xy 342.024919 -10.429136) (xy 341.975773 -10.360123)
			(xy 341.933411 -10.286752) (xy 341.898215 -10.209685) (xy 341.870504 -10.129622) (xy 341.850529 -10.047288)
			(xy 341.838471 -9.963427) (xy 341.83444 -9.8788) (xy 335.24018 -9.8788) (xy 335.230971 -9.942848)
			(xy 335.211001 -10.025164) (xy 335.183296 -10.105209) (xy 335.148108 -10.182257) (xy 335.105756 -10.255612)
			(xy 335.056622 -10.324608) (xy 335.001152 -10.388622) (xy 334.939848 -10.447072) (xy 334.873265 -10.499431)
			(xy 334.802007 -10.545223) (xy 334.726719 -10.584034) (xy 334.648082 -10.615513) (xy 334.566809 -10.639374)
			(xy 334.483636 -10.655401) (xy 334.399316 -10.66345) (xy 334.356964 -10.663936) (xy 334.356456 -10.663936)
			(xy 334.310125 -10.663305) (xy 334.217968 -10.653641) (xy 334.127314 -10.634452) (xy 334.039144 -10.605948)
			(xy 333.996538 -10.587736) (xy 333.986596 -10.58393) (xy 333.965332 -10.58393) (xy 333.95539 -10.587736)
			(xy 333.912733 -10.605994) (xy 333.824439 -10.634535) (xy 333.733652 -10.653724) (xy 333.641361 -10.663353)
			(xy 333.594964 -10.663936) (xy 333.548569 -10.663328) (xy 333.456282 -10.65369) (xy 333.365498 -10.634501)
			(xy 333.277204 -10.60597) (xy 333.234538 -10.587736) (xy 333.224596 -10.58393) (xy 333.203332 -10.58393)
			(xy 333.19339 -10.587736) (xy 333.150733 -10.605994) (xy 333.062439 -10.634535) (xy 332.971652 -10.653724)
			(xy 332.879361 -10.663353) (xy 332.832964 -10.663936) (xy 332.786569 -10.663328) (xy 332.694282 -10.65369)
			(xy 332.603498 -10.634501) (xy 332.515204 -10.60597) (xy 332.472538 -10.587736) (xy 332.462596 -10.58393)
			(xy 332.441332 -10.58393) (xy 332.43139 -10.587736) (xy 332.388793 -10.605972) (xy 332.300623 -10.634485)
			(xy 332.209966 -10.653674) (xy 332.117805 -10.66333) (xy 332.071472 -10.663936) (xy 332.070964 -10.663936)
			(xy 332.028618 -10.663375) (xy 331.94431 -10.655321) (xy 331.861149 -10.63929) (xy 331.779888 -10.615427)
			(xy 331.701263 -10.583947) (xy 331.625987 -10.545137) (xy 331.554741 -10.499347) (xy 331.488169 -10.446993)
			(xy 331.426876 -10.388547) (xy 331.371415 -10.32454) (xy 331.32229 -10.255551) (xy 331.279945 -10.182205)
			(xy 331.244764 -10.105166) (xy 331.217064 -10.025131) (xy 331.197098 -9.942826) (xy 331.185045 -9.858996)
			(xy 331.181015 -9.7744) (xy 324.997412 -9.7744) (xy 325.034828 -9.823129) (xy 325.068104 -9.880729)
			(xy 325.093575 -9.942181) (xy 325.110804 -10.006432) (xy 325.119497 -10.072383) (xy 325.12 -10.105644)
			(xy 325.12 -15.0368) (xy 325.120488 -15.046808) (xy 325.128148 -15.065299) (xy 325.142301 -15.079452)
			(xy 325.160792 -15.087112) (xy 325.1708 -15.0876) (xy 353.8982 -15.0876) (xy 353.93146 -15.088121)
			(xy 353.99741 -15.096809) (xy 354.061661 -15.114034) (xy 354.123112 -15.139503) (xy 354.180711 -15.172779)
			(xy 354.233471 -15.213292) (xy 354.257356 -15.236444) (xy 357.521002 -18.50009) (xy 363.864652 -18.50009)
			(xy 363.864652 -13.5001) (xy 363.865147 -13.399259) (xy 363.873065 -13.197732) (xy 363.888889 -12.996672)
			(xy 363.912594 -12.796388) (xy 363.944144 -12.597189) (xy 363.98349 -12.399382) (xy 364.030572 -12.203273)
			(xy 364.085317 -12.009163) (xy 364.14764 -11.817352) (xy 364.217445 -11.628135) (xy 364.294626 -11.441806)
			(xy 364.379062 -11.258649) (xy 364.470624 -11.078949) (xy 364.56917 -10.902983) (xy 364.674548 -10.73102)
			(xy 364.786597 -10.563328) (xy 364.905143 -10.400164) (xy 365.030003 -10.241779) (xy 365.160985 -10.088419)
			(xy 365.297887 -9.940319) (xy 365.440497 -9.797709) (xy 365.588597 -9.660807) (xy 365.741957 -9.529825)
			(xy 365.900342 -9.404965) (xy 366.063506 -9.286419) (xy 366.231198 -9.17437) (xy 366.403161 -9.068992)
			(xy 366.579127 -8.970446) (xy 366.758827 -8.878884) (xy 366.941984 -8.794448) (xy 367.128313 -8.717267)
			(xy 367.31753 -8.647462) (xy 367.509341 -8.585139) (xy 367.703451 -8.530394) (xy 367.89956 -8.483312)
			(xy 368.097367 -8.443966) (xy 368.296566 -8.412416) (xy 368.49685 -8.388711) (xy 368.69791 -8.372887)
			(xy 368.899437 -8.364969) (xy 369.101119 -8.364969) (xy 369.302646 -8.372887) (xy 369.503706 -8.388711)
			(xy 369.70399 -8.412416) (xy 369.903189 -8.443966) (xy 370.100996 -8.483312) (xy 370.297105 -8.530394)
			(xy 370.491215 -8.585139) (xy 370.683026 -8.647462) (xy 370.872243 -8.717267) (xy 371.058572 -8.794448)
			(xy 371.241729 -8.878884) (xy 371.421429 -8.970446) (xy 371.597395 -9.068992) (xy 371.769358 -9.17437)
			(xy 371.93705 -9.286419) (xy 372.100214 -9.404965) (xy 372.258599 -9.529825) (xy 372.411959 -9.660807)
			(xy 372.560059 -9.797709) (xy 372.702669 -9.940319) (xy 372.839571 -10.088419) (xy 372.970553 -10.241779)
			(xy 373.095413 -10.400164) (xy 373.213959 -10.563328) (xy 373.326008 -10.73102) (xy 373.431386 -10.902983)
			(xy 373.529932 -11.078949) (xy 373.621494 -11.258649) (xy 373.70593 -11.441806) (xy 373.783111 -11.628135)
			(xy 373.852916 -11.817352) (xy 373.915239 -12.009163) (xy 373.969984 -12.203273) (xy 374.017066 -12.399382)
			(xy 374.056412 -12.597189) (xy 374.087962 -12.796388) (xy 374.111667 -12.996672) (xy 374.127491 -13.197732)
			(xy 374.135409 -13.399259) (xy 374.135904 -13.5001) (xy 374.135904 -16.891) (xy 377.627872 -16.891)
			(xy 377.631902 -16.806397) (xy 377.643956 -16.72256) (xy 377.663925 -16.640248) (xy 377.691628 -16.560207)
			(xy 377.726813 -16.483162) (xy 377.769163 -16.409811) (xy 377.818294 -16.340817) (xy 377.87376 -16.276806)
			(xy 377.935061 -16.218357) (xy 378.001639 -16.166) (xy 378.072893 -16.120209) (xy 378.148177 -16.081398)
			(xy 378.226809 -16.04992) (xy 378.308078 -16.026058) (xy 378.391247 -16.01003) (xy 378.475562 -16.00198)
			(xy 378.517912 -16.001492) (xy 378.518166 -16.001492) (xy 378.559653 -16.001969) (xy 378.642261 -16.009745)
			(xy 378.723788 -16.025175) (xy 378.803524 -16.048126) (xy 378.880778 -16.078398) (xy 378.95488 -16.11573)
			(xy 379.025185 -16.159796) (xy 379.058424 -16.184626) (xy 379.067623 -16.190969) (xy 379.089412 -16.1958)
			(xy 379.111201 -16.190969) (xy 379.1204 -16.184626) (xy 379.156273 -16.157882) (xy 379.232425 -16.110894)
			(xy 379.31291 -16.071788) (xy 379.396914 -16.040961) (xy 379.483589 -16.018722) (xy 379.572059 -16.005298)
			(xy 379.616716 -16.002508) (xy 379.628004 -16.001328) (xy 379.647972 -15.9906) (xy 379.661437 -15.972365)
			(xy 379.664214 -15.96136) (xy 379.67239 -15.921222) (xy 379.695154 -15.842531) (xy 379.725057 -15.766265)
			(xy 379.761848 -15.693073) (xy 379.805212 -15.623575) (xy 379.854785 -15.558358) (xy 379.910144 -15.497976)
			(xy 379.970821 -15.442941) (xy 380.036302 -15.393719) (xy 380.106032 -15.350726) (xy 380.17942 -15.314328)
			(xy 380.255844 -15.284833) (xy 380.334656 -15.262491) (xy 380.41519 -15.24749) (xy 380.496761 -15.239959)
			(xy 380.53772 -15.239492) (xy 380.580622 -15.240048) (xy 380.666028 -15.24831) (xy 380.750242 -15.264755)
			(xy 380.832481 -15.289231) (xy 380.911983 -15.32151) (xy 380.988007 -15.361293) (xy 381.059849 -15.408209)
			(xy 381.126841 -15.461824) (xy 381.18836 -15.521638) (xy 381.243836 -15.587097) (xy 381.292752 -15.657593)
			(xy 381.334655 -15.73247) (xy 381.369155 -15.811033) (xy 381.383032 -15.851632) (xy 381.383032 -15.851886)
			(xy 381.386373 -15.860675) (xy 381.398326 -15.875169) (xy 381.414693 -15.884394) (xy 381.423926 -15.886176)
			(xy 381.528574 -15.901162) (xy 381.55499 -15.889732) (xy 381.563118 -15.877794) (xy 381.587956 -15.842673)
			(xy 381.643438 -15.776928) (xy 381.705006 -15.716844) (xy 381.772084 -15.662982) (xy 381.844047 -15.615844)
			(xy 381.920222 -15.575871) (xy 381.9999 -15.543435) (xy 382.082336 -15.518839) (xy 382.166761 -15.502313)
			(xy 382.252387 -15.494012) (xy 382.2954 -15.493492) (xy 382.337748 -15.493996) (xy 382.422062 -15.502047)
			(xy 382.505228 -15.518076) (xy 382.586495 -15.541937) (xy 382.665125 -15.573416) (xy 382.740406 -15.612227)
			(xy 382.811658 -15.658017) (xy 382.878234 -15.710373) (xy 382.939532 -15.768821) (xy 382.994997 -15.832831)
			(xy 383.044126 -15.901823) (xy 383.086475 -15.975173) (xy 383.121659 -16.052216) (xy 383.149361 -16.132255)
			(xy 383.169329 -16.214564) (xy 383.181382 -16.298399) (xy 383.185413 -16.383) (xy 383.181382 -16.467601)
			(xy 383.169329 -16.551436) (xy 383.149361 -16.633745) (xy 383.121659 -16.713784) (xy 383.086475 -16.790827)
			(xy 383.044126 -16.864177) (xy 382.994997 -16.933169) (xy 382.939532 -16.997179) (xy 382.878234 -17.055627)
			(xy 382.872214 -17.060361) (xy 397.255742 -17.060361) (xy 397.255742 -16.975639) (xy 397.263795 -16.891302)
			(xy 397.279829 -16.808112) (xy 397.303697 -16.726822) (xy 397.335185 -16.64817) (xy 397.374007 -16.572867)
			(xy 397.41981 -16.501595) (xy 397.472181 -16.434999) (xy 397.530646 -16.373684) (xy 397.594674 -16.318203)
			(xy 397.663686 -16.26906) (xy 397.737056 -16.2267) (xy 397.814121 -16.191505) (xy 397.894183 -16.163796)
			(xy 397.976516 -16.143822) (xy 398.060375 -16.131765) (xy 398.145 -16.127734) (xy 398.229625 -16.131765)
			(xy 398.313484 -16.143822) (xy 398.395817 -16.163796) (xy 398.475879 -16.191505) (xy 398.552944 -16.2267)
			(xy 398.626314 -16.26906) (xy 398.695326 -16.318203) (xy 398.759354 -16.373684) (xy 398.817819 -16.434999)
			(xy 398.87019 -16.501595) (xy 398.915993 -16.572867) (xy 398.954815 -16.64817) (xy 398.986303 -16.726822)
			(xy 399.010171 -16.808112) (xy 399.026205 -16.891302) (xy 399.034258 -16.975639) (xy 399.034762 -17.018)
			(xy 399.034258 -17.060361) (xy 399.026205 -17.144698) (xy 399.010171 -17.227888) (xy 398.986303 -17.309178)
			(xy 398.954815 -17.38783) (xy 398.915993 -17.463133) (xy 398.87019 -17.534405) (xy 398.817819 -17.601001)
			(xy 398.768237 -17.653) (xy 406.043892 -17.653) (xy 406.043892 -17.652492) (xy 406.044411 -17.608728)
			(xy 406.052986 -17.521622) (xy 406.070082 -17.435781) (xy 406.095533 -17.352035) (xy 406.129093 -17.271197)
			(xy 406.149302 -17.232376) (xy 406.154629 -17.221023) (xy 406.154629 -17.195977) (xy 406.149302 -17.184624)
			(xy 406.129087 -17.14575) (xy 406.095517 -17.064809) (xy 406.070061 -16.980962) (xy 406.052966 -16.895019)
			(xy 406.044396 -16.807813) (xy 406.043892 -16.764) (xy 406.044388 -16.720185) (xy 406.052933 -16.632974)
			(xy 406.07002 -16.547027) (xy 406.095481 -16.463179) (xy 406.129071 -16.382243) (xy 406.149302 -16.343376)
			(xy 406.154629 -16.332023) (xy 406.154629 -16.306977) (xy 406.149302 -16.295624) (xy 406.129108 -16.256796)
			(xy 406.095568 -16.175953) (xy 406.070123 -16.092208) (xy 406.053018 -16.006371) (xy 406.044419 -15.91927)
			(xy 406.043892 -15.875508) (xy 406.043892 -15.875) (xy 406.044367 -15.833898) (xy 406.051952 -15.752043)
			(xy 406.067057 -15.671238) (xy 406.089553 -15.592171) (xy 406.119249 -15.515517) (xy 406.155891 -15.44193)
			(xy 406.199166 -15.372038) (xy 406.248706 -15.306437) (xy 406.304087 -15.245687) (xy 406.364837 -15.190306)
			(xy 406.430438 -15.140766) (xy 406.50033 -15.097491) (xy 406.573917 -15.060849) (xy 406.650571 -15.031153)
			(xy 406.729638 -15.008657) (xy 406.810443 -14.993552) (xy 406.892298 -14.985967) (xy 406.9334 -14.985492)
			(xy 406.975715 -14.985995) (xy 407.059963 -14.994026) (xy 407.143066 -15.010024) (xy 407.224275 -15.033845)
			(xy 407.302852 -15.065272) (xy 407.378089 -15.104023) (xy 407.413968 -15.126462) (xy 407.422357 -15.131345)
			(xy 407.4414 -15.135016) (xy 407.460443 -15.131345) (xy 407.468832 -15.126462) (xy 407.504706 -15.104016)
			(xy 407.579947 -15.065273) (xy 407.658526 -15.033849) (xy 407.739735 -15.01003) (xy 407.822838 -14.99403)
			(xy 407.907085 -14.985994) (xy 407.9494 -14.985492) (xy 407.949908 -14.985492) (xy 407.99624 -14.986098)
			(xy 408.088398 -14.995769) (xy 408.179052 -15.014965) (xy 408.267221 -15.043477) (xy 408.309826 -15.061692)
			(xy 408.319768 -15.065498) (xy 408.341032 -15.065498) (xy 408.350974 -15.061692) (xy 408.393577 -15.04347)
			(xy 408.481744 -15.014952) (xy 408.5724 -14.99576) (xy 408.66456 -14.9861) (xy 408.710892 -14.985492)
			(xy 408.7114 -14.985492) (xy 408.752502 -14.985967) (xy 408.834357 -14.993552) (xy 408.915162 -15.008657)
			(xy 408.994229 -15.031153) (xy 409.070883 -15.060849) (xy 409.14447 -15.097491) (xy 409.214362 -15.140766)
			(xy 409.279963 -15.190306) (xy 409.340713 -15.245687) (xy 409.396094 -15.306437) (xy 409.445634 -15.372038)
			(xy 409.488909 -15.44193) (xy 409.525551 -15.515517) (xy 409.555247 -15.592171) (xy 409.577743 -15.671238)
			(xy 409.592848 -15.752043) (xy 409.600433 -15.833898) (xy 409.600908 -15.875) (xy 409.600908 -15.875508)
			(xy 409.600389 -15.919272) (xy 409.591814 -16.006378) (xy 409.574718 -16.092219) (xy 409.549267 -16.175965)
			(xy 409.515707 -16.256803) (xy 409.495498 -16.295624) (xy 409.490171 -16.306977) (xy 409.490171 -16.332023)
			(xy 409.495498 -16.343376) (xy 409.515713 -16.38225) (xy 409.549283 -16.463191) (xy 409.574739 -16.547038)
			(xy 409.591834 -16.632981) (xy 409.600404 -16.720187) (xy 409.600908 -16.764) (xy 409.600412 -16.807815)
			(xy 409.591867 -16.895026) (xy 409.57478 -16.980973) (xy 409.549319 -17.064821) (xy 409.515729 -17.145757)
			(xy 409.495498 -17.184624) (xy 409.490171 -17.195977) (xy 409.490171 -17.221023) (xy 409.495498 -17.232376)
			(xy 409.515692 -17.271204) (xy 409.549232 -17.352047) (xy 409.574677 -17.435792) (xy 409.591782 -17.521629)
			(xy 409.600381 -17.60873) (xy 409.600908 -17.652492) (xy 409.600908 -17.653) (xy 409.600433 -17.694102)
			(xy 409.592848 -17.775957) (xy 409.577743 -17.856762) (xy 409.555247 -17.935829) (xy 409.525551 -18.012483)
			(xy 409.488909 -18.08607) (xy 409.445634 -18.155962) (xy 409.396094 -18.221563) (xy 409.340713 -18.282313)
			(xy 409.279963 -18.337694) (xy 409.214362 -18.387234) (xy 409.14447 -18.430509) (xy 409.070883 -18.467151)
			(xy 408.994229 -18.496847) (xy 408.915162 -18.519343) (xy 408.834357 -18.534448) (xy 408.752502 -18.542033)
			(xy 408.7114 -18.542508) (xy 408.710892 -18.542508) (xy 408.66456 -18.541902) (xy 408.572402 -18.532231)
			(xy 408.481748 -18.513035) (xy 408.393579 -18.484523) (xy 408.350974 -18.466308) (xy 408.341032 -18.462502)
			(xy 408.319768 -18.462502) (xy 408.309826 -18.466308) (xy 408.267223 -18.48453) (xy 408.179056 -18.513048)
			(xy 408.0884 -18.53224) (xy 407.99624 -18.5419) (xy 407.949908 -18.542508) (xy 407.9494 -18.542508)
			(xy 407.907085 -18.542005) (xy 407.822837 -18.533974) (xy 407.739734 -18.517976) (xy 407.658525 -18.494155)
			(xy 407.579948 -18.462728) (xy 407.504711 -18.423977) (xy 407.468832 -18.401538) (xy 407.460443 -18.396655)
			(xy 407.4414 -18.392984) (xy 407.422357 -18.396655) (xy 407.413968 -18.401538) (xy 407.378094 -18.423984)
			(xy 407.302853 -18.462727) (xy 407.224274 -18.494151) (xy 407.143065 -18.51797) (xy 407.059962 -18.53397)
			(xy 406.975715 -18.542006) (xy 406.9334 -18.542508) (xy 406.892298 -18.542033) (xy 406.810443 -18.534448)
			(xy 406.729638 -18.519343) (xy 406.650571 -18.496847) (xy 406.573917 -18.467151) (xy 406.50033 -18.430509)
			(xy 406.430438 -18.387234) (xy 406.364837 -18.337694) (xy 406.304087 -18.282313) (xy 406.248706 -18.221563)
			(xy 406.199166 -18.155962) (xy 406.155891 -18.08607) (xy 406.119249 -18.012483) (xy 406.089553 -17.935829)
			(xy 406.067057 -17.856762) (xy 406.051952 -17.775957) (xy 406.044367 -17.694102) (xy 406.043892 -17.653)
			(xy 398.768237 -17.653) (xy 398.759354 -17.662316) (xy 398.695326 -17.717797) (xy 398.626314 -17.76694)
			(xy 398.552944 -17.8093) (xy 398.475879 -17.844495) (xy 398.395817 -17.872204) (xy 398.313484 -17.892178)
			(xy 398.229625 -17.904235) (xy 398.145 -17.908267) (xy 398.060375 -17.904235) (xy 397.976516 -17.892178)
			(xy 397.894183 -17.872204) (xy 397.814121 -17.844495) (xy 397.737056 -17.8093) (xy 397.663686 -17.76694)
			(xy 397.594674 -17.717797) (xy 397.530646 -17.662316) (xy 397.472181 -17.601001) (xy 397.41981 -17.534405)
			(xy 397.374007 -17.463133) (xy 397.335185 -17.38783) (xy 397.303697 -17.309178) (xy 397.279829 -17.227888)
			(xy 397.263795 -17.144698) (xy 397.255742 -17.060361) (xy 382.872214 -17.060361) (xy 382.811658 -17.107983)
			(xy 382.740406 -17.153773) (xy 382.665125 -17.192584) (xy 382.586495 -17.224063) (xy 382.505228 -17.247924)
			(xy 382.422062 -17.263953) (xy 382.337748 -17.272004) (xy 382.2954 -17.272508) (xy 382.252496 -17.272024)
			(xy 382.167088 -17.263755) (xy 382.082873 -17.247302) (xy 382.000632 -17.222819) (xy 381.92113 -17.190533)
			(xy 381.845105 -17.150744) (xy 381.773264 -17.103821) (xy 381.706273 -17.050201) (xy 381.644754 -16.990381)
			(xy 381.58928 -16.924917) (xy 381.540365 -16.854417) (xy 381.498463 -16.779536) (xy 381.463964 -16.700969)
			(xy 381.450088 -16.660368) (xy 381.450088 -16.660114) (xy 381.446734 -16.651332) (xy 381.434786 -16.636837)
			(xy 381.418425 -16.627609) (xy 381.409194 -16.625824) (xy 381.304546 -16.610838) (xy 381.27813 -16.622268)
			(xy 381.270002 -16.634206) (xy 381.24643 -16.667515) (xy 381.194121 -16.73015) (xy 381.136296 -16.787733)
			(xy 381.073442 -16.83978) (xy 381.006087 -16.885854) (xy 380.934796 -16.925567) (xy 380.860169 -16.958586)
			(xy 380.782832 -16.984634) (xy 380.703435 -17.003492) (xy 380.622645 -17.015001) (xy 380.581916 -17.017492)
			(xy 380.570631 -17.018695) (xy 380.550663 -17.029411) (xy 380.537196 -17.047638) (xy 380.534418 -17.05864)
			(xy 380.526307 -17.098792) (xy 380.50354 -17.177487) (xy 380.473634 -17.253755) (xy 380.43684 -17.326949)
			(xy 380.393471 -17.39645) (xy 380.343894 -17.461667) (xy 380.28853 -17.52205) (xy 380.227848 -17.577085)
			(xy 380.162362 -17.626306) (xy 380.092626 -17.669297) (xy 380.019233 -17.705692) (xy 379.942804 -17.735184)
			(xy 379.863986 -17.757523) (xy 379.783449 -17.772518) (xy 379.701873 -17.780044) (xy 379.660912 -17.780508)
			(xy 379.660658 -17.780508) (xy 379.619172 -17.780017) (xy 379.536564 -17.772244) (xy 379.455037 -17.756816)
			(xy 379.375301 -17.733868) (xy 379.298047 -17.703597) (xy 379.223945 -17.666268) (xy 379.15364 -17.622203)
			(xy 379.1204 -17.597374) (xy 379.111201 -17.591031) (xy 379.089412 -17.5862) (xy 379.067623 -17.591031)
			(xy 379.058424 -17.597374) (xy 379.025187 -17.622209) (xy 378.954892 -17.666295) (xy 378.880794 -17.703639)
			(xy 378.803539 -17.733915) (xy 378.723799 -17.756859) (xy 378.642267 -17.772273) (xy 378.559654 -17.780021)
			(xy 378.518166 -17.780508) (xy 378.517912 -17.780508) (xy 378.475562 -17.78002) (xy 378.391247 -17.77197)
			(xy 378.308078 -17.755942) (xy 378.226809 -17.73208) (xy 378.148177 -17.700602) (xy 378.072893 -17.661791)
			(xy 378.001639 -17.616) (xy 377.935061 -17.563643) (xy 377.87376 -17.505194) (xy 377.818294 -17.441183)
			(xy 377.769163 -17.372189) (xy 377.726813 -17.298838) (xy 377.691628 -17.221793) (xy 377.663925 -17.141752)
			(xy 377.643956 -17.05944) (xy 377.631902 -16.975603) (xy 377.627872 -16.891) (xy 374.135904 -16.891)
			(xy 374.135904 -18.50009) (xy 374.135409 -18.600931) (xy 374.127491 -18.802458) (xy 374.118004 -18.923)
			(xy 379.913872 -18.923) (xy 379.917902 -18.838397) (xy 379.929956 -18.75456) (xy 379.949925 -18.672248)
			(xy 379.977628 -18.592207) (xy 380.012813 -18.515162) (xy 380.055163 -18.441811) (xy 380.104294 -18.372817)
			(xy 380.15976 -18.308806) (xy 380.221061 -18.250357) (xy 380.287639 -18.198) (xy 380.358893 -18.152209)
			(xy 380.434177 -18.113398) (xy 380.512809 -18.08192) (xy 380.594078 -18.058058) (xy 380.677247 -18.04203)
			(xy 380.761562 -18.03398) (xy 380.803912 -18.033492) (xy 380.80442 -18.033492) (xy 380.845563 -18.033937)
			(xy 380.927497 -18.041543) (xy 381.008377 -18.056687) (xy 381.087512 -18.079241) (xy 381.164224 -18.109011)
			(xy 381.237857 -18.145742) (xy 381.307781 -18.18912) (xy 381.340868 -18.213578) (xy 381.350079 -18.219811)
			(xy 381.371782 -18.22453) (xy 381.393451 -18.219658) (xy 381.40259 -18.213324) (xy 381.435984 -18.188103)
			(xy 381.506701 -18.143345) (xy 381.581309 -18.105426) (xy 381.659148 -18.074681) (xy 381.73953 -18.051381)
			(xy 381.821745 -18.035733) (xy 381.905067 -18.027875) (xy 381.946912 -18.027396) (xy 381.98927 -18.027984)
			(xy 382.073603 -18.036038) (xy 382.156788 -18.052072) (xy 382.238073 -18.07594) (xy 382.316721 -18.107427)
			(xy 382.392019 -18.146247) (xy 382.463287 -18.192049) (xy 382.529878 -18.244418) (xy 382.59119 -18.302879)
			(xy 382.646667 -18.366904) (xy 382.695807 -18.435912) (xy 382.738165 -18.509279) (xy 382.773357 -18.58634)
			(xy 382.801065 -18.666397) (xy 382.821037 -18.748725) (xy 382.833094 -18.83258) (xy 382.837125 -18.9172)
			(xy 382.833094 -19.00182) (xy 382.821037 -19.085675) (xy 382.801065 -19.168003) (xy 382.773357 -19.24806)
			(xy 382.738165 -19.325121) (xy 382.695807 -19.398488) (xy 382.646667 -19.467496) (xy 382.59119 -19.531521)
			(xy 382.529878 -19.589982) (xy 382.463287 -19.642351) (xy 382.392019 -19.688153) (xy 382.316721 -19.726973)
			(xy 382.238073 -19.75846) (xy 382.156788 -19.782328) (xy 382.073603 -19.798362) (xy 381.98927 -19.806416)
			(xy 381.946912 -19.80692) (xy 381.905729 -19.806447) (xy 381.823717 -19.79882) (xy 381.74276 -19.78365)
			(xy 381.663551 -19.761065) (xy 381.586767 -19.731259) (xy 381.513065 -19.694486) (xy 381.443075 -19.651063)
			(xy 381.409956 -19.62658) (xy 381.400784 -19.620283) (xy 381.379057 -19.615589) (xy 381.357375 -19.620488)
			(xy 381.348234 -19.626834) (xy 381.31487 -19.651993) (xy 381.244237 -19.696654) (xy 381.16973 -19.7345)
			(xy 381.092004 -19.765194) (xy 381.011742 -19.788469) (xy 380.929653 -19.804118) (xy 380.846458 -19.812005)
			(xy 380.804674 -19.812508) (xy 380.803912 -19.812508) (xy 380.761562 -19.81202) (xy 380.677247 -19.80397)
			(xy 380.594078 -19.787942) (xy 380.512809 -19.76408) (xy 380.434177 -19.732602) (xy 380.358893 -19.693791)
			(xy 380.287639 -19.648) (xy 380.221061 -19.595643) (xy 380.15976 -19.537194) (xy 380.104294 -19.473183)
			(xy 380.055163 -19.404189) (xy 380.012813 -19.330838) (xy 379.977628 -19.253793) (xy 379.949925 -19.173752)
			(xy 379.929956 -19.09144) (xy 379.917902 -19.007603) (xy 379.913872 -18.923) (xy 374.118004 -18.923)
			(xy 374.111667 -19.003518) (xy 374.087962 -19.203802) (xy 374.056412 -19.403001) (xy 374.017066 -19.600808)
			(xy 373.969984 -19.796917) (xy 373.915239 -19.991027) (xy 373.852916 -20.182838) (xy 373.783111 -20.372055)
			(xy 373.70593 -20.558384) (xy 373.621494 -20.741541) (xy 373.529932 -20.921241) (xy 373.431386 -21.097207)
			(xy 373.326008 -21.26917) (xy 373.281353 -21.336) (xy 377.570492 -21.336) (xy 377.570492 -21.335492)
			(xy 377.571011 -21.291728) (xy 377.579586 -21.204622) (xy 377.596682 -21.118781) (xy 377.622133 -21.035035)
			(xy 377.655693 -20.954197) (xy 377.675902 -20.915376) (xy 377.681229 -20.904023) (xy 377.681229 -20.878977)
			(xy 377.675902 -20.867624) (xy 377.655708 -20.828796) (xy 377.622168 -20.747953) (xy 377.596723 -20.664208)
			(xy 377.579618 -20.578371) (xy 377.571019 -20.49127) (xy 377.570492 -20.447508) (xy 377.570492 -20.447)
			(xy 377.570967 -20.405898) (xy 377.578552 -20.324043) (xy 377.593657 -20.243238) (xy 377.616153 -20.164171)
			(xy 377.645849 -20.087517) (xy 377.682491 -20.01393) (xy 377.725766 -19.944038) (xy 377.775306 -19.878437)
			(xy 377.830687 -19.817687) (xy 377.891437 -19.762306) (xy 377.957038 -19.712766) (xy 378.02693 -19.669491)
			(xy 378.100517 -19.632849) (xy 378.177171 -19.603153) (xy 378.256238 -19.580657) (xy 378.337043 -19.565552)
			(xy 378.418898 -19.557967) (xy 378.46 -19.557492) (xy 378.50339 -19.55802) (xy 378.589756 -19.566478)
			(xy 378.674889 -19.583304) (xy 378.757979 -19.608337) (xy 378.838238 -19.641341) (xy 378.914902 -19.682001)
			(xy 378.987244 -19.729931) (xy 379.054576 -19.784676) (xy 379.116259 -19.845717) (xy 379.171707 -19.912472)
			(xy 379.220392 -19.984308) (xy 379.232923 -20.007349) (xy 386.042397 -20.007349) (xy 386.042397 -19.870651)
			(xy 386.050345 -19.734184) (xy 386.066215 -19.598411) (xy 386.089952 -19.463789) (xy 386.121477 -19.330776)
			(xy 386.160683 -19.199821) (xy 386.207436 -19.071367) (xy 386.261579 -18.945848) (xy 386.322929 -18.823691)
			(xy 386.391278 -18.705307) (xy 386.466395 -18.591097) (xy 386.548026 -18.481448) (xy 386.635893 -18.376732)
			(xy 386.729701 -18.277301) (xy 386.829132 -18.183493) (xy 386.933848 -18.095626) (xy 387.043497 -18.013995)
			(xy 387.157707 -17.938878) (xy 387.276091 -17.870529) (xy 387.398248 -17.809179) (xy 387.523767 -17.755036)
			(xy 387.652221 -17.708283) (xy 387.783176 -17.669077) (xy 387.916189 -17.637552) (xy 388.050811 -17.613815)
			(xy 388.186584 -17.597945) (xy 388.323051 -17.589997) (xy 388.459749 -17.589997) (xy 388.596216 -17.597945)
			(xy 388.731989 -17.613815) (xy 388.866611 -17.637552) (xy 388.999624 -17.669077) (xy 389.130579 -17.708283)
			(xy 389.259033 -17.755036) (xy 389.384552 -17.809179) (xy 389.506709 -17.870529) (xy 389.625093 -17.938878)
			(xy 389.739303 -18.013995) (xy 389.848952 -18.095626) (xy 389.953668 -18.183493) (xy 390.053099 -18.277301)
			(xy 390.146907 -18.376732) (xy 390.234774 -18.481448) (xy 390.316405 -18.591097) (xy 390.391522 -18.705307)
			(xy 390.459871 -18.823691) (xy 390.521221 -18.945848) (xy 390.575364 -19.071367) (xy 390.622117 -19.199821)
			(xy 390.661323 -19.330776) (xy 390.692848 -19.463789) (xy 390.716585 -19.598411) (xy 390.732455 -19.734184)
			(xy 390.740403 -19.870651) (xy 390.7409 -19.939) (xy 390.740403 -20.007349) (xy 390.732455 -20.143816)
			(xy 390.716585 -20.279589) (xy 390.692848 -20.414211) (xy 390.661323 -20.547224) (xy 390.622117 -20.678179)
			(xy 390.575364 -20.806633) (xy 390.521221 -20.932152) (xy 390.459871 -21.054309) (xy 390.391522 -21.172693)
			(xy 390.316405 -21.286903) (xy 390.234774 -21.396552) (xy 390.146907 -21.501268) (xy 390.053099 -21.600699)
			(xy 389.953668 -21.694507) (xy 389.848952 -21.782374) (xy 389.739303 -21.864005) (xy 389.625093 -21.939122)
			(xy 389.506709 -22.007471) (xy 389.384552 -22.068821) (xy 389.259033 -22.122964) (xy 389.130579 -22.169717)
			(xy 388.999624 -22.208923) (xy 388.866611 -22.240448) (xy 388.731989 -22.264185) (xy 388.596216 -22.280055)
			(xy 388.459749 -22.288003) (xy 388.323051 -22.288003) (xy 388.186584 -22.280055) (xy 388.050811 -22.264185)
			(xy 387.916189 -22.240448) (xy 387.783176 -22.208923) (xy 387.652221 -22.169717) (xy 387.523767 -22.122964)
			(xy 387.398248 -22.068821) (xy 387.276091 -22.007471) (xy 387.157707 -21.939122) (xy 387.043497 -21.864005)
			(xy 386.933848 -21.782374) (xy 386.829132 -21.694507) (xy 386.729701 -21.600699) (xy 386.635893 -21.501268)
			(xy 386.548026 -21.396552) (xy 386.466395 -21.286903) (xy 386.391278 -21.172693) (xy 386.322929 -21.054309)
			(xy 386.261579 -20.932152) (xy 386.207436 -20.806633) (xy 386.160683 -20.678179) (xy 386.121477 -20.547224)
			(xy 386.089952 -20.414211) (xy 386.066215 -20.279589) (xy 386.050345 -20.143816) (xy 386.042397 -20.007349)
			(xy 379.232923 -20.007349) (xy 379.261853 -20.060542) (xy 379.295695 -20.140451) (xy 379.321597 -20.223275)
			(xy 379.330966 -20.265644) (xy 379.332998 -20.275804) (xy 379.344682 -20.292822) (xy 379.415294 -20.337272)
			(xy 379.424035 -20.342185) (xy 379.44377 -20.345593) (xy 379.453648 -20.343876) (xy 379.45441 -20.343876)
			(xy 379.505273 -20.332478) (xy 379.608793 -20.320252) (xy 379.660912 -20.319492) (xy 379.70326 -20.319996)
			(xy 379.787573 -20.328048) (xy 379.870738 -20.344078) (xy 379.952004 -20.367941) (xy 380.030632 -20.39942)
			(xy 380.105913 -20.438231) (xy 380.177164 -20.484021) (xy 380.243739 -20.536378) (xy 380.305036 -20.594825)
			(xy 380.3605 -20.658835) (xy 380.409629 -20.727827) (xy 380.451976 -20.801176) (xy 380.48716 -20.878218)
			(xy 380.514861 -20.958257) (xy 380.534829 -21.040565) (xy 380.546883 -21.1244) (xy 380.550913 -21.209)
			(xy 380.546883 -21.2936) (xy 380.534829 -21.377435) (xy 380.514861 -21.459743) (xy 380.48716 -21.539782)
			(xy 380.451976 -21.616824) (xy 380.409629 -21.690173) (xy 380.3605 -21.759165) (xy 380.305036 -21.823175)
			(xy 380.243739 -21.881622) (xy 380.177164 -21.933979) (xy 380.105913 -21.979769) (xy 380.030632 -22.01858)
			(xy 379.952004 -22.050059) (xy 379.870738 -22.073922) (xy 379.787573 -22.089952) (xy 379.70326 -22.098004)
			(xy 379.660912 -22.098508) (xy 379.617052 -22.097989) (xy 379.529758 -22.089349) (xy 379.443737 -22.072163)
			(xy 379.359825 -22.046596) (xy 379.278836 -22.012898) (xy 379.201555 -21.971394) (xy 379.16485 -21.947378)
			(xy 379.157237 -21.942758) (xy 379.139973 -21.938457) (xy 379.12228 -21.940315) (xy 379.106286 -21.948109)
			(xy 379.099826 -21.954236) (xy 379.06843 -21.985919) (xy 379.00032 -22.04352) (xy 378.926788 -22.094017)
			(xy 378.848572 -22.136902) (xy 378.766457 -22.171745) (xy 378.681268 -22.198196) (xy 378.593859 -22.215989)
			(xy 378.505108 -22.224946) (xy 378.460508 -22.225508) (xy 378.46 -22.225508) (xy 378.418898 -22.225033)
			(xy 378.337043 -22.217448) (xy 378.256238 -22.202343) (xy 378.177171 -22.179847) (xy 378.100517 -22.150151)
			(xy 378.02693 -22.113509) (xy 377.957038 -22.070234) (xy 377.891437 -22.020694) (xy 377.830687 -21.965313)
			(xy 377.775306 -21.904563) (xy 377.725766 -21.838962) (xy 377.682491 -21.76907) (xy 377.645849 -21.695483)
			(xy 377.616153 -21.618829) (xy 377.593657 -21.539762) (xy 377.578552 -21.458957) (xy 377.570967 -21.377102)
			(xy 377.570492 -21.336) (xy 373.281353 -21.336) (xy 373.213959 -21.436862) (xy 373.095413 -21.600026)
			(xy 372.970553 -21.758411) (xy 372.839571 -21.911771) (xy 372.702669 -22.059871) (xy 372.560059 -22.202481)
			(xy 372.411959 -22.339383) (xy 372.258599 -22.470365) (xy 372.100214 -22.595225) (xy 372.085384 -22.606)
			(xy 406.043892 -22.606) (xy 406.043892 -22.605492) (xy 406.044411 -22.561728) (xy 406.052986 -22.474622)
			(xy 406.070082 -22.388781) (xy 406.095533 -22.305035) (xy 406.129093 -22.224197) (xy 406.149302 -22.185376)
			(xy 406.154629 -22.174023) (xy 406.154629 -22.148977) (xy 406.149302 -22.137624) (xy 406.129087 -22.09875)
			(xy 406.095517 -22.017809) (xy 406.070061 -21.933962) (xy 406.052966 -21.848019) (xy 406.044396 -21.760813)
			(xy 406.043892 -21.717) (xy 406.044388 -21.673185) (xy 406.052933 -21.585974) (xy 406.07002 -21.500027)
			(xy 406.095481 -21.416179) (xy 406.129071 -21.335243) (xy 406.149302 -21.296376) (xy 406.154629 -21.285023)
			(xy 406.154629 -21.259977) (xy 406.149302 -21.248624) (xy 406.129108 -21.209796) (xy 406.095568 -21.128953)
			(xy 406.070123 -21.045208) (xy 406.053018 -20.959371) (xy 406.044419 -20.87227) (xy 406.043892 -20.828508)
			(xy 406.043892 -20.828) (xy 406.044367 -20.786898) (xy 406.051952 -20.705043) (xy 406.067057 -20.624238)
			(xy 406.089553 -20.545171) (xy 406.119249 -20.468517) (xy 406.155891 -20.39493) (xy 406.199166 -20.325038)
			(xy 406.248706 -20.259437) (xy 406.304087 -20.198687) (xy 406.364837 -20.143306) (xy 406.430438 -20.093766)
			(xy 406.50033 -20.050491) (xy 406.573917 -20.013849) (xy 406.650571 -19.984153) (xy 406.729638 -19.961657)
			(xy 406.810443 -19.946552) (xy 406.892298 -19.938967) (xy 406.9334 -19.938492) (xy 406.975715 -19.938995)
			(xy 407.059963 -19.947026) (xy 407.143066 -19.963024) (xy 407.224275 -19.986845) (xy 407.302852 -20.018272)
			(xy 407.378089 -20.057023) (xy 407.413968 -20.079462) (xy 407.422357 -20.084345) (xy 407.4414 -20.088016)
			(xy 407.460443 -20.084345) (xy 407.468832 -20.079462) (xy 407.504706 -20.057016) (xy 407.579947 -20.018273)
			(xy 407.658526 -19.986849) (xy 407.739735 -19.96303) (xy 407.822838 -19.94703) (xy 407.907085 -19.938994)
			(xy 407.9494 -19.938492) (xy 407.949908 -19.938492) (xy 407.99624 -19.939098) (xy 408.088398 -19.948769)
			(xy 408.179052 -19.967965) (xy 408.267221 -19.996477) (xy 408.309826 -20.014692) (xy 408.319768 -20.018498)
			(xy 408.341032 -20.018498) (xy 408.350974 -20.014692) (xy 408.393577 -19.99647) (xy 408.481744 -19.967952)
			(xy 408.5724 -19.94876) (xy 408.66456 -19.9391) (xy 408.710892 -19.938492) (xy 408.7114 -19.938492)
			(xy 408.751279 -19.938936) (xy 408.830716 -19.946066) (xy 408.909197 -19.96028) (xy 408.98609 -19.981462)
			(xy 409.060778 -20.009442) (xy 409.132661 -20.043996) (xy 409.201163 -20.084846) (xy 409.265732 -20.131664)
			(xy 409.325851 -20.184075) (xy 409.353766 -20.212558) (xy 409.35402 -20.212812) (xy 409.361001 -20.219412)
			(xy 409.378474 -20.22735) (xy 409.397645 -20.228249) (xy 409.406852 -20.225512) (xy 409.494228 -20.19554)
			(xy 409.503263 -20.19203) (xy 409.517944 -20.179394) (xy 409.526881 -20.162209) (xy 409.528264 -20.152614)
			(xy 409.533654 -20.106286) (xy 409.552889 -20.015018) (xy 409.581556 -19.926259) (xy 409.599892 -19.883374)
			(xy 409.603698 -19.873432) (xy 409.603698 -19.852168) (xy 409.599892 -19.842226) (xy 409.58167 -19.799623)
			(xy 409.553152 -19.711456) (xy 409.53396 -19.6208) (xy 409.5243 -19.52864) (xy 409.523692 -19.482308)
			(xy 409.523692 -19.4818) (xy 409.524167 -19.440698) (xy 409.531752 -19.358843) (xy 409.546857 -19.278038)
			(xy 409.569353 -19.198971) (xy 409.599049 -19.122317) (xy 409.635691 -19.04873) (xy 409.678966 -18.978838)
			(xy 409.728506 -18.913237) (xy 409.783887 -18.852487) (xy 409.844637 -18.797106) (xy 409.910238 -18.747566)
			(xy 409.98013 -18.704291) (xy 410.053717 -18.667649) (xy 410.130371 -18.637953) (xy 410.209438 -18.615457)
			(xy 410.290243 -18.600352) (xy 410.372098 -18.592767) (xy 410.4132 -18.592292) (xy 410.413708 -18.592292)
			(xy 410.46004 -18.592898) (xy 410.552198 -18.602569) (xy 410.642852 -18.621765) (xy 410.731021 -18.650277)
			(xy 410.773626 -18.668492) (xy 410.783568 -18.672298) (xy 410.804832 -18.672298) (xy 410.814774 -18.668492)
			(xy 410.857377 -18.65027) (xy 410.945544 -18.621752) (xy 411.0362 -18.60256) (xy 411.12836 -18.5929)
			(xy 411.174692 -18.592292) (xy 411.1752 -18.592292) (xy 411.216302 -18.592767) (xy 411.298157 -18.600352)
			(xy 411.378962 -18.615457) (xy 411.458029 -18.637953) (xy 411.534683 -18.667649) (xy 411.60827 -18.704291)
			(xy 411.678162 -18.747566) (xy 411.743763 -18.797106) (xy 411.804513 -18.852487) (xy 411.859894 -18.913237)
			(xy 411.909434 -18.978838) (xy 411.952709 -19.04873) (xy 411.989351 -19.122317) (xy 412.019047 -19.198971)
			(xy 412.041543 -19.278038) (xy 412.056648 -19.358843) (xy 412.064233 -19.440698) (xy 412.064708 -19.4818)
			(xy 412.064708 -19.482308) (xy 412.064102 -19.52864) (xy 412.054431 -19.620798) (xy 412.035235 -19.711452)
			(xy 412.006723 -19.799621) (xy 411.988508 -19.842226) (xy 411.984702 -19.852168) (xy 411.984702 -19.873432)
			(xy 411.988508 -19.883374) (xy 412.006753 -19.926036) (xy 412.035297 -20.014329) (xy 412.05449 -20.105114)
			(xy 412.064123 -20.197404) (xy 412.064708 -20.2438) (xy 412.064125 -20.290196) (xy 412.05448 -20.382484)
			(xy 412.035284 -20.473268) (xy 412.006746 -20.561561) (xy 411.988508 -20.604226) (xy 411.984702 -20.614168)
			(xy 411.984702 -20.635432) (xy 411.988508 -20.645374) (xy 412.00673 -20.687977) (xy 412.035248 -20.776144)
			(xy 412.05444 -20.8668) (xy 412.0641 -20.95896) (xy 412.064708 -21.005292) (xy 412.064708 -21.0058)
			(xy 412.064233 -21.046902) (xy 412.056648 -21.128757) (xy 412.055892 -21.1328) (xy 417.651692 -21.1328)
			(xy 417.651692 -21.132292) (xy 417.652298 -21.08596) (xy 417.661969 -20.993802) (xy 417.681165 -20.903148)
			(xy 417.709677 -20.814979) (xy 417.727892 -20.772374) (xy 417.731698 -20.762432) (xy 417.731698 -20.741168)
			(xy 417.727892 -20.731226) (xy 417.709647 -20.688564) (xy 417.681103 -20.600271) (xy 417.66191 -20.509486)
			(xy 417.652277 -20.417196) (xy 417.651692 -20.3708) (xy 417.652275 -20.324404) (xy 417.66192 -20.232116)
			(xy 417.681116 -20.141332) (xy 417.709654 -20.053039) (xy 417.727892 -20.010374) (xy 417.731698 -20.000432)
			(xy 417.731698 -19.979168) (xy 417.727892 -19.969226) (xy 417.70967 -19.926623) (xy 417.681152 -19.838456)
			(xy 417.66196 -19.7478) (xy 417.6523 -19.65564) (xy 417.651692 -19.609308) (xy 417.651692 -19.6088)
			(xy 417.652196 -19.566452) (xy 417.660247 -19.482138) (xy 417.676276 -19.398972) (xy 417.700137 -19.317705)
			(xy 417.731616 -19.239075) (xy 417.770427 -19.163794) (xy 417.816217 -19.092542) (xy 417.868573 -19.025966)
			(xy 417.927021 -18.964668) (xy 417.991031 -18.909203) (xy 418.060023 -18.860074) (xy 418.133373 -18.817725)
			(xy 418.210416 -18.782541) (xy 418.290455 -18.754839) (xy 418.372764 -18.734871) (xy 418.456599 -18.722818)
			(xy 418.5412 -18.718788) (xy 418.625801 -18.722818) (xy 418.709636 -18.734871) (xy 418.791945 -18.754839)
			(xy 418.871984 -18.782541) (xy 418.949027 -18.817725) (xy 419.022377 -18.860074) (xy 419.091369 -18.909203)
			(xy 419.155379 -18.964668) (xy 419.213827 -19.025966) (xy 419.266183 -19.092542) (xy 419.311973 -19.163794)
			(xy 419.350784 -19.239075) (xy 419.382263 -19.317705) (xy 419.406124 -19.398972) (xy 419.415728 -19.4488)
			(xy 428.877968 -19.4488) (xy 428.881998 -19.364197) (xy 428.894052 -19.28036) (xy 428.91402 -19.198049)
			(xy 428.941722 -19.118008) (xy 428.976908 -19.040964) (xy 429.019257 -18.967612) (xy 429.068387 -18.898618)
			(xy 429.123853 -18.834607) (xy 429.185153 -18.776158) (xy 429.25173 -18.723801) (xy 429.322984 -18.678009)
			(xy 429.398267 -18.639198) (xy 429.476899 -18.607719) (xy 429.558167 -18.583856) (xy 429.641335 -18.567827)
			(xy 429.725651 -18.559776) (xy 429.768 -18.559272) (xy 429.768254 -18.559272) (xy 429.810241 -18.559752)
			(xy 429.893839 -18.567693) (xy 429.976318 -18.583469) (xy 430.056944 -18.606941) (xy 430.135003 -18.6379)
			(xy 430.172622 -18.656554) (xy 430.184121 -18.661717) (xy 430.209296 -18.661314) (xy 430.220628 -18.655792)
			(xy 430.260629 -18.63396) (xy 430.3442 -18.59761) (xy 430.431051 -18.570003) (xy 430.520272 -18.551428)
			(xy 430.610925 -18.542081) (xy 430.656492 -18.541492) (xy 430.657 -18.541492) (xy 430.699348 -18.541996)
			(xy 430.783662 -18.550047) (xy 430.866828 -18.566076) (xy 430.948095 -18.589937) (xy 431.026725 -18.621416)
			(xy 431.102006 -18.660227) (xy 431.173258 -18.706017) (xy 431.239834 -18.758373) (xy 431.301132 -18.816821)
			(xy 431.356597 -18.880831) (xy 431.405726 -18.949823) (xy 431.448075 -19.023173) (xy 431.483259 -19.100216)
			(xy 431.510961 -19.180255) (xy 431.530929 -19.262564) (xy 431.542982 -19.346399) (xy 431.547013 -19.431)
			(xy 431.542982 -19.515601) (xy 431.530929 -19.599436) (xy 431.510961 -19.681745) (xy 431.483259 -19.761784)
			(xy 431.448075 -19.838827) (xy 431.405726 -19.912177) (xy 431.356597 -19.981169) (xy 431.301132 -20.045179)
			(xy 431.239834 -20.103627) (xy 431.173258 -20.155983) (xy 431.102006 -20.201773) (xy 431.026725 -20.240584)
			(xy 430.948095 -20.272063) (xy 430.866828 -20.295924) (xy 430.783662 -20.311953) (xy 430.699348 -20.320004)
			(xy 430.657 -20.320508) (xy 430.656746 -20.320508) (xy 430.614759 -20.320019) (xy 430.531162 -20.31208)
			(xy 430.448684 -20.296305) (xy 430.368057 -20.272835) (xy 430.289997 -20.241878) (xy 430.252378 -20.223226)
			(xy 430.24088 -20.218057) (xy 430.215703 -20.21846) (xy 430.204372 -20.223988) (xy 430.164375 -20.245827)
			(xy 430.080803 -20.282174) (xy 429.99395 -20.30978) (xy 429.904729 -20.328353) (xy 429.814075 -20.337699)
			(xy 429.768508 -20.338288) (xy 429.768 -20.338288) (xy 429.725651 -20.337824) (xy 429.641335 -20.329773)
			(xy 429.558167 -20.313744) (xy 429.476899 -20.289881) (xy 429.398267 -20.258402) (xy 429.322984 -20.219591)
			(xy 429.25173 -20.173799) (xy 429.185153 -20.121442) (xy 429.123853 -20.062993) (xy 429.068387 -19.998982)
			(xy 429.019257 -19.929988) (xy 428.976908 -19.856636) (xy 428.941722 -19.779592) (xy 428.91402 -19.699551)
			(xy 428.894052 -19.61724) (xy 428.881998 -19.533403) (xy 428.877968 -19.4488) (xy 419.415728 -19.4488)
			(xy 419.422153 -19.482138) (xy 419.430204 -19.566452) (xy 419.430708 -19.6088) (xy 419.430708 -19.609308)
			(xy 419.430102 -19.65564) (xy 419.420431 -19.747798) (xy 419.401235 -19.838452) (xy 419.372723 -19.926621)
			(xy 419.354508 -19.969226) (xy 419.350702 -19.979168) (xy 419.350702 -20.000432) (xy 419.354508 -20.010374)
			(xy 419.372753 -20.053036) (xy 419.401297 -20.141329) (xy 419.42049 -20.232114) (xy 419.430123 -20.324404)
			(xy 419.430708 -20.3708) (xy 419.430125 -20.417196) (xy 419.42048 -20.509484) (xy 419.401284 -20.600268)
			(xy 419.372746 -20.688561) (xy 419.354508 -20.731226) (xy 419.350702 -20.741168) (xy 419.350702 -20.762432)
			(xy 419.354508 -20.772374) (xy 419.37273 -20.814977) (xy 419.401248 -20.903144) (xy 419.42044 -20.9938)
			(xy 419.4301 -21.08596) (xy 419.430708 -21.132292) (xy 419.430708 -21.1328) (xy 419.430204 -21.175148)
			(xy 419.422153 -21.259462) (xy 419.406124 -21.342628) (xy 419.382263 -21.423895) (xy 419.350784 -21.502525)
			(xy 419.311973 -21.577806) (xy 419.266183 -21.649058) (xy 419.213827 -21.715634) (xy 419.155379 -21.776932)
			(xy 419.091369 -21.832397) (xy 419.022377 -21.881526) (xy 418.949027 -21.923875) (xy 418.871984 -21.959059)
			(xy 418.791945 -21.986761) (xy 418.709636 -22.006729) (xy 418.625801 -22.018782) (xy 418.5412 -22.022813)
			(xy 418.456599 -22.018782) (xy 418.372764 -22.006729) (xy 418.290455 -21.986761) (xy 418.210416 -21.959059)
			(xy 418.133373 -21.923875) (xy 418.060023 -21.881526) (xy 417.991031 -21.832397) (xy 417.927021 -21.776932)
			(xy 417.868573 -21.715634) (xy 417.816217 -21.649058) (xy 417.770427 -21.577806) (xy 417.731616 -21.502525)
			(xy 417.700137 -21.423895) (xy 417.676276 -21.342628) (xy 417.660247 -21.259462) (xy 417.652196 -21.175148)
			(xy 417.651692 -21.1328) (xy 412.055892 -21.1328) (xy 412.041543 -21.209562) (xy 412.019047 -21.288629)
			(xy 411.989351 -21.365283) (xy 411.952709 -21.43887) (xy 411.909434 -21.508762) (xy 411.859894 -21.574363)
			(xy 411.804513 -21.635113) (xy 411.743763 -21.690494) (xy 411.678162 -21.740034) (xy 411.60827 -21.783309)
			(xy 411.534683 -21.819951) (xy 411.458029 -21.849647) (xy 411.378962 -21.872143) (xy 411.298157 -21.887248)
			(xy 411.216302 -21.894833) (xy 411.1752 -21.895308) (xy 411.174692 -21.895308) (xy 411.12836 -21.894702)
			(xy 411.036202 -21.885031) (xy 410.945548 -21.865835) (xy 410.857379 -21.837323) (xy 410.814774 -21.819108)
			(xy 410.804832 -21.815302) (xy 410.783568 -21.815302) (xy 410.773626 -21.819108) (xy 410.730964 -21.837353)
			(xy 410.642671 -21.865897) (xy 410.551886 -21.88509) (xy 410.459596 -21.894723) (xy 410.4132 -21.895308)
			(xy 410.368725 -21.894772) (xy 410.280218 -21.885915) (xy 410.193037 -21.868269) (xy 410.108052 -21.842011)
			(xy 410.026112 -21.807402) (xy 409.948035 -21.764789) (xy 409.8746 -21.714596) (xy 409.806541 -21.657326)
			(xy 409.775152 -21.625814) (xy 409.76423 -21.614638) (xy 409.734004 -21.608288) (xy 409.617418 -21.657056)
			(xy 409.600654 -21.682964) (xy 409.600908 -21.698204) (xy 409.600908 -21.69922) (xy 409.600908 -21.717)
			(xy 409.600412 -21.760815) (xy 409.591867 -21.848026) (xy 409.57478 -21.933973) (xy 409.549319 -22.017821)
			(xy 409.515729 -22.098757) (xy 409.495498 -22.137624) (xy 409.490171 -22.148977) (xy 409.490171 -22.174023)
			(xy 409.495498 -22.185376) (xy 409.515692 -22.224204) (xy 409.549232 -22.305047) (xy 409.574677 -22.388792)
			(xy 409.591782 -22.474629) (xy 409.600381 -22.56173) (xy 409.600908 -22.605492) (xy 409.600908 -22.606)
			(xy 409.600433 -22.647102) (xy 409.592848 -22.728957) (xy 409.577743 -22.809762) (xy 409.555247 -22.888829)
			(xy 409.525551 -22.965483) (xy 409.488909 -23.03907) (xy 409.445634 -23.108962) (xy 409.396094 -23.174563)
			(xy 409.340713 -23.235313) (xy 409.279963 -23.290694) (xy 409.214362 -23.340234) (xy 409.14447 -23.383509)
			(xy 409.090544 -23.410361) (xy 432.460142 -23.410361) (xy 432.460142 -23.325639) (xy 432.468195 -23.241302)
			(xy 432.484229 -23.158112) (xy 432.508097 -23.076822) (xy 432.539585 -22.99817) (xy 432.578407 -22.922867)
			(xy 432.62421 -22.851595) (xy 432.676581 -22.784999) (xy 432.735046 -22.723684) (xy 432.799074 -22.668203)
			(xy 432.868086 -22.61906) (xy 432.941456 -22.5767) (xy 433.018521 -22.541505) (xy 433.098583 -22.513796)
			(xy 433.180916 -22.493822) (xy 433.264775 -22.481765) (xy 433.3494 -22.477734) (xy 433.434025 -22.481765)
			(xy 433.517884 -22.493822) (xy 433.600217 -22.513796) (xy 433.680279 -22.541505) (xy 433.757344 -22.5767)
			(xy 433.830714 -22.61906) (xy 433.899726 -22.668203) (xy 433.963754 -22.723684) (xy 434.022219 -22.784999)
			(xy 434.07459 -22.851595) (xy 434.120393 -22.922867) (xy 434.159215 -22.99817) (xy 434.190703 -23.076822)
			(xy 434.214571 -23.158112) (xy 434.230605 -23.241302) (xy 434.238658 -23.325639) (xy 434.239162 -23.368)
			(xy 434.238658 -23.410361) (xy 434.230605 -23.494698) (xy 434.214571 -23.577888) (xy 434.190703 -23.659178)
			(xy 434.159215 -23.73783) (xy 434.120393 -23.813133) (xy 434.07459 -23.884405) (xy 434.022219 -23.951001)
			(xy 433.963754 -24.012316) (xy 433.899726 -24.067797) (xy 433.830714 -24.11694) (xy 433.757344 -24.1593)
			(xy 433.680279 -24.194495) (xy 433.600217 -24.222204) (xy 433.517884 -24.242178) (xy 433.434025 -24.254235)
			(xy 433.3494 -24.258267) (xy 433.264775 -24.254235) (xy 433.180916 -24.242178) (xy 433.098583 -24.222204)
			(xy 433.018521 -24.194495) (xy 432.941456 -24.1593) (xy 432.868086 -24.11694) (xy 432.799074 -24.067797)
			(xy 432.735046 -24.012316) (xy 432.676581 -23.951001) (xy 432.62421 -23.884405) (xy 432.578407 -23.813133)
			(xy 432.539585 -23.73783) (xy 432.508097 -23.659178) (xy 432.484229 -23.577888) (xy 432.468195 -23.494698)
			(xy 432.460142 -23.410361) (xy 409.090544 -23.410361) (xy 409.070883 -23.420151) (xy 408.994229 -23.449847)
			(xy 408.915162 -23.472343) (xy 408.834357 -23.487448) (xy 408.752502 -23.495033) (xy 408.7114 -23.495508)
			(xy 408.710892 -23.495508) (xy 408.66456 -23.494902) (xy 408.572402 -23.485231) (xy 408.481748 -23.466035)
			(xy 408.393579 -23.437523) (xy 408.350974 -23.419308) (xy 408.341032 -23.415502) (xy 408.319768 -23.415502)
			(xy 408.309826 -23.419308) (xy 408.267223 -23.43753) (xy 408.179056 -23.466048) (xy 408.0884 -23.48524)
			(xy 407.99624 -23.4949) (xy 407.949908 -23.495508) (xy 407.9494 -23.495508) (xy 407.907085 -23.495005)
			(xy 407.822837 -23.486974) (xy 407.739734 -23.470976) (xy 407.658525 -23.447155) (xy 407.579948 -23.415728)
			(xy 407.504711 -23.376977) (xy 407.468832 -23.354538) (xy 407.460443 -23.349655) (xy 407.4414 -23.345984)
			(xy 407.422357 -23.349655) (xy 407.413968 -23.354538) (xy 407.378094 -23.376984) (xy 407.302853 -23.415727)
			(xy 407.224274 -23.447151) (xy 407.143065 -23.47097) (xy 407.059962 -23.48697) (xy 406.975715 -23.495006)
			(xy 406.9334 -23.495508) (xy 406.892298 -23.495033) (xy 406.810443 -23.487448) (xy 406.729638 -23.472343)
			(xy 406.650571 -23.449847) (xy 406.573917 -23.420151) (xy 406.50033 -23.383509) (xy 406.430438 -23.340234)
			(xy 406.364837 -23.290694) (xy 406.304087 -23.235313) (xy 406.248706 -23.174563) (xy 406.199166 -23.108962)
			(xy 406.155891 -23.03907) (xy 406.119249 -22.965483) (xy 406.089553 -22.888829) (xy 406.067057 -22.809762)
			(xy 406.051952 -22.728957) (xy 406.044367 -22.647102) (xy 406.043892 -22.606) (xy 372.085384 -22.606)
			(xy 371.93705 -22.713771) (xy 371.769358 -22.82582) (xy 371.597395 -22.931198) (xy 371.421429 -23.029744)
			(xy 371.241729 -23.121306) (xy 371.058572 -23.205742) (xy 370.872243 -23.282923) (xy 370.683026 -23.352728)
			(xy 370.491215 -23.415051) (xy 370.297105 -23.469796) (xy 370.100996 -23.516878) (xy 369.903189 -23.556224)
			(xy 369.70399 -23.587774) (xy 369.503706 -23.611479) (xy 369.302646 -23.627303) (xy 369.101119 -23.635221)
			(xy 368.899437 -23.635221) (xy 368.69791 -23.627303) (xy 368.49685 -23.611479) (xy 368.296566 -23.587774)
			(xy 368.097367 -23.556224) (xy 367.89956 -23.516878) (xy 367.703451 -23.469796) (xy 367.509341 -23.415051)
			(xy 367.31753 -23.352728) (xy 367.128313 -23.282923) (xy 366.941984 -23.205742) (xy 366.758827 -23.121306)
			(xy 366.579127 -23.029744) (xy 366.403161 -22.931198) (xy 366.231198 -22.82582) (xy 366.063506 -22.713771)
			(xy 365.900342 -22.595225) (xy 365.741957 -22.470365) (xy 365.588597 -22.339383) (xy 365.440497 -22.202481)
			(xy 365.297887 -22.059871) (xy 365.160985 -21.911771) (xy 365.030003 -21.758411) (xy 364.905143 -21.600026)
			(xy 364.786597 -21.436862) (xy 364.674548 -21.26917) (xy 364.56917 -21.097207) (xy 364.470624 -20.921241)
			(xy 364.379062 -20.741541) (xy 364.294626 -20.558384) (xy 364.217445 -20.372055) (xy 364.14764 -20.182838)
			(xy 364.085317 -19.991027) (xy 364.030572 -19.796917) (xy 363.98349 -19.600808) (xy 363.944144 -19.403001)
			(xy 363.912594 -19.203802) (xy 363.888889 -19.003518) (xy 363.873065 -18.802458) (xy 363.865147 -18.600931)
			(xy 363.864652 -18.50009) (xy 357.521002 -18.50009) (xy 364.147812 -25.1269) (xy 386.993184 -25.1269)
			(xy 386.997214 -25.04228) (xy 387.009271 -24.958425) (xy 387.029244 -24.876097) (xy 387.056952 -24.79604)
			(xy 387.092144 -24.718979) (xy 387.134502 -24.645613) (xy 387.183643 -24.576605) (xy 387.23912 -24.51258)
			(xy 387.300432 -24.454119) (xy 387.367024 -24.401751) (xy 387.438292 -24.35595) (xy 387.513591 -24.317131)
			(xy 387.592239 -24.285645) (xy 387.673524 -24.261777) (xy 387.756709 -24.245745) (xy 387.841042 -24.237692)
			(xy 387.8834 -24.237188) (xy 387.929538 -24.237811) (xy 388.021312 -24.247437) (xy 388.111596 -24.266512)
			(xy 388.155688 -24.280114) (xy 388.164633 -24.282583) (xy 388.18315 -24.28159) (xy 388.200094 -24.274055)
			(xy 388.213234 -24.26097) (xy 388.21741 -24.252682) (xy 388.235507 -24.214416) (xy 388.277885 -24.141135)
			(xy 388.327034 -24.072211) (xy 388.382507 -24.008268) (xy 388.443803 -23.949883) (xy 388.510368 -23.897585)
			(xy 388.5816 -23.851846) (xy 388.656855 -23.81308) (xy 388.735451 -23.781639) (xy 388.816679 -23.757805)
			(xy 388.899804 -23.741796) (xy 388.984074 -23.733754) (xy 389.0264 -23.733252) (xy 389.068761 -23.733728)
			(xy 389.1531 -23.741781) (xy 389.236292 -23.757815) (xy 389.317582 -23.781684) (xy 389.396236 -23.813172)
			(xy 389.47154 -23.851994) (xy 389.542813 -23.897799) (xy 389.60941 -23.950171) (xy 389.670726 -24.008636)
			(xy 389.726208 -24.072665) (xy 389.775352 -24.141678) (xy 389.817713 -24.21505) (xy 389.852908 -24.292116)
			(xy 389.880618 -24.372179) (xy 389.900592 -24.454513) (xy 389.912649 -24.538373) (xy 389.913363 -24.553361)
			(xy 393.064742 -24.553361) (xy 393.064742 -24.468639) (xy 393.072795 -24.384302) (xy 393.088829 -24.301112)
			(xy 393.112697 -24.219822) (xy 393.144185 -24.14117) (xy 393.183007 -24.065867) (xy 393.22881 -23.994595)
			(xy 393.281181 -23.927999) (xy 393.339646 -23.866684) (xy 393.403674 -23.811203) (xy 393.472686 -23.76206)
			(xy 393.546056 -23.7197) (xy 393.623121 -23.684505) (xy 393.703183 -23.656796) (xy 393.785516 -23.636822)
			(xy 393.869375 -23.624765) (xy 393.954 -23.620734) (xy 394.038625 -23.624765) (xy 394.122484 -23.636822)
			(xy 394.204817 -23.656796) (xy 394.284879 -23.684505) (xy 394.361944 -23.7197) (xy 394.435314 -23.76206)
			(xy 394.504326 -23.811203) (xy 394.568354 -23.866684) (xy 394.626819 -23.927999) (xy 394.67919 -23.994595)
			(xy 394.724993 -24.065867) (xy 394.763815 -24.14117) (xy 394.795303 -24.219822) (xy 394.819171 -24.301112)
			(xy 394.835205 -24.384302) (xy 394.843258 -24.468639) (xy 394.843762 -24.511) (xy 394.843258 -24.553361)
			(xy 394.835205 -24.637698) (xy 394.819171 -24.720888) (xy 394.795303 -24.802178) (xy 394.763815 -24.88083)
			(xy 394.724993 -24.956133) (xy 394.67919 -25.027405) (xy 394.626819 -25.094001) (xy 394.568354 -25.155316)
			(xy 394.504326 -25.210797) (xy 394.435314 -25.25994) (xy 394.361944 -25.3023) (xy 394.284879 -25.337495)
			(xy 394.204817 -25.365204) (xy 394.122484 -25.385178) (xy 394.038625 -25.397235) (xy 393.954 -25.401267)
			(xy 393.869375 -25.397235) (xy 393.785516 -25.385178) (xy 393.703183 -25.365204) (xy 393.623121 -25.337495)
			(xy 393.546056 -25.3023) (xy 393.472686 -25.25994) (xy 393.403674 -25.210797) (xy 393.339646 -25.155316)
			(xy 393.281181 -25.094001) (xy 393.22881 -25.027405) (xy 393.183007 -24.956133) (xy 393.144185 -24.88083)
			(xy 393.112697 -24.802178) (xy 393.088829 -24.720888) (xy 393.072795 -24.637698) (xy 393.064742 -24.553361)
			(xy 389.913363 -24.553361) (xy 389.916681 -24.623) (xy 389.912649 -24.707627) (xy 389.900592 -24.791487)
			(xy 389.880618 -24.873821) (xy 389.852908 -24.953884) (xy 389.817713 -25.03095) (xy 389.775352 -25.104322)
			(xy 389.726208 -25.173335) (xy 389.670726 -25.237364) (xy 389.60941 -25.295829) (xy 389.542813 -25.348201)
			(xy 389.47154 -25.394006) (xy 389.396236 -25.432828) (xy 389.317582 -25.464316) (xy 389.236292 -25.488185)
			(xy 389.1531 -25.504219) (xy 389.068761 -25.512272) (xy 389.0264 -25.512776) (xy 388.980262 -25.51215)
			(xy 388.888488 -25.502525) (xy 388.798204 -25.483451) (xy 388.754112 -25.46985) (xy 388.745163 -25.467401)
			(xy 388.726651 -25.468394) (xy 388.709711 -25.475923) (xy 388.69657 -25.488999) (xy 388.69239 -25.497282)
			(xy 388.674276 -25.53554) (xy 388.6319 -25.608821) (xy 388.582754 -25.677746) (xy 388.527283 -25.741691)
			(xy 388.465989 -25.800077) (xy 388.399426 -25.852376) (xy 388.328195 -25.898115) (xy 388.252942 -25.936882)
			(xy 388.174346 -25.968324) (xy 388.093119 -25.992158) (xy 388.009995 -26.008168) (xy 387.925726 -26.01621)
			(xy 387.8834 -26.016712) (xy 387.841042 -26.016108) (xy 387.756709 -26.008055) (xy 387.673524 -25.992023)
			(xy 387.592239 -25.968155) (xy 387.513591 -25.936669) (xy 387.438292 -25.89785) (xy 387.367024 -25.852049)
			(xy 387.300432 -25.799681) (xy 387.23912 -25.74122) (xy 387.183643 -25.677195) (xy 387.134502 -25.608187)
			(xy 387.092144 -25.534821) (xy 387.056952 -25.45776) (xy 387.029244 -25.377703) (xy 387.009271 -25.295375)
			(xy 386.997214 -25.21152) (xy 386.993184 -25.1269) (xy 364.147812 -25.1269) (xy 367.919254 -28.898342)
			(xy 375.771664 -28.898342) (xy 375.772264 -28.851947) (xy 375.781904 -28.759659) (xy 375.801095 -28.668875)
			(xy 375.829629 -28.580581) (xy 375.847864 -28.537916) (xy 375.851646 -28.527966) (xy 375.851662 -28.50671)
			(xy 375.847864 -28.496768) (xy 375.829631 -28.454101) (xy 375.801085 -28.36581) (xy 375.781888 -28.275027)
			(xy 375.772251 -28.182738) (xy 375.771664 -28.136342) (xy 375.772264 -28.089947) (xy 375.781904 -27.997659)
			(xy 375.801095 -27.906875) (xy 375.829629 -27.818581) (xy 375.847864 -27.775916) (xy 375.851646 -27.765966)
			(xy 375.851662 -27.74471) (xy 375.847864 -27.734768) (xy 375.829631 -27.692101) (xy 375.801085 -27.60381)
			(xy 375.781888 -27.513027) (xy 375.772251 -27.420738) (xy 375.771664 -27.374342) (xy 375.772264 -27.327947)
			(xy 375.781904 -27.235659) (xy 375.801095 -27.144875) (xy 375.829629 -27.056581) (xy 375.847864 -27.013916)
			(xy 375.851646 -27.003966) (xy 375.851662 -26.98271) (xy 375.847864 -26.972768) (xy 375.829654 -26.93016)
			(xy 375.801134 -26.841994) (xy 375.781938 -26.751341) (xy 375.772274 -26.659182) (xy 375.771664 -26.61285)
			(xy 375.771664 -26.612342) (xy 375.772153 -26.571235) (xy 375.779733 -26.489372) (xy 375.794834 -26.408557)
			(xy 375.817327 -26.32948) (xy 375.847018 -26.252815) (xy 375.883656 -26.179216) (xy 375.926927 -26.109312)
			(xy 375.976463 -26.043697) (xy 376.031842 -25.982933) (xy 376.092589 -25.927536) (xy 376.158189 -25.87798)
			(xy 376.22808 -25.834687) (xy 376.301668 -25.798027) (xy 376.378324 -25.768312) (xy 376.457394 -25.745796)
			(xy 376.538204 -25.730671) (xy 376.620065 -25.723065) (xy 376.661172 -25.72258) (xy 376.707575 -25.723181)
			(xy 376.799873 -25.732879) (xy 376.890658 -25.75214) (xy 376.978943 -25.780755) (xy 377.021598 -25.799034)
			(xy 377.03154 -25.80284) (xy 377.052804 -25.80284) (xy 377.062746 -25.799034) (xy 377.105411 -25.780781)
			(xy 377.193697 -25.752186) (xy 377.284479 -25.732926) (xy 377.376771 -25.72321) (xy 377.423172 -25.72258)
			(xy 377.469575 -25.723181) (xy 377.561873 -25.732879) (xy 377.652658 -25.75214) (xy 377.740943 -25.780755)
			(xy 377.783598 -25.799034) (xy 377.79354 -25.80284) (xy 377.814804 -25.80284) (xy 377.824746 -25.799034)
			(xy 377.867411 -25.780781) (xy 377.955697 -25.752186) (xy 378.046479 -25.732926) (xy 378.138771 -25.72321)
			(xy 378.185172 -25.72258) (xy 378.231575 -25.723181) (xy 378.323873 -25.732879) (xy 378.414658 -25.75214)
			(xy 378.502943 -25.780755) (xy 378.545598 -25.799034) (xy 378.55554 -25.80284) (xy 378.576804 -25.80284)
			(xy 378.586746 -25.799034) (xy 378.629411 -25.780781) (xy 378.717697 -25.752186) (xy 378.808479 -25.732926)
			(xy 378.900771 -25.72321) (xy 378.947172 -25.72258) (xy 378.988282 -25.723079) (xy 379.070151 -25.730664)
			(xy 379.15097 -25.745772) (xy 379.230051 -25.768275) (xy 379.306717 -25.797979) (xy 379.380315 -25.834632)
			(xy 379.450216 -25.87792) (xy 379.515824 -25.927474) (xy 379.576579 -25.982872) (xy 379.631962 -26.04364)
			(xy 379.681501 -26.10926) (xy 379.724773 -26.179172) (xy 379.761408 -26.252779) (xy 379.791093 -26.329452)
			(xy 379.811377 -26.4008) (xy 411.953947 -26.4008) (xy 411.957978 -26.316196) (xy 411.970031 -26.232359)
			(xy 411.99 -26.150047) (xy 412.017702 -26.070005) (xy 412.052887 -25.99296) (xy 412.095236 -25.919607)
			(xy 412.144366 -25.850613) (xy 412.199832 -25.7866) (xy 412.261131 -25.72815) (xy 412.327709 -25.675792)
			(xy 412.398962 -25.629999) (xy 412.474246 -25.591186) (xy 412.552877 -25.559705) (xy 412.634146 -25.535841)
			(xy 412.717314 -25.51981) (xy 412.80163 -25.511757) (xy 412.84398 -25.511252) (xy 412.884281 -25.511699)
			(xy 412.964552 -25.518997) (xy 413.043833 -25.533527) (xy 413.121475 -25.555169) (xy 413.196842 -25.583746)
			(xy 413.269314 -25.619023) (xy 413.338298 -25.660711) (xy 413.37103 -25.684226) (xy 413.378907 -25.689516)
			(xy 413.397211 -25.694449) (xy 413.416053 -25.692356) (xy 413.424624 -25.68829) (xy 413.462668 -25.669069)
			(xy 413.541705 -25.637142) (xy 413.623437 -25.61293) (xy 413.707111 -25.596658) (xy 413.791959 -25.588473)
			(xy 413.83458 -25.58796) (xy 413.85168 -25.588086) (xy 413.885853 -25.589484) (xy 413.902906 -25.590754)
			(xy 413.911034 -25.590754) (xy 413.92973 -25.589242) (xy 413.967207 -25.58759) (xy 413.985964 -25.587452)
			(xy 413.98698 -25.587452) (xy 414.028081 -25.587986) (xy 414.109932 -25.595568) (xy 414.190735 -25.610671)
			(xy 414.2698 -25.633164) (xy 414.346452 -25.662857) (xy 414.420037 -25.699496) (xy 414.489928 -25.742767)
			(xy 414.555528 -25.792303) (xy 414.616278 -25.84768) (xy 414.671659 -25.908426) (xy 414.721199 -25.974023)
			(xy 414.764475 -26.043911) (xy 414.801119 -26.117493) (xy 414.830816 -26.194143) (xy 414.853315 -26.273206)
			(xy 414.868423 -26.354008) (xy 414.876012 -26.435859) (xy 414.876176 -26.450036) (xy 415.298636 -26.450036)
			(xy 415.299086 -26.408325) (xy 415.306888 -26.32527) (xy 415.322435 -26.24331) (xy 415.345591 -26.163167)
			(xy 415.376153 -26.085546) (xy 415.413851 -26.011128) (xy 415.458355 -25.940569) (xy 415.509272 -25.874489)
			(xy 415.566155 -25.813469) (xy 415.628503 -25.758046) (xy 415.661856 -25.732994) (xy 415.670399 -25.726052)
			(xy 415.681076 -25.706833) (xy 415.68243 -25.69591) (xy 415.686144 -25.654539) (xy 415.700231 -25.572675)
			(xy 415.721888 -25.49248) (xy 415.750926 -25.414652) (xy 415.787092 -25.339871) (xy 415.830071 -25.268786)
			(xy 415.87949 -25.202018) (xy 415.934918 -25.140146) (xy 415.995871 -25.083711) (xy 416.06182 -25.033204)
			(xy 416.132189 -24.989063) (xy 416.206367 -24.951675) (xy 416.283708 -24.921364) (xy 416.363536 -24.898394)
			(xy 416.445159 -24.882965) (xy 416.527864 -24.875213) (xy 416.569398 -24.874728) (xy 416.569906 -24.874728)
			(xy 416.61367 -24.875243) (xy 416.700776 -24.883818) (xy 416.786618 -24.900915) (xy 416.870363 -24.926367)
			(xy 416.951201 -24.959928) (xy 416.990022 -24.980138) (xy 417.001375 -24.985465) (xy 417.026421 -24.985465)
			(xy 417.037774 -24.980138) (xy 417.07665 -24.959926) (xy 417.15759 -24.926355) (xy 417.241437 -24.900898)
			(xy 417.327379 -24.883802) (xy 417.414585 -24.875232) (xy 417.458398 -24.874728) (xy 417.502213 -24.875221)
			(xy 417.589424 -24.883766) (xy 417.675371 -24.900853) (xy 417.75922 -24.926315) (xy 417.840155 -24.959906)
			(xy 417.879022 -24.980138) (xy 417.890375 -24.985465) (xy 417.915421 -24.985465) (xy 417.926774 -24.980138)
			(xy 417.96565 -24.959926) (xy 418.04659 -24.926355) (xy 418.130437 -24.900898) (xy 418.216379 -24.883802)
			(xy 418.303585 -24.875232) (xy 418.347398 -24.874728) (xy 418.397553 -24.875369) (xy 418.497233 -24.886577)
			(xy 418.54628 -24.89708) (xy 418.556796 -24.898879) (xy 418.577704 -24.894762) (xy 418.595164 -24.882547)
			(xy 418.601144 -24.873712) (xy 418.623031 -24.838312) (xy 418.672438 -24.771329) (xy 418.727885 -24.709253)
			(xy 418.788887 -24.652626) (xy 418.85491 -24.601944) (xy 418.925379 -24.55765) (xy 418.999676 -24.52013)
			(xy 419.077152 -24.489713) (xy 419.15713 -24.466664) (xy 419.238912 -24.451185) (xy 419.321781 -24.443412)
			(xy 419.363398 -24.442928) (xy 419.405357 -24.443406) (xy 419.488901 -24.451325) (xy 419.571328 -24.467074)
			(xy 419.651907 -24.490513) (xy 419.729921 -24.521434) (xy 419.804678 -24.559562) (xy 419.875513 -24.604559)
			(xy 419.941797 -24.656025) (xy 420.002941 -24.713502) (xy 420.058403 -24.77648) (xy 420.10769 -24.8444)
			(xy 420.150363 -24.916659) (xy 420.186044 -24.992614) (xy 420.214416 -25.071591) (xy 420.235227 -25.152888)
			(xy 420.242238 -25.19426) (xy 420.243856 -25.202602) (xy 420.25187 -25.21758) (xy 420.264317 -25.229141)
			(xy 420.271956 -25.232868) (xy 420.362126 -25.272746) (xy 420.38778 -25.27046) (xy 420.398702 -25.263348)
			(xy 420.435185 -25.23978) (xy 420.51189 -25.199026) (xy 420.592204 -25.165947) (xy 420.675362 -25.140859)
			(xy 420.76057 -25.124002) (xy 420.847016 -25.115535) (xy 420.890446 -25.115012) (xy 420.8907 -25.115012)
			(xy 420.933389 -25.115543) (xy 421.018375 -25.123714) (xy 421.102187 -25.139992) (xy 421.122484 -25.146)
			(xy 435.653688 -25.146) (xy 435.654241 -25.102511) (xy 435.662749 -25.015949) (xy 435.679663 -24.930631)
			(xy 435.704822 -24.84737) (xy 435.737987 -24.766962) (xy 435.77884 -24.690174) (xy 435.826991 -24.61774)
			(xy 435.881981 -24.55035) (xy 435.91226 -24.519128) (xy 435.912514 -24.518874) (xy 435.919089 -24.51149)
			(xy 435.926533 -24.493191) (xy 435.926992 -24.483314) (xy 435.926992 -24.411686) (xy 435.926571 -24.401803)
			(xy 435.919105 -24.383504) (xy 435.912514 -24.376126) (xy 435.91226 -24.375872) (xy 435.881999 -24.344633)
			(xy 435.827008 -24.277245) (xy 435.778855 -24.204813) (xy 435.738 -24.128028) (xy 435.704831 -24.047623)
			(xy 435.679666 -23.964365) (xy 435.662745 -23.879049) (xy 435.654229 -23.792489) (xy 435.653688 -23.749)
			(xy 435.654241 -23.705511) (xy 435.662749 -23.618949) (xy 435.679663 -23.533631) (xy 435.704822 -23.45037)
			(xy 435.737987 -23.369962) (xy 435.77884 -23.293174) (xy 435.826991 -23.22074) (xy 435.881981 -23.15335)
			(xy 435.91226 -23.122128) (xy 435.912514 -23.121874) (xy 435.919089 -23.11449) (xy 435.926533 -23.096191)
			(xy 435.926992 -23.086314) (xy 435.926992 -23.014686) (xy 435.926571 -23.004803) (xy 435.919105 -22.986504)
			(xy 435.912514 -22.979126) (xy 435.91226 -22.978872) (xy 435.881999 -22.947633) (xy 435.827008 -22.880245)
			(xy 435.778855 -22.807813) (xy 435.738 -22.731028) (xy 435.704831 -22.650623) (xy 435.679666 -22.567365)
			(xy 435.662745 -22.482049) (xy 435.654229 -22.395489) (xy 435.653688 -22.352) (xy 435.654192 -22.309639)
			(xy 435.662245 -22.225302) (xy 435.678279 -22.142112) (xy 435.702147 -22.060822) (xy 435.733635 -21.98217)
			(xy 435.772457 -21.906867) (xy 435.81826 -21.835595) (xy 435.870631 -21.768999) (xy 435.929096 -21.707684)
			(xy 435.993124 -21.652203) (xy 436.062136 -21.60306) (xy 436.135506 -21.5607) (xy 436.212571 -21.525505)
			(xy 436.292633 -21.497796) (xy 436.374966 -21.477822) (xy 436.458825 -21.465765) (xy 436.54345 -21.461734)
			(xy 436.628075 -21.465765) (xy 436.711934 -21.477822) (xy 436.794267 -21.497796) (xy 436.874329 -21.525505)
			(xy 436.951394 -21.5607) (xy 437.024764 -21.60306) (xy 437.093776 -21.652203) (xy 437.157804 -21.707684)
			(xy 437.216269 -21.768999) (xy 437.26864 -21.835595) (xy 437.314443 -21.906867) (xy 437.353265 -21.98217)
			(xy 437.384753 -22.060822) (xy 437.408621 -22.142112) (xy 437.424655 -22.225302) (xy 437.432708 -22.309639)
			(xy 437.433212 -22.352) (xy 437.432659 -22.395489) (xy 437.424151 -22.482051) (xy 437.407237 -22.567369)
			(xy 437.382078 -22.65063) (xy 437.348913 -22.731038) (xy 437.30806 -22.807826) (xy 437.259909 -22.88026)
			(xy 437.204919 -22.94765) (xy 437.17464 -22.978872) (xy 437.174386 -22.979126) (xy 437.167811 -22.98651)
			(xy 437.160367 -23.004809) (xy 437.159908 -23.014686) (xy 437.159908 -23.086314) (xy 437.160329 -23.096197)
			(xy 437.167795 -23.114496) (xy 437.174386 -23.121874) (xy 437.17464 -23.122128) (xy 437.202096 -23.150398)
			(xy 437.252481 -23.210999) (xy 437.297304 -23.275822) (xy 437.336214 -23.344358) (xy 437.368904 -23.41607)
			(xy 437.382412 -23.45309) (xy 437.385871 -23.461769) (xy 437.397984 -23.475981) (xy 437.414366 -23.484943)
			(xy 437.42356 -23.486618) (xy 437.46586 -23.492702) (xy 437.549147 -23.511861) (xy 437.630213 -23.53892)
			(xy 437.708311 -23.573628) (xy 437.782719 -23.615666) (xy 437.852753 -23.664647) (xy 437.917767 -23.720119)
			(xy 437.97716 -23.781571) (xy 438.030386 -23.848435) (xy 438.076954 -23.920096) (xy 438.116435 -23.995893)
			(xy 438.148464 -24.075127) (xy 438.172746 -24.157068) (xy 438.189058 -24.240959) (xy 438.197249 -24.326029)
			(xy 438.197752 -24.36876) (xy 438.197279 -24.410153) (xy 438.189575 -24.492579) (xy 438.174249 -24.573933)
			(xy 438.151432 -24.653512) (xy 438.121323 -24.730628) (xy 438.084182 -24.804614) (xy 438.040329 -24.87483)
			(xy 437.990144 -24.94067) (xy 437.934061 -25.001564) (xy 437.872564 -25.056986) (xy 437.806186 -25.106457)
			(xy 437.7355 -25.149548) (xy 437.661117 -25.185888) (xy 437.58368 -25.215162) (xy 437.503859 -25.237117)
			(xy 437.463184 -25.244806) (xy 437.452914 -25.247122) (xy 437.435391 -25.258751) (xy 437.423984 -25.276421)
			(xy 437.421782 -25.286716) (xy 437.414689 -25.327986) (xy 437.393721 -25.409064) (xy 437.365225 -25.487812)
			(xy 437.329455 -25.563534) (xy 437.286727 -25.635559) (xy 437.237419 -25.703249) (xy 437.181968 -25.766006)
			(xy 437.120864 -25.823274) (xy 437.054649 -25.874546) (xy 436.983908 -25.919368) (xy 436.909268 -25.957344)
			(xy 436.83139 -25.988136) (xy 436.750962 -26.011474) (xy 436.668697 -26.02715) (xy 436.585323 -26.035025)
			(xy 436.54345 -26.035508) (xy 436.502345 -26.03494) (xy 436.420486 -26.02736) (xy 436.339676 -26.012262)
			(xy 436.260602 -25.989773) (xy 436.183941 -25.960085) (xy 436.110345 -25.923451) (xy 436.040443 -25.880184)
			(xy 435.97483 -25.830654) (xy 435.914067 -25.775281) (xy 435.85867 -25.714539) (xy 435.809114 -25.648946)
			(xy 435.765819 -25.579061) (xy 435.729157 -25.505479) (xy 435.699439 -25.42883) (xy 435.676918 -25.349765)
			(xy 435.661788 -25.26896) (xy 435.654176 -25.187104) (xy 435.653688 -25.146) (xy 421.122484 -25.146)
			(xy 421.184054 -25.164225) (xy 421.263221 -25.196192) (xy 421.338961 -25.235598) (xy 421.410577 -25.28208)
			(xy 421.477409 -25.33521) (xy 421.538843 -25.3945) (xy 421.594313 -25.459404) (xy 421.643308 -25.529325)
			(xy 421.685377 -25.603618) (xy 421.720135 -25.681601) (xy 421.747259 -25.762556) (xy 421.766502 -25.845737)
			(xy 421.777685 -25.93038) (xy 421.7797 -25.973024) (xy 421.7797 -25.973278) (xy 421.780733 -25.984721)
			(xy 421.791565 -26.004954) (xy 421.800528 -26.01214) (xy 421.865044 -26.059384) (xy 421.874704 -26.065583)
			(xy 421.897257 -26.069674) (xy 421.908478 -26.067258) (xy 421.908732 -26.067258) (xy 421.94771 -26.056857)
			(xy 422.027062 -26.04229) (xy 422.107407 -26.03496) (xy 422.147746 -26.034492) (xy 422.148 -26.034492)
			(xy 422.190348 -26.034996) (xy 422.274662 -26.043047) (xy 422.357828 -26.059076) (xy 422.439095 -26.082937)
			(xy 422.517725 -26.114416) (xy 422.593006 -26.153227) (xy 422.664258 -26.199017) (xy 422.730834 -26.251373)
			(xy 422.792132 -26.309821) (xy 422.847597 -26.373831) (xy 422.896726 -26.442823) (xy 422.939075 -26.516173)
			(xy 422.974259 -26.593216) (xy 423.001961 -26.673255) (xy 423.021929 -26.755564) (xy 423.033982 -26.839399)
			(xy 423.038013 -26.924) (xy 423.033982 -27.008601) (xy 423.021929 -27.092436) (xy 423.001961 -27.174745)
			(xy 422.974259 -27.254784) (xy 422.939075 -27.331827) (xy 422.896726 -27.405177) (xy 422.847597 -27.474169)
			(xy 422.792132 -27.538179) (xy 422.730834 -27.596627) (xy 422.664258 -27.648983) (xy 422.593006 -27.694773)
			(xy 422.517725 -27.733584) (xy 422.439095 -27.765063) (xy 422.357828 -27.788924) (xy 422.274662 -27.804953)
			(xy 422.190348 -27.813004) (xy 422.148 -27.813508) (xy 422.105312 -27.812958) (xy 422.020327 -27.804787)
			(xy 421.936516 -27.78851) (xy 421.85465 -27.764277) (xy 421.775484 -27.732311) (xy 421.699744 -27.692906)
			(xy 421.628129 -27.646425) (xy 421.561297 -27.593296) (xy 421.499864 -27.534008) (xy 421.444394 -27.469105)
			(xy 421.395399 -27.399187) (xy 421.353328 -27.324895) (xy 421.31857 -27.246913) (xy 421.291445 -27.16596)
			(xy 421.272201 -27.082781) (xy 421.261016 -26.99814) (xy 421.259 -26.955496) (xy 421.259 -26.955242)
			(xy 421.257956 -26.943801) (xy 421.247132 -26.923568) (xy 421.238172 -26.91638) (xy 421.173656 -26.869136)
			(xy 421.163995 -26.862938) (xy 421.141442 -26.858846) (xy 421.130222 -26.861262) (xy 421.129968 -26.861262)
			(xy 421.090989 -26.871661) (xy 421.011638 -26.88623) (xy 420.931293 -26.89356) (xy 420.890954 -26.894028)
			(xy 420.8907 -26.894028) (xy 420.84874 -26.893589) (xy 420.765193 -26.88567) (xy 420.682764 -26.869919)
			(xy 420.602183 -26.846479) (xy 420.524168 -26.815556) (xy 420.44941 -26.777425) (xy 420.378574 -26.732425)
			(xy 420.312289 -26.680957) (xy 420.251144 -26.623476) (xy 420.195683 -26.560494) (xy 420.146397 -26.492571)
			(xy 420.103725 -26.420309) (xy 420.068046 -26.34435) (xy 420.039677 -26.26537) (xy 420.018869 -26.18407)
			(xy 420.01186 -26.142696) (xy 420.01021 -26.134361) (xy 420.002211 -26.119382) (xy 419.989776 -26.107818)
			(xy 419.982142 -26.104088) (xy 419.891972 -26.06421) (xy 419.866318 -26.066496) (xy 419.855396 -26.073608)
			(xy 419.8189 -26.097194) (xy 419.742154 -26.137962) (xy 419.661796 -26.171048) (xy 419.578593 -26.196134)
			(xy 419.49334 -26.212983) (xy 419.406849 -26.221433) (xy 419.363398 -26.221944) (xy 419.313244 -26.221288)
			(xy 419.213563 -26.21009) (xy 419.164516 -26.199592) (xy 419.153999 -26.197803) (xy 419.133095 -26.201919)
			(xy 419.115635 -26.214129) (xy 419.109652 -26.22296) (xy 419.086507 -26.260393) (xy 419.033879 -26.330942)
			(xy 418.974549 -26.395956) (xy 418.909094 -26.454799) (xy 418.87394 -26.481278) (xy 418.865367 -26.488188)
			(xy 418.854706 -26.507431) (xy 418.853366 -26.518362) (xy 418.849632 -26.559731) (xy 418.835547 -26.641595)
			(xy 418.813893 -26.72179) (xy 418.784857 -26.799618) (xy 418.748693 -26.874399) (xy 418.705715 -26.945484)
			(xy 418.656298 -27.012253) (xy 418.600872 -27.074125) (xy 418.539919 -27.13056) (xy 418.473972 -27.181068)
			(xy 418.403603 -27.225209) (xy 418.329426 -27.262598) (xy 418.252086 -27.292909) (xy 418.172258 -27.315879)
			(xy 418.090636 -27.331307) (xy 418.007932 -27.339059) (xy 417.966398 -27.339544) (xy 417.96589 -27.339544)
			(xy 417.922126 -27.339034) (xy 417.835019 -27.330458) (xy 417.749178 -27.313361) (xy 417.665432 -27.287907)
			(xy 417.584595 -27.254345) (xy 417.545774 -27.234134) (xy 417.534421 -27.228807) (xy 417.509375 -27.228807)
			(xy 417.498022 -27.234134) (xy 417.459145 -27.254345) (xy 417.378206 -27.287917) (xy 417.294359 -27.313374)
			(xy 417.208417 -27.33047) (xy 417.121211 -27.33904) (xy 417.077398 -27.339544) (xy 417.033583 -27.339044)
			(xy 416.946372 -27.330499) (xy 416.860426 -27.313414) (xy 416.776577 -27.287953) (xy 416.695642 -27.254365)
			(xy 416.656774 -27.234134) (xy 416.645421 -27.228807) (xy 416.620375 -27.228807) (xy 416.609022 -27.234134)
			(xy 416.570191 -27.254323) (xy 416.489349 -27.287865) (xy 416.405606 -27.313312) (xy 416.319769 -27.330418)
			(xy 416.232668 -27.339017) (xy 416.188906 -27.339544) (xy 416.188398 -27.339544) (xy 416.147291 -27.339089)
			(xy 416.065427 -27.331505) (xy 415.984611 -27.3164) (xy 415.905534 -27.293905) (xy 415.82887 -27.26421)
			(xy 415.755271 -27.227569) (xy 415.685367 -27.184295) (xy 415.619753 -27.134757) (xy 415.558989 -27.079377)
			(xy 415.503593 -27.018627) (xy 415.454037 -26.953026) (xy 415.410745 -26.883133) (xy 415.374085 -26.809545)
			(xy 415.34437 -26.732888) (xy 415.321854 -26.653816) (xy 415.306728 -26.573005) (xy 415.299121 -26.491143)
			(xy 415.298636 -26.450036) (xy 414.876176 -26.450036) (xy 414.876488 -26.47696) (xy 414.876488 -26.477468)
			(xy 414.875898 -26.52298) (xy 414.86657 -26.613525) (xy 414.848047 -26.702645) (xy 414.834832 -26.7462)
			(xy 414.831784 -26.755852) (xy 414.833308 -26.77541) (xy 414.87471 -26.857198) (xy 414.889696 -26.869898)
			(xy 414.899094 -26.8732) (xy 414.939229 -26.887382) (xy 415.01686 -26.922312) (xy 415.0908 -26.964498)
			(xy 415.160371 -27.013554) (xy 415.224939 -27.069031) (xy 415.283913 -27.130422) (xy 415.336752 -27.197165)
			(xy 415.382975 -27.26865) (xy 415.422157 -27.344224) (xy 415.453942 -27.423195) (xy 415.478038 -27.504841)
			(xy 415.494225 -27.588416) (xy 415.502355 -27.673154) (xy 415.502852 -27.715718) (xy 415.502852 -27.716226)
			(xy 415.502358 -27.759295) (xy 415.494009 -27.845028) (xy 415.477411 -27.929553) (xy 415.45272 -28.012077)
			(xy 415.420168 -28.091827) (xy 415.380058 -28.168058) (xy 415.332766 -28.240053) (xy 415.278737 -28.30714)
			(xy 415.218475 -28.36869) (xy 415.152545 -28.424126) (xy 415.081565 -28.472929) (xy 415.044128 -28.494228)
			(xy 415.034222 -28.499816) (xy 415.02076 -28.518612) (xy 415.003488 -28.620212) (xy 415.009838 -28.642056)
			(xy 415.017712 -28.650946) (xy 415.044607 -28.681516) (xy 415.093285 -28.746793) (xy 415.135795 -28.816245)
			(xy 415.171781 -28.889291) (xy 415.200942 -28.965319) (xy 415.223035 -29.043694) (xy 415.227966 -29.0703)
			(xy 415.53638 -29.0703) (xy 415.53638 -29.06903) (xy 415.536841 -29.030892) (xy 415.543626 -28.954917)
			(xy 415.557093 -28.879838) (xy 415.577137 -28.806242) (xy 415.589974 -28.770326) (xy 415.592737 -28.761777)
			(xy 415.592737 -28.743823) (xy 415.589974 -28.735274) (xy 415.577159 -28.699352) (xy 415.557133 -28.625752)
			(xy 415.543662 -28.550677) (xy 415.536848 -28.474707) (xy 415.53638 -28.43657) (xy 415.53638 -28.4353)
			(xy 415.536912 -28.392875) (xy 415.545229 -28.308434) (xy 415.561782 -28.225214) (xy 415.586413 -28.144018)
			(xy 415.618883 -28.065627) (xy 415.658881 -27.990795) (xy 415.706021 -27.920245) (xy 415.759848 -27.854655)
			(xy 415.819846 -27.794656) (xy 415.885435 -27.740828) (xy 415.955985 -27.693687) (xy 416.030816 -27.653688)
			(xy 416.109206 -27.621217) (xy 416.190402 -27.596585) (xy 416.273622 -27.580031) (xy 416.358063 -27.571713)
			(xy 416.400488 -27.571192) (xy 416.40125 -27.571192) (xy 416.445629 -27.571767) (xy 416.533919 -27.580881)
			(xy 416.620809 -27.598998) (xy 416.705384 -27.625927) (xy 416.786753 -27.661385) (xy 416.825684 -27.682698)
			(xy 416.833436 -27.686657) (xy 416.850576 -27.689617) (xy 416.867716 -27.686657) (xy 416.875468 -27.682698)
			(xy 416.914456 -27.661385) (xy 416.995923 -27.625906) (xy 417.080599 -27.598968) (xy 417.167591 -27.580853)
			(xy 417.255981 -27.571753) (xy 417.30041 -27.571192) (xy 417.344841 -27.571756) (xy 417.433238 -27.580824)
			(xy 417.520236 -27.598923) (xy 417.604915 -27.625862) (xy 417.686378 -27.661357) (xy 417.725352 -27.682698)
			(xy 417.733104 -27.686657) (xy 417.750244 -27.689617) (xy 417.767384 -27.686657) (xy 417.775136 -27.682698)
			(xy 417.814147 -27.661375) (xy 417.895661 -27.625875) (xy 417.980388 -27.598928) (xy 418.067433 -27.580819)
			(xy 418.155877 -27.571739) (xy 418.200332 -27.571192) (xy 418.244788 -27.571712) (xy 418.333237 -27.580784)
			(xy 418.420286 -27.598891) (xy 418.505015 -27.625841) (xy 418.586529 -27.661349) (xy 418.625528 -27.682698)
			(xy 418.63328 -27.686657) (xy 418.65042 -27.689617) (xy 418.66756 -27.686657) (xy 418.675312 -27.682698)
			(xy 418.714239 -27.661379) (xy 418.795612 -27.625931) (xy 418.880188 -27.599007) (xy 418.967078 -27.58089)
			(xy 419.055367 -27.57177) (xy 419.099746 -27.571192) (xy 419.100508 -27.571192) (xy 419.141194 -27.571638)
			(xy 419.222206 -27.579288) (xy 419.30214 -27.594521) (xy 419.380288 -27.6172) (xy 419.455958 -27.647126)
			(xy 419.528479 -27.684033) (xy 419.597209 -27.727594) (xy 419.661541 -27.777423) (xy 419.720902 -27.83308)
			(xy 419.774769 -27.89407) (xy 419.822663 -27.959855) (xy 419.864161 -28.02985) (xy 419.898895 -28.103437)
			(xy 419.926558 -28.179963) (xy 419.946903 -28.258751) (xy 419.959752 -28.339102) (xy 419.962838 -28.379674)
			(xy 419.962838 -28.379928) (xy 419.964167 -28.390377) (xy 419.973995 -28.40898) (xy 419.990414 -28.422136)
			(xy 420.00043 -28.425394) (xy 420.10965 -28.454604) (xy 420.139876 -28.44292) (xy 420.14902 -28.429204)
			(xy 420.173705 -28.392952) (xy 420.229109 -28.324957) (xy 420.290934 -28.262743) (xy 420.358582 -28.206916)
			(xy 420.431396 -28.158016) (xy 420.508668 -28.116519) (xy 420.589648 -28.082828) (xy 420.673551 -28.057269)
			(xy 420.759562 -28.04009) (xy 420.846845 -28.031459) (xy 420.8907 -28.030932) (xy 420.891462 -28.030932)
			(xy 420.931154 -28.031351) (xy 421.010222 -28.038429) (xy 421.088343 -28.052532) (xy 421.164895 -28.073547)
			(xy 421.239267 -28.101308) (xy 421.275256 -28.118054) (xy 421.285757 -28.122386) (xy 421.308443 -28.122386)
			(xy 421.318944 -28.118054) (xy 421.354937 -28.101321) (xy 421.429316 -28.073589) (xy 421.505868 -28.052586)
			(xy 421.583985 -28.038481) (xy 421.663048 -28.031384) (xy 421.702738 -28.030932) (xy 421.7035 -28.030932)
			(xy 421.744604 -28.031352) (xy 421.826462 -28.038938) (xy 421.907271 -28.054044) (xy 421.986341 -28.076542)
			(xy 422.062998 -28.10624) (xy 422.136588 -28.142885) (xy 422.206483 -28.186163) (xy 422.272086 -28.235706)
			(xy 422.332837 -28.291091) (xy 422.38822 -28.351845) (xy 422.43776 -28.41745) (xy 422.481035 -28.487347)
			(xy 422.517676 -28.560938) (xy 422.547371 -28.637597) (xy 422.569865 -28.716668) (xy 422.584968 -28.797477)
			(xy 422.59255 -28.879336) (xy 422.593008 -28.92044) (xy 422.593008 -28.920694) (xy 422.592454 -28.965433)
			(xy 422.583434 -29.054455) (xy 422.565525 -29.142122) (xy 422.538908 -29.227549) (xy 422.521888 -29.268928)
			(xy 422.518299 -29.278512) (xy 422.518314 -29.298961) (xy 422.521888 -29.308552) (xy 422.538914 -29.349928)
			(xy 422.565532 -29.435355) (xy 422.583435 -29.523024) (xy 422.592443 -29.612047) (xy 422.593008 -29.656786)
			(xy 422.593008 -29.65704) (xy 422.592572 -29.698143) (xy 422.584983 -29.779998) (xy 422.569874 -29.860804)
			(xy 422.547375 -29.939872) (xy 422.517676 -30.016526) (xy 422.481031 -30.090113) (xy 422.437753 -30.160005)
			(xy 422.388211 -30.225606) (xy 422.332827 -30.286355) (xy 422.272075 -30.341736) (xy 422.206472 -30.391275)
			(xy 422.136578 -30.43455) (xy 422.062989 -30.471192) (xy 421.986334 -30.500887) (xy 421.907266 -30.523384)
			(xy 421.826459 -30.538489) (xy 421.744603 -30.546073) (xy 421.7035 -30.546548) (xy 421.702738 -30.546548)
			(xy 421.663046 -30.546131) (xy 421.583978 -30.539053) (xy 421.505857 -30.524949) (xy 421.429305 -30.503934)
			(xy 421.354933 -30.476173) (xy 421.318944 -30.459426) (xy 421.308443 -30.455094) (xy 421.285757 -30.455094)
			(xy 421.275256 -30.459426) (xy 421.239262 -30.476158) (xy 421.164884 -30.50389) (xy 421.088332 -30.524893)
			(xy 421.010215 -30.538999) (xy 420.931152 -30.546096) (xy 420.891462 -30.546548) (xy 420.8907 -30.546548)
			(xy 420.849599 -30.546033) (xy 420.767747 -30.538449) (xy 420.686944 -30.523345) (xy 420.607879 -30.500849)
			(xy 420.531227 -30.471155) (xy 420.457642 -30.434515) (xy 420.387751 -30.391242) (xy 420.322151 -30.341705)
			(xy 420.261401 -30.286327) (xy 420.20602 -30.22558) (xy 420.15648 -30.159982) (xy 420.113204 -30.090093)
			(xy 420.076561 -30.01651) (xy 420.046863 -29.939859) (xy 420.024364 -29.860795) (xy 420.009257 -29.779993)
			(xy 420.001668 -29.698141) (xy 420.001192 -29.65704) (xy 420.001192 -29.656786) (xy 420.001773 -29.612048)
			(xy 420.010785 -29.523027) (xy 420.028686 -29.435359) (xy 420.055296 -29.349931) (xy 420.072312 -29.308552)
			(xy 420.075855 -29.298955) (xy 420.07587 -29.278518) (xy 420.072312 -29.268928) (xy 420.06628 -29.254625)
			(xy 420.055102 -29.225662) (xy 420.04996 -29.211016) (xy 420.047674 -29.205428) (xy 420.042591 -29.196362)
			(xy 420.026808 -29.182879) (xy 420.006979 -29.176738) (xy 419.986338 -29.178941) (xy 419.968251 -29.189127)
			(xy 419.955668 -29.205637) (xy 419.952678 -29.215588) (xy 419.951916 -29.21889) (xy 419.944515 -29.258485)
			(xy 419.923324 -29.336204) (xy 419.894993 -29.411613) (xy 419.859768 -29.484059) (xy 419.817955 -29.552914)
			(xy 419.769916 -29.617578) (xy 419.716069 -29.677493) (xy 419.65688 -29.732136) (xy 419.592863 -29.781035)
			(xy 419.524574 -29.823765) (xy 419.452605 -29.859956) (xy 419.377581 -29.889293) (xy 419.300153 -29.911521)
			(xy 419.220992 -29.926448) (xy 419.140786 -29.933945) (xy 419.100508 -29.934408) (xy 419.099746 -29.934408)
			(xy 419.055367 -29.933835) (xy 418.967077 -29.92472) (xy 418.880187 -29.906603) (xy 418.795612 -29.879673)
			(xy 418.714243 -29.844215) (xy 418.675312 -29.822902) (xy 418.66756 -29.818943) (xy 418.65042 -29.815983)
			(xy 418.63328 -29.818943) (xy 418.625528 -29.822902) (xy 418.586524 -29.84424) (xy 418.505008 -29.879737)
			(xy 418.420279 -29.906681) (xy 418.333232 -29.924786) (xy 418.244787 -29.933863) (xy 418.200332 -29.934408)
			(xy 418.155876 -29.93386) (xy 418.067429 -29.924794) (xy 417.98038 -29.906694) (xy 417.89565 -29.87975)
			(xy 417.814135 -29.844248) (xy 417.775136 -29.822902) (xy 417.767384 -29.818943) (xy 417.750244 -29.815983)
			(xy 417.733104 -29.818943) (xy 417.725352 -29.822902) (xy 417.686381 -29.844246) (xy 417.604909 -29.879719)
			(xy 417.520229 -29.906651) (xy 417.433233 -29.924759) (xy 417.34484 -29.933851) (xy 417.30041 -29.934408)
			(xy 417.255978 -29.933879) (xy 417.16758 -29.924804) (xy 417.080582 -29.906696) (xy 416.995903 -29.879749)
			(xy 416.914441 -29.844247) (xy 416.875468 -29.822902) (xy 416.867716 -29.818943) (xy 416.850576 -29.815983)
			(xy 416.833436 -29.818943) (xy 416.825684 -29.822902) (xy 416.786758 -29.844223) (xy 416.705385 -29.87967)
			(xy 416.620808 -29.906594) (xy 416.533918 -29.924711) (xy 416.445629 -29.93383) (xy 416.40125 -29.934408)
			(xy 416.400488 -29.934408) (xy 416.358062 -29.933899) (xy 416.27362 -29.925581) (xy 416.1904 -29.909026)
			(xy 416.109202 -29.884394) (xy 416.030811 -29.851923) (xy 415.955979 -29.811923) (xy 415.885428 -29.764782)
			(xy 415.819838 -29.710952) (xy 415.759839 -29.650953) (xy 415.706011 -29.585362) (xy 415.658871 -29.514811)
			(xy 415.618872 -29.439979) (xy 415.586402 -29.361586) (xy 415.561771 -29.280389) (xy 415.545217 -29.197168)
			(xy 415.5369 -29.112726) (xy 415.53638 -29.0703) (xy 415.227966 -29.0703) (xy 415.237875 -29.123759)
			(xy 415.245337 -29.204846) (xy 415.245804 -29.24556) (xy 415.2453 -29.287921) (xy 415.237247 -29.372258)
			(xy 415.221213 -29.455448) (xy 415.197345 -29.536738) (xy 415.165857 -29.61539) (xy 415.127035 -29.690693)
			(xy 415.081232 -29.761965) (xy 415.028861 -29.828561) (xy 414.970396 -29.889876) (xy 414.906368 -29.945357)
			(xy 414.837356 -29.9945) (xy 414.763986 -30.03686) (xy 414.686921 -30.072055) (xy 414.606859 -30.099764)
			(xy 414.524526 -30.119738) (xy 414.440667 -30.131795) (xy 414.356042 -30.135827) (xy 414.271417 -30.131795)
			(xy 414.187558 -30.119738) (xy 414.105225 -30.099764) (xy 414.025163 -30.072055) (xy 413.948098 -30.03686)
			(xy 413.874728 -29.9945) (xy 413.805716 -29.945357) (xy 413.741688 -29.889876) (xy 413.683223 -29.828561)
			(xy 413.630852 -29.761965) (xy 413.585049 -29.690693) (xy 413.546227 -29.61539) (xy 413.514739 -29.536738)
			(xy 413.490871 -29.455448) (xy 413.474837 -29.372258) (xy 413.466784 -29.287921) (xy 413.46628 -29.24556)
			(xy 413.466797 -29.202463) (xy 413.475136 -29.116674) (xy 413.49173 -29.032094) (xy 413.516426 -28.949514)
			(xy 413.54899 -28.869709) (xy 413.589119 -28.793427) (xy 413.636436 -28.721383) (xy 413.690497 -28.654251)
			(xy 413.750797 -28.592662) (xy 413.816769 -28.537192) (xy 413.887796 -28.488361) (xy 413.925258 -28.46705)
			(xy 413.935164 -28.461462) (xy 413.948626 -28.442666) (xy 413.963866 -28.352496) (xy 413.965109 -28.34115)
			(xy 413.958789 -28.319254) (xy 413.951674 -28.310332) (xy 413.924814 -28.27974) (xy 413.876171 -28.214454)
			(xy 413.833695 -28.144997) (xy 413.79774 -28.071951) (xy 413.768609 -27.995925) (xy 413.746545 -27.917557)
			(xy 413.731731 -27.837501) (xy 413.724292 -27.756426) (xy 413.723836 -27.715718) (xy 413.723836 -27.714702)
			(xy 413.724291 -27.674888) (xy 413.731455 -27.595582) (xy 413.74568 -27.517235) (xy 413.75584 -27.478736)
			(xy 413.75584 -27.478482) (xy 413.758071 -27.468243) (xy 413.755057 -27.447527) (xy 413.749998 -27.43835)
			(xy 413.71012 -27.37485) (xy 413.704034 -27.366119) (xy 413.686443 -27.354179) (xy 413.676084 -27.351736)
			(xy 413.636452 -27.344104) (xy 413.558658 -27.322582) (xy 413.483134 -27.294101) (xy 413.410502 -27.258893)
			(xy 413.341358 -27.21725) (xy 413.308546 -27.193748) (xy 413.30068 -27.18844) (xy 413.282369 -27.183514)
			(xy 413.263524 -27.185614) (xy 413.254952 -27.189684) (xy 413.216868 -27.20895) (xy 413.137733 -27.240932)
			(xy 413.0559 -27.265194) (xy 412.972121 -27.281512) (xy 412.887164 -27.289737) (xy 412.844488 -27.290268)
			(xy 412.84398 -27.290268) (xy 412.80163 -27.289843) (xy 412.717314 -27.28179) (xy 412.634146 -27.265759)
			(xy 412.552877 -27.241895) (xy 412.474246 -27.210414) (xy 412.398962 -27.171601) (xy 412.327709 -27.125808)
			(xy 412.261131 -27.07345) (xy 412.199832 -27.015) (xy 412.144366 -26.950987) (xy 412.095236 -26.881993)
			(xy 412.052887 -26.80864) (xy 412.017702 -26.731595) (xy 411.99 -26.651553) (xy 411.970031 -26.569241)
			(xy 411.957978 -26.485404) (xy 411.953947 -26.4008) (xy 379.811377 -26.4008) (xy 379.813577 -26.408538)
			(xy 379.828665 -26.489361) (xy 379.836231 -26.571232) (xy 379.83668 -26.612342) (xy 379.836079 -26.658737)
			(xy 379.82644 -26.751025) (xy 379.807249 -26.841809) (xy 379.778716 -26.930103) (xy 379.76048 -26.972768)
			(xy 379.756651 -26.982703) (xy 379.756667 -27.003973) (xy 379.76048 -27.013916) (xy 379.778737 -27.056573)
			(xy 379.807278 -27.144867) (xy 379.826468 -27.235654) (xy 379.836097 -27.327946) (xy 379.83668 -27.374342)
			(xy 379.836079 -27.420737) (xy 379.82644 -27.513025) (xy 379.807249 -27.603809) (xy 379.778716 -27.692103)
			(xy 379.76048 -27.734768) (xy 379.756651 -27.744703) (xy 379.756667 -27.765973) (xy 379.76048 -27.775916)
			(xy 379.778737 -27.818573) (xy 379.807278 -27.906867) (xy 379.826468 -27.997654) (xy 379.836097 -28.089946)
			(xy 379.83668 -28.136342) (xy 379.836079 -28.182737) (xy 379.82644 -28.275025) (xy 379.816721 -28.321)
			(xy 386.358892 -28.321) (xy 386.359378 -28.27822) (xy 386.3676 -28.193056) (xy 386.383959 -28.109075)
			(xy 386.408303 -28.027052) (xy 386.440408 -27.947744) (xy 386.479976 -27.871883) (xy 386.526644 -27.800171)
			(xy 386.579979 -27.73327) (xy 386.63949 -27.671797) (xy 386.704626 -27.616319) (xy 386.774787 -27.567351)
			(xy 386.849324 -27.525342) (xy 386.927549 -27.490682) (xy 386.967984 -27.476704) (xy 386.9768 -27.473333)
			(xy 386.991321 -27.461296) (xy 387.000524 -27.444833) (xy 387.002274 -27.435556) (xy 387.008633 -27.393572)
			(xy 387.028401 -27.310984) (xy 387.055948 -27.230655) (xy 387.091023 -27.153316) (xy 387.133307 -27.07967)
			(xy 387.182415 -27.010388) (xy 387.237901 -26.9461) (xy 387.299259 -26.88739) (xy 387.365931 -26.834794)
			(xy 387.437311 -26.788788) (xy 387.512749 -26.749793) (xy 387.59156 -26.718162) (xy 387.673025 -26.694184)
			(xy 387.756405 -26.678076) (xy 387.840939 -26.669985) (xy 387.8834 -26.669492) (xy 387.924502 -26.669967)
			(xy 388.006357 -26.677552) (xy 388.087162 -26.692657) (xy 388.166229 -26.715153) (xy 388.242883 -26.744849)
			(xy 388.31647 -26.781491) (xy 388.386362 -26.824766) (xy 388.451963 -26.874306) (xy 388.512713 -26.929687)
			(xy 388.568094 -26.990437) (xy 388.617634 -27.056038) (xy 388.660909 -27.12593) (xy 388.697551 -27.199517)
			(xy 388.727247 -27.276171) (xy 388.749743 -27.355238) (xy 388.764848 -27.436043) (xy 388.772433 -27.517898)
			(xy 388.772908 -27.559) (xy 388.772422 -27.60178) (xy 388.7642 -27.686944) (xy 388.747841 -27.770925)
			(xy 388.723497 -27.852948) (xy 388.691392 -27.932256) (xy 388.651824 -28.008117) (xy 388.605156 -28.079829)
			(xy 388.551821 -28.14673) (xy 388.49231 -28.208203) (xy 388.427174 -28.263681) (xy 388.357013 -28.312649)
			(xy 388.282476 -28.354658) (xy 388.204251 -28.389318) (xy 388.163816 -28.403296) (xy 388.155 -28.406667)
			(xy 388.140479 -28.418704) (xy 388.131276 -28.435167) (xy 388.129526 -28.444444) (xy 388.123167 -28.486428)
			(xy 388.103399 -28.569016) (xy 388.075852 -28.649345) (xy 388.040777 -28.726684) (xy 387.998493 -28.80033)
			(xy 387.949385 -28.869612) (xy 387.893899 -28.9339) (xy 387.832541 -28.99261) (xy 387.765869 -29.045206)
			(xy 387.694489 -29.091212) (xy 387.619051 -29.130207) (xy 387.54024 -29.161838) (xy 387.458775 -29.185816)
			(xy 387.375395 -29.201924) (xy 387.290861 -29.210015) (xy 387.2484 -29.210508) (xy 387.207298 -29.210033)
			(xy 387.125443 -29.202448) (xy 387.044638 -29.187343) (xy 386.965571 -29.164847) (xy 386.888917 -29.135151)
			(xy 386.81533 -29.098509) (xy 386.745438 -29.055234) (xy 386.679837 -29.005694) (xy 386.619087 -28.950313)
			(xy 386.563706 -28.889563) (xy 386.514166 -28.823962) (xy 386.470891 -28.75407) (xy 386.434249 -28.680483)
			(xy 386.404553 -28.603829) (xy 386.382057 -28.524762) (xy 386.366952 -28.443957) (xy 386.359367 -28.362102)
			(xy 386.358892 -28.321) (xy 379.816721 -28.321) (xy 379.807249 -28.365809) (xy 379.778716 -28.454103)
			(xy 379.76048 -28.496768) (xy 379.756651 -28.506703) (xy 379.756667 -28.527973) (xy 379.76048 -28.537916)
			(xy 379.778714 -28.580514) (xy 379.807229 -28.668683) (xy 379.826418 -28.75934) (xy 379.836074 -28.851501)
			(xy 379.83668 -28.897834) (xy 379.83668 -28.898342) (xy 379.836228 -28.939449) (xy 379.82864 -29.021312)
			(xy 379.813532 -29.102126) (xy 379.791035 -29.181202) (xy 379.76347 -29.252361) (xy 404.222962 -29.252361)
			(xy 404.222962 -29.167639) (xy 404.231015 -29.083302) (xy 404.247049 -29.000112) (xy 404.270917 -28.918822)
			(xy 404.302405 -28.84017) (xy 404.341227 -28.764867) (xy 404.38703 -28.693595) (xy 404.439401 -28.626999)
			(xy 404.497866 -28.565684) (xy 404.561894 -28.510203) (xy 404.630906 -28.46106) (xy 404.704276 -28.4187)
			(xy 404.781341 -28.383505) (xy 404.861403 -28.355796) (xy 404.943736 -28.335822) (xy 405.027595 -28.323765)
			(xy 405.11222 -28.319734) (xy 405.196845 -28.323765) (xy 405.280704 -28.335822) (xy 405.363037 -28.355796)
			(xy 405.443099 -28.383505) (xy 405.520164 -28.4187) (xy 405.593534 -28.46106) (xy 405.662546 -28.510203)
			(xy 405.726574 -28.565684) (xy 405.785039 -28.626999) (xy 405.83741 -28.693595) (xy 405.883213 -28.764867)
			(xy 405.922035 -28.84017) (xy 405.953523 -28.918822) (xy 405.977391 -29.000112) (xy 405.993425 -29.083302)
			(xy 406.001478 -29.167639) (xy 406.001982 -29.21) (xy 406.001478 -29.252361) (xy 405.993425 -29.336698)
			(xy 405.977391 -29.419888) (xy 405.953523 -29.501178) (xy 405.922035 -29.57983) (xy 405.883213 -29.655133)
			(xy 405.83741 -29.726405) (xy 405.785039 -29.793001) (xy 405.726574 -29.854316) (xy 405.662546 -29.909797)
			(xy 405.593534 -29.95894) (xy 405.520164 -30.0013) (xy 405.443099 -30.036495) (xy 405.363037 -30.064204)
			(xy 405.280704 -30.084178) (xy 405.196845 -30.096235) (xy 405.11222 -30.100267) (xy 405.027595 -30.096235)
			(xy 404.943736 -30.084178) (xy 404.861403 -30.064204) (xy 404.781341 -30.036495) (xy 404.704276 -30.0013)
			(xy 404.630906 -29.95894) (xy 404.561894 -29.909797) (xy 404.497866 -29.854316) (xy 404.439401 -29.793001)
			(xy 404.38703 -29.726405) (xy 404.341227 -29.655133) (xy 404.302405 -29.57983) (xy 404.270917 -29.501178)
			(xy 404.247049 -29.419888) (xy 404.231015 -29.336698) (xy 404.222962 -29.252361) (xy 379.76347 -29.252361)
			(xy 379.761338 -29.257865) (xy 379.724697 -29.331462) (xy 379.681422 -29.401365) (xy 379.631884 -29.466978)
			(xy 379.576504 -29.527741) (xy 379.515755 -29.583137) (xy 379.450155 -29.632692) (xy 379.380263 -29.675985)
			(xy 379.306675 -29.712645) (xy 379.23002 -29.742362) (xy 379.15095 -29.76488) (xy 379.07014 -29.780008)
			(xy 378.988279 -29.787617) (xy 378.947172 -29.788104) (xy 378.90077 -29.787489) (xy 378.808472 -29.777796)
			(xy 378.717686 -29.758539) (xy 378.629402 -29.729927) (xy 378.586746 -29.71165) (xy 378.576804 -29.707844)
			(xy 378.55554 -29.707844) (xy 378.545598 -29.71165) (xy 378.502941 -29.72992) (xy 378.414651 -29.758512)
			(xy 378.323867 -29.777767) (xy 378.231573 -29.787476) (xy 378.185172 -29.788104) (xy 378.13877 -29.787489)
			(xy 378.046472 -29.777796) (xy 377.955686 -29.758539) (xy 377.867402 -29.729927) (xy 377.824746 -29.71165)
			(xy 377.814804 -29.707844) (xy 377.79354 -29.707844) (xy 377.783598 -29.71165) (xy 377.740941 -29.72992)
			(xy 377.652651 -29.758512) (xy 377.561867 -29.777767) (xy 377.469573 -29.787476) (xy 377.423172 -29.788104)
			(xy 377.37677 -29.787489) (xy 377.284472 -29.777796) (xy 377.193686 -29.758539) (xy 377.105402 -29.729927)
			(xy 377.062746 -29.71165) (xy 377.052804 -29.707844) (xy 377.03154 -29.707844) (xy 377.021598 -29.71165)
			(xy 376.978941 -29.72992) (xy 376.890651 -29.758512) (xy 376.799867 -29.777767) (xy 376.707573 -29.787476)
			(xy 376.661172 -29.788104) (xy 376.620061 -29.787674) (xy 376.538189 -29.780084) (xy 376.457368 -29.764971)
			(xy 376.378286 -29.742463) (xy 376.301619 -29.712754) (xy 376.22802 -29.676096) (xy 376.158118 -29.632803)
			(xy 376.09251 -29.583244) (xy 376.031756 -29.527842) (xy 375.976373 -29.467069) (xy 375.926835 -29.401445)
			(xy 375.883564 -29.33153) (xy 375.84693 -29.25792) (xy 375.817246 -29.181243) (xy 375.794764 -29.102153)
			(xy 375.779677 -29.021327) (xy 375.772113 -28.939453) (xy 375.771664 -28.898342) (xy 367.919254 -28.898342)
			(xy 370.501926 -31.481014) (xy 370.502434 -31.481522) (xy 370.509813 -31.488111) (xy 370.528112 -31.495573)
			(xy 370.537994 -31.496) (xy 389.560308 -31.496) (xy 389.593568 -31.496522) (xy 389.659518 -31.50521)
			(xy 389.723768 -31.522436) (xy 389.785218 -31.547906) (xy 389.842816 -31.581183) (xy 389.895575 -31.621696)
			(xy 389.919464 -31.644844) (xy 390.320981 -32.046361) (xy 404.774142 -32.046361) (xy 404.774142 -31.961639)
			(xy 404.782195 -31.877302) (xy 404.798229 -31.794112) (xy 404.822097 -31.712822) (xy 404.853585 -31.63417)
			(xy 404.892407 -31.558867) (xy 404.93821 -31.487595) (xy 404.990581 -31.420999) (xy 405.049046 -31.359684)
			(xy 405.113074 -31.304203) (xy 405.182086 -31.25506) (xy 405.255456 -31.2127) (xy 405.332521 -31.177505)
			(xy 405.412583 -31.149796) (xy 405.494916 -31.129822) (xy 405.578775 -31.117765) (xy 405.6634 -31.113734)
			(xy 405.748025 -31.117765) (xy 405.831884 -31.129822) (xy 405.914217 -31.149796) (xy 405.994279 -31.177505)
			(xy 406.071344 -31.2127) (xy 406.144714 -31.25506) (xy 406.213726 -31.304203) (xy 406.277754 -31.359684)
			(xy 406.336219 -31.420999) (xy 406.38859 -31.487595) (xy 406.434393 -31.558867) (xy 406.473215 -31.63417)
			(xy 406.504703 -31.712822) (xy 406.515619 -31.75) (xy 409.091273 -31.75) (xy 409.095372 -31.664659)
			(xy 409.107631 -31.580104) (xy 409.127938 -31.497113) (xy 409.156106 -31.416451) (xy 409.191875 -31.33886)
			(xy 409.234915 -31.265053) (xy 409.284832 -31.195712) (xy 409.312618 -31.16326) (xy 409.318383 -31.156171)
			(xy 409.324895 -31.139114) (xy 409.325318 -31.129986) (xy 409.325318 -31.100014) (xy 409.324884 -31.090891)
			(xy 409.318364 -31.073841) (xy 409.312618 -31.06674) (xy 409.284832 -31.034288) (xy 409.234915 -30.964947)
			(xy 409.191875 -30.89114) (xy 409.156106 -30.813549) (xy 409.127938 -30.732887) (xy 409.107631 -30.649896)
			(xy 409.095372 -30.565341) (xy 409.091273 -30.48) (xy 409.095372 -30.394659) (xy 409.107631 -30.310104)
			(xy 409.127938 -30.227113) (xy 409.156106 -30.146451) (xy 409.191875 -30.06886) (xy 409.234915 -29.995053)
			(xy 409.284832 -29.925712) (xy 409.312618 -29.89326) (xy 409.318383 -29.886171) (xy 409.324895 -29.869114)
			(xy 409.325318 -29.859986) (xy 409.325318 -29.830014) (xy 409.324884 -29.820891) (xy 409.318364 -29.803841)
			(xy 409.312618 -29.79674) (xy 409.284832 -29.764288) (xy 409.234915 -29.694947) (xy 409.191875 -29.62114)
			(xy 409.156106 -29.543549) (xy 409.127938 -29.462887) (xy 409.107631 -29.379896) (xy 409.095372 -29.295341)
			(xy 409.091273 -29.21) (xy 409.095372 -29.124659) (xy 409.107631 -29.040104) (xy 409.127938 -28.957113)
			(xy 409.156106 -28.876451) (xy 409.191875 -28.79886) (xy 409.234915 -28.725053) (xy 409.284832 -28.655712)
			(xy 409.312618 -28.62326) (xy 409.318383 -28.616171) (xy 409.324895 -28.599114) (xy 409.325318 -28.589986)
			(xy 409.325318 -28.560014) (xy 409.324884 -28.550891) (xy 409.318364 -28.533841) (xy 409.312618 -28.52674)
			(xy 409.28656 -28.496326) (xy 409.239374 -28.431608) (xy 409.198198 -28.362908) (xy 409.163367 -28.290784)
			(xy 409.135163 -28.21582) (xy 409.113814 -28.138623) (xy 409.099494 -28.059819) (xy 409.092319 -27.980047)
			(xy 409.091892 -27.94) (xy 409.092396 -27.897652) (xy 409.100447 -27.813338) (xy 409.116476 -27.730172)
			(xy 409.140337 -27.648905) (xy 409.171816 -27.570275) (xy 409.210627 -27.494994) (xy 409.256417 -27.423742)
			(xy 409.308773 -27.357166) (xy 409.367221 -27.295868) (xy 409.431231 -27.240403) (xy 409.500223 -27.191274)
			(xy 409.573573 -27.148925) (xy 409.650616 -27.113741) (xy 409.730655 -27.086039) (xy 409.812964 -27.066071)
			(xy 409.896799 -27.054018) (xy 409.9814 -27.049988) (xy 410.066001 -27.054018) (xy 410.149836 -27.066071)
			(xy 410.232145 -27.086039) (xy 410.312184 -27.113741) (xy 410.389227 -27.148925) (xy 410.462577 -27.191274)
			(xy 410.531569 -27.240403) (xy 410.595579 -27.295868) (xy 410.654027 -27.357166) (xy 410.706383 -27.423742)
			(xy 410.752173 -27.494994) (xy 410.790984 -27.570275) (xy 410.822463 -27.648905) (xy 410.846324 -27.730172)
			(xy 410.862353 -27.813338) (xy 410.870404 -27.897652) (xy 410.870908 -27.94) (xy 410.870493 -27.980047)
			(xy 410.863298 -28.059816) (xy 410.848964 -28.138616) (xy 410.82761 -28.21581) (xy 410.799406 -28.290773)
			(xy 410.764582 -28.3629) (xy 410.723418 -28.431605) (xy 410.676249 -28.496335) (xy 410.650182 -28.52674)
			(xy 410.644417 -28.533829) (xy 410.637905 -28.550886) (xy 410.637482 -28.560014) (xy 410.637482 -28.589986)
			(xy 410.637916 -28.599109) (xy 410.644436 -28.616159) (xy 410.650182 -28.62326) (xy 410.677968 -28.655712)
			(xy 410.727885 -28.725053) (xy 410.770925 -28.79886) (xy 410.806694 -28.876451) (xy 410.834862 -28.957113)
			(xy 410.855169 -29.040104) (xy 410.867428 -29.124659) (xy 410.871527 -29.21) (xy 410.867428 -29.295341)
			(xy 410.855169 -29.379896) (xy 410.834862 -29.462887) (xy 410.806694 -29.543549) (xy 410.770925 -29.62114)
			(xy 410.727885 -29.694947) (xy 410.677968 -29.764288) (xy 410.650182 -29.79674) (xy 410.644417 -29.803829)
			(xy 410.637905 -29.820886) (xy 410.637482 -29.830014) (xy 410.637482 -29.859986) (xy 410.637916 -29.869109)
			(xy 410.644436 -29.886159) (xy 410.650182 -29.89326) (xy 410.677968 -29.925712) (xy 410.727885 -29.995053)
			(xy 410.770925 -30.06886) (xy 410.806694 -30.146451) (xy 410.829151 -30.21076) (xy 411.173168 -30.21076)
			(xy 411.173672 -30.168439) (xy 411.181747 -30.084182) (xy 411.19779 -30.001073) (xy 411.221657 -29.919865)
			(xy 411.253132 -29.841292) (xy 411.29193 -29.766064) (xy 411.314392 -29.730192) (xy 411.319291 -29.721815)
			(xy 411.322935 -29.702766) (xy 411.319266 -29.683722) (xy 411.314392 -29.675328) (xy 411.291934 -29.639455)
			(xy 411.253155 -29.564221) (xy 411.221693 -29.485645) (xy 411.19783 -29.404438) (xy 411.181783 -29.321333)
			(xy 411.173696 -29.23708) (xy 411.173168 -29.19476) (xy 411.173672 -29.152399) (xy 411.181725 -29.068062)
			(xy 411.197759 -28.984872) (xy 411.221627 -28.903582) (xy 411.253115 -28.82493) (xy 411.291937 -28.749627)
			(xy 411.33774 -28.678355) (xy 411.390111 -28.611759) (xy 411.448576 -28.550444) (xy 411.512604 -28.494963)
			(xy 411.581616 -28.44582) (xy 411.654986 -28.40346) (xy 411.732051 -28.368265) (xy 411.812113 -28.340556)
			(xy 411.894446 -28.320582) (xy 411.978305 -28.308525) (xy 412.06293 -28.304494) (xy 412.147555 -28.308525)
			(xy 412.231414 -28.320582) (xy 412.313747 -28.340556) (xy 412.393809 -28.368265) (xy 412.470874 -28.40346)
			(xy 412.544244 -28.44582) (xy 412.613256 -28.494963) (xy 412.677284 -28.550444) (xy 412.735749 -28.611759)
			(xy 412.78812 -28.678355) (xy 412.833923 -28.749627) (xy 412.872745 -28.82493) (xy 412.904233 -28.903582)
			(xy 412.928101 -28.984872) (xy 412.944135 -29.068062) (xy 412.952188 -29.152399) (xy 412.952692 -29.19476)
			(xy 412.952189 -29.237081) (xy 412.944113 -29.321338) (xy 412.928069 -29.404446) (xy 412.904202 -29.485655)
			(xy 412.872727 -29.564228) (xy 412.83393 -29.639456) (xy 412.811468 -29.675328) (xy 412.806638 -29.683739)
			(xy 412.802975 -29.702766) (xy 412.806613 -29.721798) (xy 412.811468 -29.730192) (xy 412.83393 -29.766063)
			(xy 412.872709 -29.841297) (xy 412.904171 -29.919873) (xy 412.928034 -30.001081) (xy 412.94408 -30.084186)
			(xy 412.952165 -30.16844) (xy 412.952692 -30.21076) (xy 412.952188 -30.253121) (xy 412.944135 -30.337458)
			(xy 412.928101 -30.420648) (xy 412.904233 -30.501938) (xy 412.872745 -30.58059) (xy 412.833923 -30.655893)
			(xy 412.78812 -30.727165) (xy 412.735749 -30.793761) (xy 412.677284 -30.855076) (xy 412.613256 -30.910557)
			(xy 412.544244 -30.9597) (xy 412.470874 -31.00206) (xy 412.393809 -31.037255) (xy 412.313747 -31.064964)
			(xy 412.231414 -31.084938) (xy 412.147555 -31.096995) (xy 412.06293 -31.101027) (xy 411.978305 -31.096995)
			(xy 411.894446 -31.084938) (xy 411.812113 -31.064964) (xy 411.732051 -31.037255) (xy 411.654986 -31.00206)
			(xy 411.581616 -30.9597) (xy 411.512604 -30.910557) (xy 411.448576 -30.855076) (xy 411.390111 -30.793761)
			(xy 411.33774 -30.727165) (xy 411.291937 -30.655893) (xy 411.253115 -30.58059) (xy 411.221627 -30.501938)
			(xy 411.197759 -30.420648) (xy 411.181725 -30.337458) (xy 411.173672 -30.253121) (xy 411.173168 -30.21076)
			(xy 410.829151 -30.21076) (xy 410.834862 -30.227113) (xy 410.855169 -30.310104) (xy 410.867428 -30.394659)
			(xy 410.871527 -30.48) (xy 410.867428 -30.565341) (xy 410.855169 -30.649896) (xy 410.834862 -30.732887)
			(xy 410.806694 -30.813549) (xy 410.770925 -30.89114) (xy 410.727885 -30.964947) (xy 410.677968 -31.034288)
			(xy 410.650182 -31.06674) (xy 410.644417 -31.073829) (xy 410.637905 -31.090886) (xy 410.637482 -31.100014)
			(xy 410.637482 -31.129986) (xy 410.637916 -31.139109) (xy 410.644436 -31.156159) (xy 410.650182 -31.16326)
			(xy 410.677968 -31.195712) (xy 410.705621 -31.234126) (xy 416.160966 -31.234126) (xy 416.161423 -31.193011)
			(xy 416.169008 -31.111131) (xy 416.184116 -31.0303) (xy 416.206618 -30.951208) (xy 416.236322 -30.87453)
			(xy 416.272975 -30.80092) (xy 416.316263 -30.731006) (xy 416.365818 -30.665384) (xy 416.421216 -30.604615)
			(xy 416.481985 -30.549217) (xy 416.547607 -30.499662) (xy 416.617521 -30.456374) (xy 416.691132 -30.419722)
			(xy 416.76781 -30.390018) (xy 416.846902 -30.367516) (xy 416.927733 -30.352408) (xy 417.009613 -30.344823)
			(xy 417.050728 -30.344364) (xy 417.094389 -30.344901) (xy 417.181287 -30.353487) (xy 417.266927 -30.370543)
			(xy 417.350484 -30.395906) (xy 417.431156 -30.429332) (xy 417.508164 -30.470499) (xy 417.58077 -30.519012)
			(xy 417.614862 -30.546294) (xy 417.623928 -30.552903) (xy 417.64567 -30.558316) (xy 417.656772 -30.556708)
			(xy 417.73348 -30.541722) (xy 417.744442 -30.539007) (xy 417.762647 -30.525704) (xy 417.768532 -30.516068)
			(xy 417.789672 -30.478128) (xy 417.838358 -30.406195) (xy 417.89382 -30.339348) (xy 417.955531 -30.278222)
			(xy 418.022903 -30.2234) (xy 418.095296 -30.175401) (xy 418.172021 -30.134684) (xy 418.252347 -30.101635)
			(xy 418.335511 -30.07657) (xy 418.420722 -30.059726) (xy 418.507168 -30.051263) (xy 418.550598 -30.05074)
			(xy 418.551106 -30.05074) (xy 418.596551 -30.051316) (xy 418.686967 -30.060585) (xy 418.775967 -30.079026)
			(xy 418.862623 -30.106446) (xy 418.94603 -30.14256) (xy 418.985954 -30.164278) (xy 418.996045 -30.169238)
			(xy 419.018447 -30.17082) (xy 419.029134 -30.167326) (xy 419.067652 -30.152877) (xy 419.146773 -30.130325)
			(xy 419.227641 -30.115185) (xy 419.309562 -30.107587) (xy 419.350698 -30.107128) (xy 419.35146 -30.107128)
			(xy 419.392564 -30.10759) (xy 419.47442 -30.115172) (xy 419.555228 -30.130275) (xy 419.634298 -30.15277)
			(xy 419.710954 -30.182464) (xy 419.784544 -30.219106) (xy 419.854438 -30.262381) (xy 419.920042 -30.311921)
			(xy 419.980794 -30.367304) (xy 420.036176 -30.428055) (xy 420.085717 -30.493658) (xy 420.128992 -30.563553)
			(xy 420.137978 -30.5816) (xy 423.239188 -30.5816) (xy 423.243218 -30.496999) (xy 423.255271 -30.413164)
			(xy 423.275239 -30.330855) (xy 423.302941 -30.250816) (xy 423.338125 -30.173773) (xy 423.380474 -30.100423)
			(xy 423.429603 -30.031431) (xy 423.485068 -29.967421) (xy 423.546366 -29.908973) (xy 423.612942 -29.856617)
			(xy 423.684194 -29.810827) (xy 423.759475 -29.772016) (xy 423.838105 -29.740537) (xy 423.919372 -29.716676)
			(xy 424.002538 -29.700647) (xy 424.086852 -29.692596) (xy 424.1292 -29.692092) (xy 424.129708 -29.692092)
			(xy 424.17604 -29.692698) (xy 424.268198 -29.702369) (xy 424.358852 -29.721565) (xy 424.447021 -29.750077)
			(xy 424.489626 -29.768292) (xy 424.499568 -29.772098) (xy 424.520832 -29.772098) (xy 424.530774 -29.768292)
			(xy 424.573436 -29.750047) (xy 424.661729 -29.721503) (xy 424.752514 -29.70231) (xy 424.844804 -29.692677)
			(xy 424.8912 -29.692092) (xy 424.937596 -29.692675) (xy 425.029884 -29.70232) (xy 425.120668 -29.721516)
			(xy 425.208961 -29.750054) (xy 425.251626 -29.768292) (xy 425.261568 -29.772098) (xy 425.282832 -29.772098)
			(xy 425.292774 -29.768292) (xy 425.335377 -29.75007) (xy 425.423544 -29.721552) (xy 425.5142 -29.70236)
			(xy 425.60636 -29.6927) (xy 425.652692 -29.692092) (xy 425.6532 -29.692092) (xy 425.697015 -29.692659)
			(xy 425.784221 -29.701274) (xy 425.870158 -29.71842) (xy 425.953993 -29.743931) (xy 426.034914 -29.77756)
			(xy 426.112137 -29.818981) (xy 426.184915 -29.867793) (xy 426.252541 -29.923524) (xy 426.31436 -29.985632)
			(xy 426.369775 -30.053517) (xy 426.418248 -30.12652) (xy 426.459309 -30.203935) (xy 426.492561 -30.285012)
			(xy 426.505624 -30.326838) (xy 426.508551 -30.335482) (xy 426.51951 -30.350061) (xy 426.534884 -30.359873)
			(xy 426.543724 -30.362144) (xy 426.6311 -30.380686) (xy 426.64001 -30.382162) (xy 426.657857 -30.379449)
			(xy 426.673675 -30.370752) (xy 426.679868 -30.364176) (xy 426.680122 -30.363922) (xy 426.708239 -30.33195)
			(xy 426.769631 -30.27295) (xy 426.836377 -30.220083) (xy 426.907867 -30.173832) (xy 426.983447 -30.134619)
			(xy 427.062427 -30.102805) (xy 427.144084 -30.078678) (xy 427.227672 -30.062461) (xy 427.312427 -30.0543)
			(xy 427.355 -30.053788) (xy 427.396111 -30.054252) (xy 427.477981 -30.06184) (xy 427.558801 -30.076951)
			(xy 427.637882 -30.099456) (xy 427.714549 -30.129162) (xy 427.788147 -30.165818) (xy 427.858049 -30.209108)
			(xy 427.861904 -30.21202) (xy 430.046497 -30.21202) (xy 430.051762 -30.128335) (xy 430.064879 -30.045517)
			(xy 430.085732 -29.9643) (xy 430.114136 -29.885407) (xy 430.149838 -29.809537) (xy 430.192521 -29.737363)
			(xy 430.241807 -29.669526) (xy 430.297259 -29.606629) (xy 430.358383 -29.549229) (xy 430.424638 -29.497837)
			(xy 430.495436 -29.452907) (xy 430.570147 -29.41484) (xy 430.648109 -29.383972) (xy 430.728631 -29.360579)
			(xy 430.810996 -29.344867) (xy 430.894475 -29.336976) (xy 430.9364 -29.336492) (xy 430.973664 -29.336847)
			(xy 431.047936 -29.342996) (xy 431.121433 -29.355335) (xy 431.157634 -29.364178) (xy 431.170588 -29.36748)
			(xy 431.196496 -29.360622) (xy 431.277522 -29.279596) (xy 431.28438 -29.253688) (xy 431.281078 -29.240734)
			(xy 431.272238 -29.204532) (xy 431.259893 -29.131036) (xy 431.25374 -29.056764) (xy 431.253392 -29.0195)
			(xy 431.253876 -28.977575) (xy 431.261767 -28.894096) (xy 431.277479 -28.811731) (xy 431.300872 -28.731209)
			(xy 431.33174 -28.653247) (xy 431.369807 -28.578536) (xy 431.414737 -28.507738) (xy 431.466129 -28.441483)
			(xy 431.523529 -28.380359) (xy 431.586426 -28.324907) (xy 431.654263 -28.275621) (xy 431.726437 -28.232938)
			(xy 431.802307 -28.197236) (xy 431.8812 -28.168832) (xy 431.962417 -28.147979) (xy 432.045235 -28.134862)
			(xy 432.12892 -28.129597) (xy 432.21273 -28.132231) (xy 432.295919 -28.14274) (xy 432.37775 -28.161032)
			(xy 432.457497 -28.186943) (xy 432.534451 -28.220244) (xy 432.60793 -28.26064) (xy 432.677282 -28.307771)
			(xy 432.74189 -28.361219) (xy 432.801181 -28.42051) (xy 432.854629 -28.485118) (xy 432.90176 -28.55447)
			(xy 432.942156 -28.627949) (xy 432.975457 -28.704903) (xy 433.001368 -28.78465) (xy 433.01966 -28.866481)
			(xy 433.030169 -28.94967) (xy 433.032803 -29.03348) (xy 433.029687 -29.083) (xy 434.34497 -29.083)
			(xy 434.349069 -28.997659) (xy 434.361328 -28.913104) (xy 434.381635 -28.830114) (xy 434.409803 -28.749451)
			(xy 434.445571 -28.67186) (xy 434.488612 -28.598054) (xy 434.538528 -28.528712) (xy 434.566314 -28.49626)
			(xy 434.572079 -28.489171) (xy 434.578591 -28.472113) (xy 434.579014 -28.462986) (xy 434.579014 -28.433014)
			(xy 434.578581 -28.423891) (xy 434.572061 -28.406841) (xy 434.566314 -28.39974) (xy 434.540256 -28.369327)
			(xy 434.493069 -28.304608) (xy 434.451894 -28.235908) (xy 434.417063 -28.163784) (xy 434.388859 -28.08882)
			(xy 434.36751 -28.011623) (xy 434.35319 -27.932819) (xy 434.346015 -27.853047) (xy 434.345588 -27.813)
			(xy 434.346067 -27.771898) (xy 434.353652 -27.690044) (xy 434.368757 -27.609238) (xy 434.391253 -27.530172)
			(xy 434.420949 -27.453518) (xy 434.45759 -27.379931) (xy 434.500865 -27.310039) (xy 434.550405 -27.244439)
			(xy 434.605786 -27.183688) (xy 434.666535 -27.128307) (xy 434.732136 -27.078768) (xy 434.802028 -27.035492)
			(xy 434.875614 -26.99885) (xy 434.952268 -26.969154) (xy 435.031335 -26.946657) (xy 435.11214 -26.931552)
			(xy 435.193994 -26.923967) (xy 435.235096 -26.923492) (xy 435.235858 -26.923492) (xy 435.27782 -26.924001)
			(xy 435.36137 -26.931921) (xy 435.443801 -26.947686) (xy 435.524378 -26.971154) (xy 435.602382 -27.002117)
			(xy 435.639972 -27.020774) (xy 435.640226 -27.020774) (xy 435.650658 -27.025444) (xy 435.673477 -27.026091)
			(xy 435.684168 -27.022044) (xy 435.766718 -26.984706) (xy 435.781704 -26.967434) (xy 435.784498 -26.956258)
			(xy 435.795522 -26.915975) (xy 435.82422 -26.837536) (xy 435.860142 -26.762133) (xy 435.902973 -26.690427)
			(xy 435.952336 -26.623051) (xy 436.007796 -26.560598) (xy 436.068865 -26.503617) (xy 436.135005 -26.45261)
			(xy 436.205634 -26.408026) (xy 436.28013 -26.370258) (xy 436.357838 -26.339637) (xy 436.438074 -26.316434)
			(xy 436.520132 -26.300852) (xy 436.603288 -26.293029) (xy 436.64505 -26.292556) (xy 436.686156 -26.29306)
			(xy 436.768019 -26.30064) (xy 436.848833 -26.31574) (xy 436.92791 -26.338232) (xy 437.004574 -26.367922)
			(xy 437.078173 -26.404559) (xy 437.148077 -26.447829) (xy 437.213691 -26.497364) (xy 437.274456 -26.552742)
			(xy 437.304203 -26.585361) (xy 437.819542 -26.585361) (xy 437.819542 -26.500639) (xy 437.827595 -26.416302)
			(xy 437.843629 -26.333112) (xy 437.867497 -26.251822) (xy 437.898985 -26.17317) (xy 437.937807 -26.097867)
			(xy 437.98361 -26.026595) (xy 438.035981 -25.959999) (xy 438.094446 -25.898684) (xy 438.158474 -25.843203)
			(xy 438.227486 -25.79406) (xy 438.300856 -25.7517) (xy 438.377921 -25.716505) (xy 438.457983 -25.688796)
			(xy 438.540316 -25.668822) (xy 438.624175 -25.656765) (xy 438.7088 -25.652734) (xy 438.793425 -25.656765)
			(xy 438.877284 -25.668822) (xy 438.959617 -25.688796) (xy 439.039679 -25.716505) (xy 439.116744 -25.7517)
			(xy 439.190114 -25.79406) (xy 439.259126 -25.843203) (xy 439.323154 -25.898684) (xy 439.381619 -25.959999)
			(xy 439.43399 -26.026595) (xy 439.479793 -26.097867) (xy 439.518615 -26.17317) (xy 439.550103 -26.251822)
			(xy 439.573971 -26.333112) (xy 439.590005 -26.416302) (xy 439.598058 -26.500639) (xy 439.598562 -26.543)
			(xy 439.598058 -26.585361) (xy 439.590005 -26.669698) (xy 439.573971 -26.752888) (xy 439.550103 -26.834178)
			(xy 439.518615 -26.91283) (xy 439.479793 -26.988133) (xy 439.43399 -27.059405) (xy 439.381619 -27.126001)
			(xy 439.323154 -27.187316) (xy 439.259126 -27.242797) (xy 439.190114 -27.29194) (xy 439.116744 -27.3343)
			(xy 439.039679 -27.369495) (xy 438.959617 -27.397204) (xy 438.877284 -27.417178) (xy 438.793425 -27.429235)
			(xy 438.7088 -27.433267) (xy 438.624175 -27.429235) (xy 438.540316 -27.417178) (xy 438.457983 -27.397204)
			(xy 438.377921 -27.369495) (xy 438.300856 -27.3343) (xy 438.227486 -27.29194) (xy 438.158474 -27.242797)
			(xy 438.094446 -27.187316) (xy 438.035981 -27.126001) (xy 437.98361 -27.059405) (xy 437.937807 -26.988133)
			(xy 437.898985 -26.91283) (xy 437.867497 -26.834178) (xy 437.843629 -26.752888) (xy 437.827595 -26.669698)
			(xy 437.819542 -26.585361) (xy 437.304203 -26.585361) (xy 437.329853 -26.613488) (xy 437.379409 -26.679087)
			(xy 437.422702 -26.748977) (xy 437.459362 -26.822564) (xy 437.489077 -26.899219) (xy 437.511594 -26.978288)
			(xy 437.52672 -27.059097) (xy 437.534326 -27.140958) (xy 437.534812 -27.182064) (xy 437.534317 -27.223122)
			(xy 437.526695 -27.304884) (xy 437.511577 -27.385597) (xy 437.489092 -27.464576) (xy 437.45943 -27.541148)
			(xy 437.422844 -27.614664) (xy 437.379644 -27.684499) (xy 437.330198 -27.75006) (xy 437.30291 -27.780742)
			(xy 437.296792 -27.787951) (xy 437.289971 -27.805575) (xy 437.28998 -27.824472) (xy 437.296818 -27.84209)
			(xy 437.30291 -27.849322) (xy 437.330222 -27.879986) (xy 437.379701 -27.94553) (xy 437.422924 -28.015358)
			(xy 437.459523 -28.088875) (xy 437.489185 -28.165454) (xy 437.511658 -28.244442) (xy 437.526751 -28.325166)
			(xy 437.534334 -28.406939) (xy 437.534812 -28.448) (xy 437.534348 -28.489111) (xy 437.52676 -28.570981)
			(xy 437.511649 -28.651801) (xy 437.489144 -28.730882) (xy 437.459438 -28.807549) (xy 437.422782 -28.881147)
			(xy 437.379492 -28.951049) (xy 437.329935 -29.016657) (xy 437.274535 -29.077412) (xy 437.213765 -29.132795)
			(xy 437.148143 -29.182333) (xy 437.078229 -29.225604) (xy 437.00462 -29.262239) (xy 436.927945 -29.291924)
			(xy 436.848858 -29.314406) (xy 436.768033 -29.329494) (xy 436.686161 -29.337059) (xy 436.64505 -29.337508)
			(xy 436.603093 -29.337049) (xy 436.51955 -29.32917) (xy 436.437122 -29.31345) (xy 436.356543 -29.290028)
			(xy 436.278532 -29.259113) (xy 436.240936 -29.24048) (xy 436.230776 -29.2354) (xy 436.207662 -29.234892)
			(xy 436.124858 -29.27223) (xy 436.114709 -29.277484) (xy 436.099942 -29.294889) (xy 436.09641 -29.305758)
			(xy 436.085538 -29.345875) (xy 436.057322 -29.424062) (xy 436.021932 -29.499275) (xy 435.979677 -29.570856)
			(xy 435.930926 -29.638181) (xy 435.903878 -29.66974) (xy 435.898079 -29.676884) (xy 435.891567 -29.694075)
			(xy 435.891178 -29.703268) (xy 435.891178 -29.732986) (xy 435.891613 -29.742109) (xy 435.898132 -29.759159)
			(xy 435.903878 -29.76626) (xy 435.929935 -29.796674) (xy 435.977122 -29.861393) (xy 436.018298 -29.930092)
			(xy 436.053129 -30.002216) (xy 436.081333 -30.07718) (xy 436.102682 -30.154377) (xy 436.117002 -30.233181)
			(xy 436.124177 -30.312953) (xy 436.124604 -30.353) (xy 436.1241 -30.395348) (xy 436.116049 -30.479662)
			(xy 436.10002 -30.562828) (xy 436.076159 -30.644095) (xy 436.04468 -30.722725) (xy 436.005869 -30.798006)
			(xy 435.960079 -30.869258) (xy 435.907723 -30.935834) (xy 435.849275 -30.997132) (xy 435.785265 -31.052597)
			(xy 435.716273 -31.101726) (xy 435.642923 -31.144075) (xy 435.56588 -31.179259) (xy 435.485841 -31.206961)
			(xy 435.403532 -31.226929) (xy 435.319697 -31.238982) (xy 435.235096 -31.243013) (xy 435.150495 -31.238982)
			(xy 435.06666 -31.226929) (xy 434.984351 -31.206961) (xy 434.904312 -31.179259) (xy 434.827269 -31.144075)
			(xy 434.753919 -31.101726) (xy 434.684927 -31.052597) (xy 434.620917 -30.997132) (xy 434.562469 -30.935834)
			(xy 434.510113 -30.869258) (xy 434.464323 -30.798006) (xy 434.425512 -30.722725) (xy 434.394033 -30.644095)
			(xy 434.370172 -30.562828) (xy 434.354143 -30.479662) (xy 434.346092 -30.395348) (xy 434.345588 -30.353)
			(xy 434.346004 -30.312953) (xy 434.353199 -30.233184) (xy 434.367532 -30.154384) (xy 434.388887 -30.07719)
			(xy 434.417091 -30.002227) (xy 434.451915 -29.930101) (xy 434.493078 -29.861395) (xy 434.540247 -29.796665)
			(xy 434.566314 -29.76626) (xy 434.572079 -29.759171) (xy 434.578591 -29.742113) (xy 434.579014 -29.732986)
			(xy 434.579014 -29.703014) (xy 434.578581 -29.693891) (xy 434.572061 -29.676841) (xy 434.566314 -29.66974)
			(xy 434.538528 -29.637288) (xy 434.488612 -29.567946) (xy 434.445571 -29.49414) (xy 434.409803 -29.416549)
			(xy 434.381635 -29.335886) (xy 434.361328 -29.252896) (xy 434.349069 -29.168341) (xy 434.34497 -29.083)
			(xy 433.029687 -29.083) (xy 433.027538 -29.117165) (xy 433.014421 -29.199983) (xy 432.993568 -29.2812)
			(xy 432.965164 -29.360093) (xy 432.929462 -29.435963) (xy 432.886779 -29.508137) (xy 432.837493 -29.575974)
			(xy 432.782041 -29.638871) (xy 432.720917 -29.696271) (xy 432.654662 -29.747663) (xy 432.583864 -29.792593)
			(xy 432.509153 -29.83066) (xy 432.431191 -29.861528) (xy 432.350669 -29.884921) (xy 432.268304 -29.900633)
			(xy 432.184825 -29.908524) (xy 432.1429 -29.909008) (xy 432.105636 -29.908653) (xy 432.031364 -29.902504)
			(xy 431.957867 -29.890165) (xy 431.921666 -29.881322) (xy 431.908712 -29.87802) (xy 431.882804 -29.884878)
			(xy 431.801778 -29.965904) (xy 431.79492 -29.991812) (xy 431.798222 -30.004766) (xy 431.807062 -30.040968)
			(xy 431.819407 -30.114464) (xy 431.82556 -30.188736) (xy 431.825908 -30.226) (xy 431.825424 -30.267925)
			(xy 431.817533 -30.351404) (xy 431.801821 -30.433769) (xy 431.778428 -30.514291) (xy 431.74756 -30.592253)
			(xy 431.709493 -30.666964) (xy 431.664563 -30.737762) (xy 431.613171 -30.804017) (xy 431.555771 -30.865141)
			(xy 431.492874 -30.920593) (xy 431.425037 -30.969879) (xy 431.352863 -31.012562) (xy 431.276993 -31.048264)
			(xy 431.1981 -31.076668) (xy 431.116883 -31.097521) (xy 431.034065 -31.110638) (xy 430.95038 -31.115903)
			(xy 430.86657 -31.113269) (xy 430.783381 -31.10276) (xy 430.70155 -31.084468) (xy 430.621803 -31.058557)
			(xy 430.544849 -31.025256) (xy 430.47137 -30.98486) (xy 430.402018 -30.937729) (xy 430.33741 -30.884281)
			(xy 430.278119 -30.82499) (xy 430.224671 -30.760382) (xy 430.17754 -30.69103) (xy 430.137144 -30.617551)
			(xy 430.103843 -30.540597) (xy 430.077932 -30.46085) (xy 430.05964 -30.379019) (xy 430.049131 -30.29583)
			(xy 430.046497 -30.21202) (xy 427.861904 -30.21202) (xy 427.923657 -30.258665) (xy 427.984412 -30.314065)
			(xy 428.039795 -30.374835) (xy 428.089333 -30.440457) (xy 428.132604 -30.510371) (xy 428.169239 -30.58398)
			(xy 428.198924 -30.660655) (xy 428.221406 -30.739742) (xy 428.236494 -30.820567) (xy 428.244059 -30.902439)
			(xy 428.244508 -30.94355) (xy 428.243952 -30.987801) (xy 428.235174 -31.075868) (xy 428.217698 -31.162628)
			(xy 428.191698 -31.247226) (xy 428.15743 -31.328826) (xy 428.136812 -31.367984) (xy 428.136812 -31.368238)
			(xy 428.131832 -31.378857) (xy 428.131028 -31.40227) (xy 428.135288 -31.413196) (xy 428.169324 -31.487364)
			(xy 428.174744 -31.497823) (xy 428.193028 -31.512641) (xy 428.204376 -31.515812) (xy 428.204884 -31.515812)
			(xy 428.246543 -31.525444) (xy 428.327941 -31.55164) (xy 428.406454 -31.585517) (xy 428.481359 -31.626761)
			(xy 428.551968 -31.674994) (xy 428.585122 -31.701994) (xy 428.592489 -31.707555) (xy 428.609929 -31.713552)
			(xy 428.619158 -31.713678) (xy 428.648876 -31.712916) (xy 428.658005 -31.712302) (xy 428.674932 -31.705389)
			(xy 428.681896 -31.699454) (xy 428.712689 -31.671687) (xy 428.778586 -31.621354) (xy 428.848881 -31.577371)
			(xy 428.922964 -31.54012) (xy 429.000191 -31.509924) (xy 429.079893 -31.487044) (xy 429.161378 -31.47168)
			(xy 429.24394 -31.463965) (xy 429.2854 -31.463488) (xy 429.327763 -31.463892) (xy 429.412105 -31.471946)
			(xy 429.4953 -31.48798) (xy 429.576594 -31.51185) (xy 429.655251 -31.54334) (xy 429.730558 -31.582163)
			(xy 429.801834 -31.62797) (xy 429.849381 -31.665361) (xy 440.562742 -31.665361) (xy 440.562742 -31.580639)
			(xy 440.570795 -31.496302) (xy 440.586829 -31.413112) (xy 440.610697 -31.331822) (xy 440.642185 -31.25317)
			(xy 440.681007 -31.177867) (xy 440.72681 -31.106595) (xy 440.779181 -31.039999) (xy 440.837646 -30.978684)
			(xy 440.901674 -30.923203) (xy 440.970686 -30.87406) (xy 441.044056 -30.8317) (xy 441.121121 -30.796505)
			(xy 441.201183 -30.768796) (xy 441.283516 -30.748822) (xy 441.367375 -30.736765) (xy 441.452 -30.732734)
			(xy 441.536625 -30.736765) (xy 441.620484 -30.748822) (xy 441.702817 -30.768796) (xy 441.782879 -30.796505)
			(xy 441.859944 -30.8317) (xy 441.933314 -30.87406) (xy 442.002326 -30.923203) (xy 442.066354 -30.978684)
			(xy 442.124819 -31.039999) (xy 442.17719 -31.106595) (xy 442.222993 -31.177867) (xy 442.261815 -31.25317)
			(xy 442.293303 -31.331822) (xy 442.317171 -31.413112) (xy 442.333205 -31.496302) (xy 442.341258 -31.580639)
			(xy 442.341762 -31.623) (xy 442.341258 -31.665361) (xy 442.333205 -31.749698) (xy 442.317171 -31.832888)
			(xy 442.293303 -31.914178) (xy 442.261815 -31.99283) (xy 442.222993 -32.068133) (xy 442.17719 -32.139405)
			(xy 442.124819 -32.206001) (xy 442.066354 -32.267316) (xy 442.002326 -32.322797) (xy 441.933314 -32.37194)
			(xy 441.859944 -32.4143) (xy 441.782879 -32.449495) (xy 441.702817 -32.477204) (xy 441.620484 -32.497178)
			(xy 441.536625 -32.509235) (xy 441.452 -32.513267) (xy 441.367375 -32.509235) (xy 441.283516 -32.497178)
			(xy 441.201183 -32.477204) (xy 441.121121 -32.449495) (xy 441.044056 -32.4143) (xy 440.970686 -32.37194)
			(xy 440.901674 -32.322797) (xy 440.837646 -32.267316) (xy 440.779181 -32.206001) (xy 440.72681 -32.139405)
			(xy 440.681007 -32.068133) (xy 440.642185 -31.99283) (xy 440.610697 -31.914178) (xy 440.586829 -31.832888)
			(xy 440.570795 -31.749698) (xy 440.562742 -31.665361) (xy 429.849381 -31.665361) (xy 429.868433 -31.680344)
			(xy 429.929752 -31.738811) (xy 429.985236 -31.802843) (xy 430.034382 -31.871859) (xy 430.076745 -31.945233)
			(xy 430.111941 -32.022303) (xy 430.139652 -32.102369) (xy 430.159627 -32.184706) (xy 430.171685 -32.26857)
			(xy 430.175717 -32.3532) (xy 430.171685 -32.43783) (xy 430.159627 -32.521694) (xy 430.139652 -32.604031)
			(xy 430.111941 -32.684097) (xy 430.076745 -32.761167) (xy 430.034382 -32.834541) (xy 429.985236 -32.903557)
			(xy 429.957678 -32.935361) (xy 431.552092 -32.935361) (xy 431.552092 -32.850639) (xy 431.560145 -32.766302)
			(xy 431.576179 -32.683112) (xy 431.600047 -32.601822) (xy 431.631535 -32.52317) (xy 431.670357 -32.447867)
			(xy 431.71616 -32.376595) (xy 431.768531 -32.309999) (xy 431.826996 -32.248684) (xy 431.891024 -32.193203)
			(xy 431.960036 -32.14406) (xy 432.033406 -32.1017) (xy 432.110471 -32.066505) (xy 432.190533 -32.038796)
			(xy 432.272866 -32.018822) (xy 432.356725 -32.006765) (xy 432.44135 -32.002734) (xy 432.525975 -32.006765)
			(xy 432.609834 -32.018822) (xy 432.692167 -32.038796) (xy 432.772229 -32.066505) (xy 432.849294 -32.1017)
			(xy 432.922664 -32.14406) (xy 432.991676 -32.193203) (xy 433.055704 -32.248684) (xy 433.114169 -32.309999)
			(xy 433.16654 -32.376595) (xy 433.212343 -32.447867) (xy 433.251165 -32.52317) (xy 433.282653 -32.601822)
			(xy 433.306521 -32.683112) (xy 433.322555 -32.766302) (xy 433.330608 -32.850639) (xy 433.331112 -32.893)
			(xy 433.330608 -32.935361) (xy 433.322555 -33.019698) (xy 433.306521 -33.102888) (xy 433.282653 -33.184178)
			(xy 433.251165 -33.26283) (xy 433.212343 -33.338133) (xy 433.16654 -33.409405) (xy 433.114169 -33.476001)
			(xy 433.055704 -33.537316) (xy 432.991676 -33.592797) (xy 432.922664 -33.64194) (xy 432.849294 -33.6843)
			(xy 432.772229 -33.719495) (xy 432.692167 -33.747204) (xy 432.609834 -33.767178) (xy 432.525975 -33.779235)
			(xy 432.44135 -33.783267) (xy 432.356725 -33.779235) (xy 432.272866 -33.767178) (xy 432.190533 -33.747204)
			(xy 432.110471 -33.719495) (xy 432.033406 -33.6843) (xy 431.960036 -33.64194) (xy 431.891024 -33.592797)
			(xy 431.826996 -33.537316) (xy 431.768531 -33.476001) (xy 431.71616 -33.409405) (xy 431.670357 -33.338133)
			(xy 431.631535 -33.26283) (xy 431.600047 -33.184178) (xy 431.576179 -33.102888) (xy 431.560145 -33.019698)
			(xy 431.552092 -32.935361) (xy 429.957678 -32.935361) (xy 429.929752 -32.967589) (xy 429.868433 -33.026056)
			(xy 429.801834 -33.07843) (xy 429.730558 -33.124237) (xy 429.655251 -33.16306) (xy 429.576594 -33.19455)
			(xy 429.4953 -33.21842) (xy 429.412105 -33.234454) (xy 429.327763 -33.242508) (xy 429.2854 -33.243012)
			(xy 429.241214 -33.242461) (xy 429.153281 -33.233664) (xy 429.066654 -33.216187) (xy 428.982188 -33.190201)
			(xy 428.900718 -33.155965) (xy 428.823045 -33.113814) (xy 428.749938 -33.064166) (xy 428.715678 -33.036256)
			(xy 428.708315 -33.03069) (xy 428.690871 -33.024697) (xy 428.681642 -33.024572) (xy 428.651924 -33.025334)
			(xy 428.642794 -33.025936) (xy 428.625866 -33.032856) (xy 428.618904 -33.038796) (xy 428.615094 -33.042098)
			(xy 428.607775 -33.049523) (xy 428.599247 -33.068524) (xy 428.598584 -33.078928) (xy 428.597822 -33.109916)
			(xy 428.598158 -33.120269) (xy 428.606012 -33.139413) (xy 428.613062 -33.147) (xy 428.644198 -33.178338)
			(xy 428.700815 -33.246156) (xy 428.750427 -33.319254) (xy 428.792545 -33.396913) (xy 428.826753 -33.478366)
			(xy 428.852714 -33.56281) (xy 428.870171 -33.649413) (xy 428.878954 -33.73732) (xy 428.879508 -33.781492)
			(xy 428.879508 -33.782) (xy 428.879004 -33.824348) (xy 428.870953 -33.908662) (xy 428.854924 -33.991828)
			(xy 428.831063 -34.073095) (xy 428.799584 -34.151725) (xy 428.760773 -34.227006) (xy 428.714983 -34.298258)
			(xy 428.662627 -34.364834) (xy 428.604179 -34.426132) (xy 428.540169 -34.481597) (xy 428.471177 -34.530726)
			(xy 428.397827 -34.573075) (xy 428.382639 -34.580011) (xy 429.031142 -34.580011) (xy 429.031142 -34.495289)
			(xy 429.039195 -34.410952) (xy 429.055229 -34.327762) (xy 429.079097 -34.246472) (xy 429.110585 -34.16782)
			(xy 429.149407 -34.092517) (xy 429.19521 -34.021245) (xy 429.247581 -33.954649) (xy 429.306046 -33.893334)
			(xy 429.370074 -33.837853) (xy 429.439086 -33.78871) (xy 429.512456 -33.74635) (xy 429.589521 -33.711155)
			(xy 429.669583 -33.683446) (xy 429.751916 -33.663472) (xy 429.835775 -33.651415) (xy 429.9204 -33.647384)
			(xy 430.005025 -33.651415) (xy 430.088884 -33.663472) (xy 430.171217 -33.683446) (xy 430.251279 -33.711155)
			(xy 430.328344 -33.74635) (xy 430.401714 -33.78871) (xy 430.470726 -33.837853) (xy 430.534754 -33.893334)
			(xy 430.593219 -33.954649) (xy 430.64559 -34.021245) (xy 430.691393 -34.092517) (xy 430.72773 -34.163)
			(xy 434.345588 -34.163) (xy 434.34606 -34.122949) (xy 434.353283 -34.043173) (xy 434.367643 -33.964368)
			(xy 434.389025 -33.887172) (xy 434.417255 -33.812209) (xy 434.452106 -33.740085) (xy 434.493295 -33.671384)
			(xy 434.540489 -33.60666) (xy 434.566568 -33.57626) (xy 434.572372 -33.569121) (xy 434.57888 -33.551925)
			(xy 434.579268 -33.542732) (xy 434.579268 -33.513268) (xy 434.578858 -33.504081) (xy 434.572343 -33.486897)
			(xy 434.566568 -33.47974) (xy 434.540484 -33.449341) (xy 434.493259 -33.384634) (xy 434.452047 -33.31594)
			(xy 434.417181 -33.243818) (xy 434.388945 -33.168852) (xy 434.367568 -33.09165) (xy 434.353222 -33.012837)
			(xy 434.346025 -32.933054) (xy 434.345588 -32.893) (xy 434.346092 -32.850639) (xy 434.354145 -32.766302)
			(xy 434.370179 -32.683112) (xy 434.394047 -32.601822) (xy 434.425535 -32.52317) (xy 434.464357 -32.447867)
			(xy 434.51016 -32.376595) (xy 434.562531 -32.309999) (xy 434.620996 -32.248684) (xy 434.685024 -32.193203)
			(xy 434.754036 -32.14406) (xy 434.827406 -32.1017) (xy 434.904471 -32.066505) (xy 434.984533 -32.038796)
			(xy 435.066866 -32.018822) (xy 435.150725 -32.006765) (xy 435.23535 -32.002734) (xy 435.319975 -32.006765)
			(xy 435.403834 -32.018822) (xy 435.486167 -32.038796) (xy 435.566229 -32.066505) (xy 435.643294 -32.1017)
			(xy 435.716664 -32.14406) (xy 435.785676 -32.193203) (xy 435.849704 -32.248684) (xy 435.908169 -32.309999)
			(xy 435.96054 -32.376595) (xy 436.006343 -32.447867) (xy 436.045165 -32.52317) (xy 436.076653 -32.601822)
			(xy 436.100521 -32.683112) (xy 436.116555 -32.766302) (xy 436.124608 -32.850639) (xy 436.125112 -32.893)
			(xy 436.12464 -32.933051) (xy 436.117417 -33.012827) (xy 436.103057 -33.091632) (xy 436.081675 -33.168828)
			(xy 436.053445 -33.243791) (xy 436.018594 -33.315915) (xy 435.977405 -33.384616) (xy 435.930211 -33.44934)
			(xy 435.904132 -33.47974) (xy 435.898328 -33.486879) (xy 435.89182 -33.504075) (xy 435.891432 -33.513268)
			(xy 435.891432 -33.542732) (xy 435.891842 -33.551919) (xy 435.898357 -33.569103) (xy 435.904132 -33.57626)
			(xy 435.930216 -33.606659) (xy 435.977441 -33.671366) (xy 436.018653 -33.74006) (xy 436.053519 -33.812182)
			(xy 436.081755 -33.887148) (xy 436.103132 -33.96435) (xy 436.117478 -34.043163) (xy 436.124675 -34.122946)
			(xy 436.125112 -34.163) (xy 436.124608 -34.205361) (xy 436.116555 -34.289698) (xy 436.100521 -34.372888)
			(xy 436.076653 -34.454178) (xy 436.045165 -34.53283) (xy 436.006343 -34.608133) (xy 435.96054 -34.679405)
			(xy 435.908169 -34.746001) (xy 435.849704 -34.807316) (xy 435.785676 -34.862797) (xy 435.716664 -34.91194)
			(xy 435.643294 -34.9543) (xy 435.566229 -34.989495) (xy 435.486167 -35.017204) (xy 435.403834 -35.037178)
			(xy 435.319975 -35.049235) (xy 435.23535 -35.053267) (xy 435.150725 -35.049235) (xy 435.066866 -35.037178)
			(xy 434.984533 -35.017204) (xy 434.904471 -34.989495) (xy 434.827406 -34.9543) (xy 434.754036 -34.91194)
			(xy 434.685024 -34.862797) (xy 434.620996 -34.807316) (xy 434.562531 -34.746001) (xy 434.51016 -34.679405)
			(xy 434.464357 -34.608133) (xy 434.425535 -34.53283) (xy 434.394047 -34.454178) (xy 434.370179 -34.372888)
			(xy 434.354145 -34.289698) (xy 434.346092 -34.205361) (xy 434.345588 -34.163) (xy 430.72773 -34.163)
			(xy 430.730215 -34.16782) (xy 430.761703 -34.246472) (xy 430.785571 -34.327762) (xy 430.801605 -34.410952)
			(xy 430.809658 -34.495289) (xy 430.810162 -34.53765) (xy 430.809658 -34.580011) (xy 430.801605 -34.664348)
			(xy 430.785571 -34.747538) (xy 430.761703 -34.828828) (xy 430.730215 -34.90748) (xy 430.691393 -34.982783)
			(xy 430.64559 -35.054055) (xy 430.593219 -35.120651) (xy 430.534754 -35.181966) (xy 430.470726 -35.237447)
			(xy 430.401714 -35.28659) (xy 430.328344 -35.32895) (xy 430.251279 -35.364145) (xy 430.171217 -35.391854)
			(xy 430.088884 -35.411828) (xy 430.005025 -35.423885) (xy 429.9204 -35.427917) (xy 429.835775 -35.423885)
			(xy 429.751916 -35.411828) (xy 429.669583 -35.391854) (xy 429.589521 -35.364145) (xy 429.512456 -35.32895)
			(xy 429.439086 -35.28659) (xy 429.370074 -35.237447) (xy 429.306046 -35.181966) (xy 429.247581 -35.120651)
			(xy 429.19521 -35.054055) (xy 429.149407 -34.982783) (xy 429.110585 -34.90748) (xy 429.079097 -34.828828)
			(xy 429.055229 -34.747538) (xy 429.039195 -34.664348) (xy 429.031142 -34.580011) (xy 428.382639 -34.580011)
			(xy 428.320784 -34.608259) (xy 428.240745 -34.635961) (xy 428.158436 -34.655929) (xy 428.074601 -34.667982)
			(xy 427.99 -34.672013) (xy 427.905399 -34.667982) (xy 427.821564 -34.655929) (xy 427.739255 -34.635961)
			(xy 427.659216 -34.608259) (xy 427.582173 -34.573075) (xy 427.508823 -34.530726) (xy 427.439831 -34.481597)
			(xy 427.375821 -34.426132) (xy 427.317373 -34.364834) (xy 427.265017 -34.298258) (xy 427.219227 -34.227006)
			(xy 427.180416 -34.151725) (xy 427.148937 -34.073095) (xy 427.125076 -33.991828) (xy 427.109047 -33.908662)
			(xy 427.100996 -33.824348) (xy 427.100492 -33.782) (xy 427.101038 -33.737496) (xy 427.109928 -33.648933)
			(xy 427.127618 -33.5617) (xy 427.153933 -33.476671) (xy 427.188608 -33.394694) (xy 427.231298 -33.316591)
			(xy 427.281574 -33.243142) (xy 427.338935 -33.175082) (xy 427.370494 -33.143698) (xy 427.370748 -33.143444)
			(xy 427.377394 -33.136141) (xy 427.385117 -33.117991) (xy 427.385734 -33.108138) (xy 427.387258 -33.03651)
			(xy 427.386965 -33.026611) (xy 427.379775 -33.008179) (xy 427.373288 -33.000696) (xy 427.373034 -33.000442)
			(xy 427.343996 -32.969428) (xy 427.291358 -32.902728) (xy 427.245315 -32.831317) (xy 427.206286 -32.755843)
			(xy 427.174626 -32.676994) (xy 427.150623 -32.595487) (xy 427.134495 -32.512064) (xy 427.12639 -32.427484)
			(xy 427.125892 -32.385) (xy 427.126426 -32.340748) (xy 427.13521 -32.252681) (xy 427.15269 -32.16592)
			(xy 427.178695 -32.081323) (xy 427.212967 -31.999724) (xy 427.233588 -31.960566) (xy 427.233588 -31.960312)
			(xy 427.2386 -31.949705) (xy 427.239384 -31.926281) (xy 427.235112 -31.915354) (xy 427.201076 -31.841186)
			(xy 427.19564 -31.830736) (xy 427.177368 -31.815912) (xy 427.166024 -31.812738) (xy 427.165516 -31.812738)
			(xy 427.123497 -31.803099) (xy 427.041428 -31.776686) (xy 426.9623 -31.742456) (xy 426.886854 -31.70073)
			(xy 426.815801 -31.6519) (xy 426.749805 -31.596424) (xy 426.689487 -31.534823) (xy 426.635412 -31.467674)
			(xy 426.588088 -31.395608) (xy 426.54796 -31.319301) (xy 426.515403 -31.23947) (xy 426.502576 -31.198312)
			(xy 426.499674 -31.189658) (xy 426.488702 -31.175083) (xy 426.473319 -31.165275) (xy 426.464476 -31.163006)
			(xy 426.3771 -31.144464) (xy 426.368191 -31.142971) (xy 426.350341 -31.145687) (xy 426.334522 -31.154393)
			(xy 426.328332 -31.160974) (xy 426.328078 -31.161228) (xy 426.299973 -31.193202) (xy 426.238569 -31.252174)
			(xy 426.171813 -31.305011) (xy 426.100317 -31.351232) (xy 426.024733 -31.390413) (xy 425.945752 -31.422197)
			(xy 425.864097 -31.446292) (xy 425.780515 -31.462479) (xy 425.695768 -31.47061) (xy 425.6532 -31.471108)
			(xy 425.652692 -31.471108) (xy 425.60636 -31.470502) (xy 425.514202 -31.460831) (xy 425.423548 -31.441635)
			(xy 425.335379 -31.413123) (xy 425.292774 -31.394908) (xy 425.282832 -31.391102) (xy 425.261568 -31.391102)
			(xy 425.251626 -31.394908) (xy 425.208964 -31.413153) (xy 425.120671 -31.441697) (xy 425.029886 -31.46089)
			(xy 424.937596 -31.470523) (xy 424.8912 -31.471108) (xy 424.844804 -31.470525) (xy 424.752516 -31.46088)
			(xy 424.661732 -31.441684) (xy 424.573439 -31.413146) (xy 424.530774 -31.394908) (xy 424.520832 -31.391102)
			(xy 424.499568 -31.391102) (xy 424.489626 -31.394908) (xy 424.447023 -31.41313) (xy 424.358856 -31.441648)
			(xy 424.2682 -31.46084) (xy 424.17604 -31.4705) (xy 424.129708 -31.471108) (xy 424.1292 -31.471108)
			(xy 424.086852 -31.470604) (xy 424.002538 -31.462553) (xy 423.919372 -31.446524) (xy 423.838105 -31.422663)
			(xy 423.759475 -31.391184) (xy 423.684194 -31.352373) (xy 423.612942 -31.306583) (xy 423.546366 -31.254227)
			(xy 423.485068 -31.195779) (xy 423.429603 -31.131769) (xy 423.380474 -31.062777) (xy 423.338125 -30.989427)
			(xy 423.302941 -30.912384) (xy 423.275239 -30.832345) (xy 423.255271 -30.750036) (xy 423.243218 -30.666201)
			(xy 423.239188 -30.5816) (xy 420.137978 -30.5816) (xy 420.165634 -30.637142) (xy 420.195329 -30.713798)
			(xy 420.217824 -30.792868) (xy 420.232927 -30.873676) (xy 420.240509 -30.955532) (xy 420.240968 -30.996636)
			(xy 420.240968 -30.997144) (xy 420.240385 -31.043988) (xy 420.230558 -31.137158) (xy 420.210995 -31.22878)
			(xy 420.197026 -31.273496) (xy 420.194123 -31.283971) (xy 420.196492 -31.305556) (xy 420.201598 -31.315152)
			(xy 420.224785 -31.35539) (xy 420.263597 -31.439766) (xy 420.279068 -31.483554) (xy 420.28237 -31.493714)
			(xy 420.296848 -31.509462) (xy 420.386256 -31.547816) (xy 420.4081 -31.547562) (xy 420.417752 -31.54299)
			(xy 420.452884 -31.527213) (xy 420.525332 -31.501071) (xy 420.599769 -31.48129) (xy 420.675637 -31.46802)
			(xy 420.752368 -31.461359) (xy 420.790878 -31.460948) (xy 420.83324 -31.461415) (xy 420.917582 -31.469467)
			(xy 421.000776 -31.4855) (xy 421.08207 -31.509368) (xy 421.160726 -31.540855) (xy 421.236033 -31.579677)
			(xy 421.307309 -31.625482) (xy 421.373908 -31.677854) (xy 421.435227 -31.73632) (xy 421.490711 -31.800351)
			(xy 421.539857 -31.869365) (xy 421.58222 -31.942739) (xy 421.617417 -32.019807) (xy 421.645128 -32.099872)
			(xy 421.665103 -32.182209) (xy 421.677161 -32.266071) (xy 421.681192 -32.3507) (xy 421.677161 -32.435329)
			(xy 421.665103 -32.519191) (xy 421.645128 -32.601528) (xy 421.617417 -32.681593) (xy 421.58222 -32.758661)
			(xy 421.539857 -32.832035) (xy 421.490711 -32.901049) (xy 421.435227 -32.96508) (xy 421.373908 -33.023546)
			(xy 421.307309 -33.075918) (xy 421.236033 -33.121723) (xy 421.160726 -33.160545) (xy 421.08207 -33.192032)
			(xy 421.000776 -33.2159) (xy 420.917582 -33.231933) (xy 420.83324 -33.239985) (xy 420.790878 -33.240472)
			(xy 420.748304 -33.239973) (xy 420.663545 -33.231852) (xy 420.57995 -33.215667) (xy 420.498285 -33.191568)
			(xy 420.419297 -33.159773) (xy 420.343709 -33.120575) (xy 420.272213 -33.074332) (xy 420.205465 -33.021467)
			(xy 420.144074 -32.962465) (xy 420.088604 -32.897866) (xy 420.039561 -32.828261) (xy 419.997395 -32.754287)
			(xy 419.962493 -32.676622) (xy 419.94836 -32.63646) (xy 419.945058 -32.6263) (xy 419.93058 -32.610552)
			(xy 419.841172 -32.572198) (xy 419.819328 -32.572452) (xy 419.809676 -32.577024) (xy 419.774632 -32.592735)
			(xy 419.702373 -32.618768) (xy 419.62814 -32.638477) (xy 419.552484 -32.651715) (xy 419.475968 -32.658383)
			(xy 419.437566 -32.658812) (xy 419.43655 -32.658812) (xy 419.394299 -32.658317) (xy 419.310177 -32.650318)
			(xy 419.227193 -32.634379) (xy 419.146094 -32.610642) (xy 419.067612 -32.579322) (xy 418.992453 -32.5407)
			(xy 418.921295 -32.495126) (xy 418.854779 -32.44301) (xy 418.793506 -32.38482) (xy 418.738026 -32.321083)
			(xy 418.68884 -32.252372) (xy 418.667184 -32.21609) (xy 418.661088 -32.205422) (xy 418.639752 -32.19196)
			(xy 418.531294 -32.183578) (xy 418.508434 -32.193484) (xy 418.50056 -32.203136) (xy 418.472442 -32.237022)
			(xy 418.410581 -32.299691) (xy 418.342829 -32.35594) (xy 418.269851 -32.405218) (xy 418.19236 -32.447044)
			(xy 418.111115 -32.481007) (xy 418.026912 -32.506774) (xy 417.940574 -32.524095) (xy 417.852947 -32.532799)
			(xy 417.808918 -32.533336) (xy 417.768434 -32.532849) (xy 417.687801 -32.5255) (xy 417.60817 -32.510852)
			(xy 417.530199 -32.489028) (xy 417.454535 -32.460206) (xy 417.381804 -32.424626) (xy 417.312608 -32.382583)
			(xy 417.24752 -32.334424) (xy 417.187079 -32.280549) (xy 417.131785 -32.221403) (xy 417.082096 -32.157476)
			(xy 417.059872 -32.123634) (xy 417.051236 -32.123888) (xy 417.05022 -32.123888) (xy 417.009122 -32.123338)
			(xy 416.927281 -32.115712) (xy 416.846491 -32.10057) (xy 416.767443 -32.078042) (xy 416.690809 -32.048318)
			(xy 416.617244 -32.011652) (xy 416.547374 -31.968358) (xy 416.481795 -31.918804) (xy 416.421067 -31.863412)
			(xy 416.365706 -31.802655) (xy 416.316185 -31.737051) (xy 416.272926 -31.667159) (xy 416.236299 -31.593575)
			(xy 416.206614 -31.516927) (xy 416.184126 -31.437867) (xy 416.169025 -31.35707) (xy 416.161441 -31.275224)
			(xy 416.160966 -31.234126) (xy 410.705621 -31.234126) (xy 410.727885 -31.265053) (xy 410.770925 -31.33886)
			(xy 410.806694 -31.416451) (xy 410.834862 -31.497113) (xy 410.855169 -31.580104) (xy 410.867428 -31.664659)
			(xy 410.871527 -31.75) (xy 410.867428 -31.835341) (xy 410.855169 -31.919896) (xy 410.834862 -32.002887)
			(xy 410.806694 -32.083549) (xy 410.770925 -32.16114) (xy 410.727885 -32.234947) (xy 410.677968 -32.304288)
			(xy 410.650182 -32.33674) (xy 410.644417 -32.343829) (xy 410.637905 -32.360886) (xy 410.637482 -32.370014)
			(xy 410.637482 -32.399986) (xy 410.637916 -32.409109) (xy 410.644436 -32.426159) (xy 410.650182 -32.43326)
			(xy 410.67624 -32.463674) (xy 410.723426 -32.528392) (xy 410.764602 -32.597092) (xy 410.799433 -32.669216)
			(xy 410.827637 -32.74418) (xy 410.848986 -32.821377) (xy 410.863306 -32.900181) (xy 410.870481 -32.979953)
			(xy 410.870908 -33.02) (xy 410.870404 -33.062348) (xy 410.862353 -33.146662) (xy 410.846324 -33.229828)
			(xy 410.822463 -33.311095) (xy 410.790984 -33.389725) (xy 410.752173 -33.465006) (xy 410.706383 -33.536258)
			(xy 410.654027 -33.602834) (xy 410.595579 -33.664132) (xy 410.531569 -33.719597) (xy 410.462577 -33.768726)
			(xy 410.389227 -33.811075) (xy 410.385719 -33.812677) (xy 415.34232 -33.812677) (xy 415.34232 -33.727955)
			(xy 415.350373 -33.643618) (xy 415.366407 -33.560428) (xy 415.390275 -33.479138) (xy 415.421763 -33.400486)
			(xy 415.460585 -33.325183) (xy 415.506388 -33.253911) (xy 415.558759 -33.187315) (xy 415.617224 -33.126)
			(xy 415.681252 -33.070519) (xy 415.750264 -33.021376) (xy 415.823634 -32.979016) (xy 415.900699 -32.943821)
			(xy 415.980761 -32.916112) (xy 416.063094 -32.896138) (xy 416.146953 -32.884081) (xy 416.231578 -32.88005)
			(xy 416.316203 -32.884081) (xy 416.400062 -32.896138) (xy 416.482395 -32.916112) (xy 416.562457 -32.943821)
			(xy 416.639522 -32.979016) (xy 416.712892 -33.021376) (xy 416.781904 -33.070519) (xy 416.845932 -33.126)
			(xy 416.904397 -33.187315) (xy 416.956768 -33.253911) (xy 417.002571 -33.325183) (xy 417.041393 -33.400486)
			(xy 417.072881 -33.479138) (xy 417.096749 -33.560428) (xy 417.112783 -33.643618) (xy 417.120836 -33.727955)
			(xy 417.12134 -33.770316) (xy 417.120954 -33.802771) (xy 418.00678 -33.802771) (xy 418.00678 -33.718049)
			(xy 418.014833 -33.633712) (xy 418.030867 -33.550522) (xy 418.054735 -33.469232) (xy 418.086223 -33.39058)
			(xy 418.125045 -33.315277) (xy 418.170848 -33.244005) (xy 418.223219 -33.177409) (xy 418.281684 -33.116094)
			(xy 418.345712 -33.060613) (xy 418.414724 -33.01147) (xy 418.488094 -32.96911) (xy 418.565159 -32.933915)
			(xy 418.645221 -32.906206) (xy 418.727554 -32.886232) (xy 418.811413 -32.874175) (xy 418.896038 -32.870144)
			(xy 418.980663 -32.874175) (xy 419.064522 -32.886232) (xy 419.146855 -32.906206) (xy 419.226917 -32.933915)
			(xy 419.303982 -32.96911) (xy 419.377352 -33.01147) (xy 419.446364 -33.060613) (xy 419.510392 -33.116094)
			(xy 419.568857 -33.177409) (xy 419.621228 -33.244005) (xy 419.667031 -33.315277) (xy 419.705853 -33.39058)
			(xy 419.737341 -33.469232) (xy 419.761209 -33.550522) (xy 419.777243 -33.633712) (xy 419.785296 -33.718049)
			(xy 419.7858 -33.76041) (xy 419.785296 -33.802771) (xy 419.777243 -33.887108) (xy 419.761209 -33.970298)
			(xy 419.737341 -34.051588) (xy 419.705853 -34.13024) (xy 419.667031 -34.205543) (xy 419.621228 -34.276815)
			(xy 419.568857 -34.343411) (xy 419.510392 -34.404726) (xy 419.446364 -34.460207) (xy 419.377352 -34.50935)
			(xy 419.303982 -34.55171) (xy 419.226917 -34.586905) (xy 419.146855 -34.614614) (xy 419.064522 -34.634588)
			(xy 418.980663 -34.646645) (xy 418.896038 -34.650677) (xy 418.811413 -34.646645) (xy 418.727554 -34.634588)
			(xy 418.645221 -34.614614) (xy 418.565159 -34.586905) (xy 418.488094 -34.55171) (xy 418.414724 -34.50935)
			(xy 418.345712 -34.460207) (xy 418.281684 -34.404726) (xy 418.223219 -34.343411) (xy 418.170848 -34.276815)
			(xy 418.125045 -34.205543) (xy 418.086223 -34.13024) (xy 418.054735 -34.051588) (xy 418.030867 -33.970298)
			(xy 418.014833 -33.887108) (xy 418.00678 -33.802771) (xy 417.120954 -33.802771) (xy 417.120836 -33.812677)
			(xy 417.112783 -33.897014) (xy 417.096749 -33.980204) (xy 417.072881 -34.061494) (xy 417.041393 -34.140146)
			(xy 417.002571 -34.215449) (xy 416.956768 -34.286721) (xy 416.904397 -34.353317) (xy 416.845932 -34.414632)
			(xy 416.781904 -34.470113) (xy 416.712892 -34.519256) (xy 416.639522 -34.561616) (xy 416.562457 -34.596811)
			(xy 416.482395 -34.62452) (xy 416.400062 -34.644494) (xy 416.316203 -34.656551) (xy 416.231578 -34.660583)
			(xy 416.146953 -34.656551) (xy 416.063094 -34.644494) (xy 415.980761 -34.62452) (xy 415.900699 -34.596811)
			(xy 415.823634 -34.561616) (xy 415.750264 -34.519256) (xy 415.681252 -34.470113) (xy 415.617224 -34.414632)
			(xy 415.558759 -34.353317) (xy 415.506388 -34.286721) (xy 415.460585 -34.215449) (xy 415.421763 -34.140146)
			(xy 415.390275 -34.061494) (xy 415.366407 -33.980204) (xy 415.350373 -33.897014) (xy 415.34232 -33.812677)
			(xy 410.385719 -33.812677) (xy 410.312184 -33.846259) (xy 410.232145 -33.873961) (xy 410.149836 -33.893929)
			(xy 410.066001 -33.905982) (xy 409.9814 -33.910013) (xy 409.896799 -33.905982) (xy 409.812964 -33.893929)
			(xy 409.730655 -33.873961) (xy 409.650616 -33.846259) (xy 409.573573 -33.811075) (xy 409.500223 -33.768726)
			(xy 409.431231 -33.719597) (xy 409.367221 -33.664132) (xy 409.308773 -33.602834) (xy 409.256417 -33.536258)
			(xy 409.210627 -33.465006) (xy 409.171816 -33.389725) (xy 409.140337 -33.311095) (xy 409.116476 -33.229828)
			(xy 409.100447 -33.146662) (xy 409.092396 -33.062348) (xy 409.091892 -33.02) (xy 409.092307 -32.979953)
			(xy 409.099502 -32.900184) (xy 409.113836 -32.821384) (xy 409.13519 -32.74419) (xy 409.163394 -32.669227)
			(xy 409.198218 -32.5971) (xy 409.239382 -32.528395) (xy 409.286551 -32.463665) (xy 409.312618 -32.43326)
			(xy 409.318383 -32.426171) (xy 409.324895 -32.409114) (xy 409.325318 -32.399986) (xy 409.325318 -32.370014)
			(xy 409.324884 -32.360891) (xy 409.318364 -32.343841) (xy 409.312618 -32.33674) (xy 409.284832 -32.304288)
			(xy 409.234915 -32.234947) (xy 409.191875 -32.16114) (xy 409.156106 -32.083549) (xy 409.127938 -32.002887)
			(xy 409.107631 -31.919896) (xy 409.095372 -31.835341) (xy 409.091273 -31.75) (xy 406.515619 -31.75)
			(xy 406.528571 -31.794112) (xy 406.544605 -31.877302) (xy 406.552658 -31.961639) (xy 406.553162 -32.004)
			(xy 406.552658 -32.046361) (xy 406.544605 -32.130698) (xy 406.528571 -32.213888) (xy 406.504703 -32.295178)
			(xy 406.473215 -32.37383) (xy 406.434393 -32.449133) (xy 406.38859 -32.520405) (xy 406.336219 -32.587001)
			(xy 406.277754 -32.648316) (xy 406.213726 -32.703797) (xy 406.144714 -32.75294) (xy 406.071344 -32.7953)
			(xy 405.994279 -32.830495) (xy 405.914217 -32.858204) (xy 405.831884 -32.878178) (xy 405.748025 -32.890235)
			(xy 405.6634 -32.894267) (xy 405.578775 -32.890235) (xy 405.494916 -32.878178) (xy 405.412583 -32.858204)
			(xy 405.332521 -32.830495) (xy 405.255456 -32.7953) (xy 405.182086 -32.75294) (xy 405.113074 -32.703797)
			(xy 405.049046 -32.648316) (xy 404.990581 -32.587001) (xy 404.93821 -32.520405) (xy 404.892407 -32.449133)
			(xy 404.853585 -32.37383) (xy 404.822097 -32.295178) (xy 404.798229 -32.213888) (xy 404.782195 -32.130698)
			(xy 404.774142 -32.046361) (xy 390.320981 -32.046361) (xy 393.368981 -35.094361) (xy 420.369742 -35.094361)
			(xy 420.369742 -35.009639) (xy 420.377795 -34.925302) (xy 420.393829 -34.842112) (xy 420.417697 -34.760822)
			(xy 420.449185 -34.68217) (xy 420.488007 -34.606867) (xy 420.53381 -34.535595) (xy 420.586181 -34.468999)
			(xy 420.644646 -34.407684) (xy 420.708674 -34.352203) (xy 420.777686 -34.30306) (xy 420.851056 -34.2607)
			(xy 420.928121 -34.225505) (xy 421.008183 -34.197796) (xy 421.090516 -34.177822) (xy 421.174375 -34.165765)
			(xy 421.259 -34.161734) (xy 421.343625 -34.165765) (xy 421.427484 -34.177822) (xy 421.509817 -34.197796)
			(xy 421.589879 -34.225505) (xy 421.666944 -34.2607) (xy 421.740314 -34.30306) (xy 421.809326 -34.352203)
			(xy 421.873354 -34.407684) (xy 421.931819 -34.468999) (xy 421.98419 -34.535595) (xy 422.029993 -34.606867)
			(xy 422.068815 -34.68217) (xy 422.100303 -34.760822) (xy 422.124171 -34.842112) (xy 422.140205 -34.925302)
			(xy 422.148258 -35.009639) (xy 422.148762 -35.052) (xy 422.148258 -35.094361) (xy 422.528742 -35.094361)
			(xy 422.528742 -35.009639) (xy 422.536795 -34.925302) (xy 422.552829 -34.842112) (xy 422.576697 -34.760822)
			(xy 422.608185 -34.68217) (xy 422.647007 -34.606867) (xy 422.69281 -34.535595) (xy 422.745181 -34.468999)
			(xy 422.803646 -34.407684) (xy 422.867674 -34.352203) (xy 422.936686 -34.30306) (xy 423.010056 -34.2607)
			(xy 423.087121 -34.225505) (xy 423.167183 -34.197796) (xy 423.249516 -34.177822) (xy 423.333375 -34.165765)
			(xy 423.418 -34.161734) (xy 423.502625 -34.165765) (xy 423.586484 -34.177822) (xy 423.668817 -34.197796)
			(xy 423.748879 -34.225505) (xy 423.825944 -34.2607) (xy 423.899314 -34.30306) (xy 423.968326 -34.352203)
			(xy 424.032354 -34.407684) (xy 424.090819 -34.468999) (xy 424.14319 -34.535595) (xy 424.188993 -34.606867)
			(xy 424.227815 -34.68217) (xy 424.259303 -34.760822) (xy 424.283171 -34.842112) (xy 424.299205 -34.925302)
			(xy 424.307258 -35.009639) (xy 424.307762 -35.052) (xy 424.307258 -35.094361) (xy 424.299205 -35.178698)
			(xy 424.283171 -35.261888) (xy 424.259303 -35.343178) (xy 424.227815 -35.42183) (xy 424.188993 -35.497133)
			(xy 424.14319 -35.568405) (xy 424.090819 -35.635001) (xy 424.041237 -35.687) (xy 432.205892 -35.687)
			(xy 432.206367 -35.645898) (xy 432.213952 -35.564043) (xy 432.229057 -35.483238) (xy 432.251553 -35.404171)
			(xy 432.281249 -35.327517) (xy 432.317891 -35.25393) (xy 432.361166 -35.184038) (xy 432.410706 -35.118437)
			(xy 432.466087 -35.057687) (xy 432.526837 -35.002306) (xy 432.592438 -34.952766) (xy 432.66233 -34.909491)
			(xy 432.735917 -34.872849) (xy 432.812571 -34.843153) (xy 432.891638 -34.820657) (xy 432.972443 -34.805552)
			(xy 433.054298 -34.797967) (xy 433.0954 -34.797492) (xy 433.139048 -34.797973) (xy 433.225923 -34.806522)
			(xy 433.311544 -34.823538) (xy 433.395087 -34.848858) (xy 433.475748 -34.882237) (xy 433.552753 -34.923356)
			(xy 433.625361 -34.971818) (xy 433.692873 -35.027158) (xy 433.754642 -35.088844) (xy 433.810072 -35.156282)
			(xy 433.858632 -35.228825) (xy 433.899853 -35.305775) (xy 433.91709 -35.345878) (xy 433.921371 -35.35491)
			(xy 433.93549 -35.369029) (xy 433.944522 -35.37331) (xy 433.984626 -35.390543) (xy 434.061569 -35.43177)
			(xy 434.134105 -35.480334) (xy 434.201536 -35.535768) (xy 434.263216 -35.597538) (xy 434.31855 -35.665052)
			(xy 434.367006 -35.737659) (xy 434.40812 -35.814663) (xy 434.441495 -35.895323) (xy 434.466812 -35.978863)
			(xy 434.483826 -36.064481) (xy 434.492374 -36.151354) (xy 434.492908 -36.195) (xy 434.492433 -36.236102)
			(xy 434.484848 -36.317957) (xy 434.469743 -36.398762) (xy 434.447247 -36.477829) (xy 434.417551 -36.554483)
			(xy 434.380909 -36.62807) (xy 434.337634 -36.697962) (xy 434.288094 -36.763563) (xy 434.244941 -36.8109)
			(xy 434.491184 -36.8109) (xy 434.495214 -36.72628) (xy 434.507271 -36.642425) (xy 434.527244 -36.560097)
			(xy 434.554952 -36.48004) (xy 434.590144 -36.402979) (xy 434.632502 -36.329613) (xy 434.681643 -36.260605)
			(xy 434.73712 -36.19658) (xy 434.798432 -36.138119) (xy 434.865024 -36.085751) (xy 434.936292 -36.03995)
			(xy 435.011591 -36.001131) (xy 435.090239 -35.969645) (xy 435.171524 -35.945777) (xy 435.254709 -35.929745)
			(xy 435.339042 -35.921692) (xy 435.3814 -35.921188) (xy 435.424724 -35.921707) (xy 435.51096 -35.930152)
			(xy 435.595966 -35.946944) (xy 435.678936 -35.971923) (xy 435.759084 -36.004852) (xy 435.835649 -36.045419)
			(xy 435.907907 -36.09324) (xy 435.975171 -36.14786) (xy 436.036806 -36.208764) (xy 436.064914 -36.241736)
			(xy 436.074039 -36.251976) (xy 436.096545 -36.267631) (xy 436.122405 -36.276738) (xy 436.149754 -36.278639)
			(xy 436.176625 -36.273198) (xy 436.201081 -36.260808) (xy 436.221361 -36.242359) (xy 436.236004 -36.219182)
			(xy 436.243956 -36.192944) (xy 436.244746 -36.179252) (xy 436.246331 -36.136289) (xy 436.256726 -36.050941)
			(xy 436.275308 -35.966994) (xy 436.301904 -35.885232) (xy 436.336264 -35.806417) (xy 436.378069 -35.731286)
			(xy 436.426928 -35.660539) (xy 436.482386 -35.594836) (xy 436.543924 -35.534791) (xy 436.610969 -35.480964)
			(xy 436.682894 -35.433858) (xy 436.75903 -35.393911) (xy 436.838664 -35.361497) (xy 436.921055 -35.336917)
			(xy 437.005433 -35.320403) (xy 437.091011 -35.312107) (xy 437.134 -35.311588) (xy 437.176363 -35.311992)
			(xy 437.260705 -35.320046) (xy 437.3439 -35.33608) (xy 437.425194 -35.35995) (xy 437.503851 -35.39144)
			(xy 437.579158 -35.430263) (xy 437.650434 -35.47607) (xy 437.717033 -35.528444) (xy 437.778352 -35.586911)
			(xy 437.833836 -35.650943) (xy 437.882982 -35.719959) (xy 437.925345 -35.793333) (xy 437.960541 -35.870403)
			(xy 437.988252 -35.950469) (xy 438.008227 -36.032806) (xy 438.020285 -36.11667) (xy 438.024317 -36.2013)
			(xy 438.020285 -36.28593) (xy 438.008227 -36.369794) (xy 437.988252 -36.452131) (xy 437.960541 -36.532197)
			(xy 437.960515 -36.532255) (xy 438.381136 -36.532255) (xy 438.381136 -36.447533) (xy 438.389189 -36.363196)
			(xy 438.405223 -36.280006) (xy 438.429091 -36.198716) (xy 438.460579 -36.120064) (xy 438.499401 -36.044761)
			(xy 438.545204 -35.973489) (xy 438.597575 -35.906893) (xy 438.65604 -35.845578) (xy 438.720068 -35.790097)
			(xy 438.78908 -35.740954) (xy 438.86245 -35.698594) (xy 438.939515 -35.663399) (xy 439.019577 -35.63569)
			(xy 439.10191 -35.615716) (xy 439.185769 -35.603659) (xy 439.270394 -35.599628) (xy 439.355019 -35.603659)
			(xy 439.438878 -35.615716) (xy 439.521211 -35.63569) (xy 439.601273 -35.663399) (xy 439.678338 -35.698594)
			(xy 439.751708 -35.740954) (xy 439.82072 -35.790097) (xy 439.884748 -35.845578) (xy 439.943213 -35.906893)
			(xy 439.995584 -35.973489) (xy 440.041387 -36.044761) (xy 440.080209 -36.120064) (xy 440.111697 -36.198716)
			(xy 440.11262 -36.201858) (xy 447.166492 -36.201858) (xy 447.166492 -36.20135) (xy 447.167051 -36.158558)
			(xy 447.175274 -36.073369) (xy 447.191638 -35.989363) (xy 447.215994 -35.907317) (xy 447.248115 -35.827989)
			(xy 447.287705 -35.752111) (xy 447.334397 -35.680386) (xy 447.387761 -35.613475) (xy 447.447304 -35.551998)
			(xy 447.512474 -35.496522) (xy 447.58267 -35.44756) (xy 447.657243 -35.405565) (xy 447.735504 -35.370925)
			(xy 447.81673 -35.343959) (xy 447.900169 -35.324917) (xy 447.985052 -35.313975) (xy 448.027806 -35.312096)
			(xy 448.040474 -35.311086) (xy 448.062464 -35.298405) (xy 448.069716 -35.287966) (xy 448.12077 -35.205162)
			(xy 448.122294 -35.179762) (xy 448.11696 -35.168332) (xy 448.101419 -35.133431) (xy 448.075676 -35.061492)
			(xy 448.056202 -34.987609) (xy 448.043142 -34.912328) (xy 448.036593 -34.836203) (xy 448.036188 -34.798)
			(xy 448.036666 -34.756905) (xy 448.044248 -34.675066) (xy 448.059348 -34.594275) (xy 448.081836 -34.515221)
			(xy 448.111521 -34.43858) (xy 448.14815 -34.365003) (xy 448.19141 -34.29512) (xy 448.240933 -34.229525)
			(xy 448.296296 -34.168778) (xy 448.357026 -34.113398) (xy 448.422607 -34.063856) (xy 448.492478 -34.020576)
			(xy 448.566044 -33.983926) (xy 448.642677 -33.954218) (xy 448.721724 -33.931707) (xy 448.80251 -33.916584)
			(xy 448.884347 -33.908978) (xy 448.925442 -33.908492) (xy 448.92595 -33.908492) (xy 448.965051 -33.908898)
			(xy 449.04295 -33.915772) (xy 449.119944 -33.929461) (xy 449.195439 -33.949859) (xy 449.268849 -33.976811)
			(xy 449.30441 -33.993074) (xy 449.314797 -33.997309) (xy 449.337203 -33.997309) (xy 449.34759 -33.993074)
			(xy 449.383157 -33.976829) (xy 449.456572 -33.949898) (xy 449.532066 -33.929508) (xy 449.609056 -33.915817)
			(xy 449.686951 -33.90893) (xy 449.72605 -33.908492) (xy 449.767155 -33.90906) (xy 449.849014 -33.91664)
			(xy 449.929824 -33.931738) (xy 450.008898 -33.954227) (xy 450.085559 -33.983915) (xy 450.159155 -34.020549)
			(xy 450.229057 -34.063816) (xy 450.29467 -34.113346) (xy 450.355433 -34.168719) (xy 450.41083 -34.229461)
			(xy 450.460386 -34.295054) (xy 450.503681 -34.364939) (xy 450.540343 -34.438521) (xy 450.570061 -34.51517)
			(xy 450.592582 -34.594235) (xy 450.607712 -34.67504) (xy 450.615324 -34.756896) (xy 450.615812 -34.798)
			(xy 450.615332 -34.839817) (xy 450.607471 -34.92308) (xy 450.591827 -35.005238) (xy 450.568539 -35.085564)
			(xy 450.537812 -35.163349) (xy 450.519292 -35.200844) (xy 450.519292 -35.201098) (xy 450.514704 -35.211349)
			(xy 450.514055 -35.23377) (xy 450.518022 -35.244278) (xy 450.549518 -35.316414) (xy 450.554546 -35.326449)
			(xy 450.571416 -35.341212) (xy 450.58203 -35.344862) (xy 450.582284 -35.344862) (xy 450.621839 -35.356469)
			(xy 450.698811 -35.385993) (xy 450.772722 -35.422512) (xy 450.842936 -35.465712) (xy 450.908853 -35.515224)
			(xy 450.969906 -35.570621) (xy 451.025572 -35.63143) (xy 451.075373 -35.697128) (xy 451.118882 -35.767151)
			(xy 451.155726 -35.8409) (xy 451.185589 -35.917741) (xy 451.208214 -35.997016) (xy 451.223408 -36.078044)
			(xy 451.23104 -36.16013) (xy 451.231508 -36.20135) (xy 451.23094 -36.242455) (xy 451.22336 -36.324314)
			(xy 451.208262 -36.405124) (xy 451.185773 -36.484198) (xy 451.156085 -36.560859) (xy 451.119451 -36.634455)
			(xy 451.076184 -36.704357) (xy 451.026654 -36.76997) (xy 450.971281 -36.830733) (xy 450.910539 -36.88613)
			(xy 450.844946 -36.935686) (xy 450.775061 -36.978981) (xy 450.701479 -37.015643) (xy 450.62483 -37.045361)
			(xy 450.545765 -37.067882) (xy 450.46496 -37.083012) (xy 450.383104 -37.090624) (xy 450.342 -37.091112)
			(xy 450.300488 -37.09062) (xy 450.217828 -37.082852) (xy 450.136252 -37.067412) (xy 450.056471 -37.044434)
			(xy 449.979179 -37.014119) (xy 449.90505 -36.97673) (xy 449.83473 -36.932593) (xy 449.801488 -36.907724)
			(xy 449.792289 -36.901381) (xy 449.7705 -36.89655) (xy 449.748711 -36.901381) (xy 449.739512 -36.907724)
			(xy 449.706254 -36.932568) (xy 449.635928 -36.97669) (xy 449.561799 -37.014069) (xy 449.48451 -37.044382)
			(xy 449.404734 -37.067365) (xy 449.323164 -37.082817) (xy 449.24051 -37.090605) (xy 449.199 -37.091112)
			(xy 449.157488 -37.09062) (xy 449.074828 -37.082852) (xy 448.993252 -37.067412) (xy 448.913471 -37.044434)
			(xy 448.836179 -37.014119) (xy 448.76205 -36.97673) (xy 448.69173 -36.932593) (xy 448.658488 -36.907724)
			(xy 448.649289 -36.901381) (xy 448.6275 -36.89655) (xy 448.605711 -36.901381) (xy 448.596512 -36.907724)
			(xy 448.563254 -36.932568) (xy 448.492928 -36.97669) (xy 448.418799 -37.014069) (xy 448.34151 -37.044382)
			(xy 448.261734 -37.067365) (xy 448.180164 -37.082817) (xy 448.09751 -37.090605) (xy 448.056 -37.091112)
			(xy 448.014905 -37.090634) (xy 447.933066 -37.083052) (xy 447.852275 -37.067952) (xy 447.773221 -37.045464)
			(xy 447.69658 -37.015779) (xy 447.623003 -36.97915) (xy 447.55312 -36.93589) (xy 447.487525 -36.886367)
			(xy 447.426778 -36.831004) (xy 447.371398 -36.770274) (xy 447.321856 -36.704693) (xy 447.278576 -36.634822)
			(xy 447.241926 -36.561256) (xy 447.212218 -36.484623) (xy 447.189707 -36.405576) (xy 447.174584 -36.32479)
			(xy 447.166978 -36.242953) (xy 447.166492 -36.201858) (xy 440.11262 -36.201858) (xy 440.135565 -36.280006)
			(xy 440.151599 -36.363196) (xy 440.159652 -36.447533) (xy 440.160156 -36.489894) (xy 440.159652 -36.532255)
			(xy 440.151599 -36.616592) (xy 440.135565 -36.699782) (xy 440.111697 -36.781072) (xy 440.080209 -36.859724)
			(xy 440.041387 -36.935027) (xy 439.995584 -37.006299) (xy 439.943213 -37.072895) (xy 439.884748 -37.13421)
			(xy 439.82072 -37.189691) (xy 439.751708 -37.238834) (xy 439.678338 -37.281194) (xy 439.601273 -37.316389)
			(xy 439.521211 -37.344098) (xy 439.438878 -37.364072) (xy 439.355019 -37.376129) (xy 439.270394 -37.380161)
			(xy 439.185769 -37.376129) (xy 439.10191 -37.364072) (xy 439.019577 -37.344098) (xy 438.939515 -37.316389)
			(xy 438.86245 -37.281194) (xy 438.78908 -37.238834) (xy 438.720068 -37.189691) (xy 438.65604 -37.13421)
			(xy 438.597575 -37.072895) (xy 438.545204 -37.006299) (xy 438.499401 -36.935027) (xy 438.460579 -36.859724)
			(xy 438.429091 -36.781072) (xy 438.405223 -36.699782) (xy 438.389189 -36.616592) (xy 438.381136 -36.532255)
			(xy 437.960515 -36.532255) (xy 437.925345 -36.609267) (xy 437.882982 -36.682641) (xy 437.833836 -36.751657)
			(xy 437.778352 -36.815689) (xy 437.717033 -36.874156) (xy 437.650434 -36.92653) (xy 437.579158 -36.972337)
			(xy 437.503851 -37.01116) (xy 437.425194 -37.04265) (xy 437.3439 -37.06652) (xy 437.260705 -37.082554)
			(xy 437.176363 -37.090608) (xy 437.134 -37.091112) (xy 437.090676 -37.090593) (xy 437.00444 -37.082148)
			(xy 436.919434 -37.065356) (xy 436.836464 -37.040377) (xy 436.756316 -37.007448) (xy 436.679751 -36.966881)
			(xy 436.607493 -36.91906) (xy 436.540229 -36.86444) (xy 436.478594 -36.803536) (xy 436.450486 -36.770564)
			(xy 436.441361 -36.760324) (xy 436.418855 -36.744669) (xy 436.392995 -36.735562) (xy 436.365646 -36.733661)
			(xy 436.338775 -36.739102) (xy 436.314319 -36.751492) (xy 436.294039 -36.769941) (xy 436.279396 -36.793118)
			(xy 436.271444 -36.819356) (xy 436.270654 -36.833048) (xy 436.269069 -36.876011) (xy 436.258674 -36.961359)
			(xy 436.240092 -37.045306) (xy 436.213496 -37.127068) (xy 436.179136 -37.205883) (xy 436.137331 -37.281014)
			(xy 436.088472 -37.351761) (xy 436.033014 -37.417464) (xy 435.971476 -37.477509) (xy 435.904431 -37.531336)
			(xy 435.832506 -37.578442) (xy 435.75637 -37.618389) (xy 435.676736 -37.650803) (xy 435.594345 -37.675383)
			(xy 435.509967 -37.691897) (xy 435.424389 -37.700193) (xy 435.3814 -37.700712) (xy 435.339042 -37.700108)
			(xy 435.254709 -37.692055) (xy 435.171524 -37.676023) (xy 435.090239 -37.652155) (xy 435.011591 -37.620669)
			(xy 434.936292 -37.58185) (xy 434.865024 -37.536049) (xy 434.798432 -37.483681) (xy 434.73712 -37.42522)
			(xy 434.681643 -37.361195) (xy 434.632502 -37.292187) (xy 434.590144 -37.218821) (xy 434.554952 -37.14176)
			(xy 434.527244 -37.061703) (xy 434.507271 -36.979375) (xy 434.495214 -36.89552) (xy 434.491184 -36.8109)
			(xy 434.244941 -36.8109) (xy 434.232713 -36.824313) (xy 434.171963 -36.879694) (xy 434.106362 -36.929234)
			(xy 434.03647 -36.972509) (xy 433.962883 -37.009151) (xy 433.886229 -37.038847) (xy 433.807162 -37.061343)
			(xy 433.726357 -37.076448) (xy 433.644502 -37.084033) (xy 433.6034 -37.084508) (xy 433.559752 -37.084027)
			(xy 433.472877 -37.075478) (xy 433.387256 -37.058462) (xy 433.303713 -37.033142) (xy 433.223052 -36.999763)
			(xy 433.146047 -36.958644) (xy 433.073439 -36.910182) (xy 433.005927 -36.854842) (xy 432.944158 -36.793156)
			(xy 432.888728 -36.725718) (xy 432.840168 -36.653175) (xy 432.798947 -36.576225) (xy 432.78171 -36.536122)
			(xy 432.777429 -36.52709) (xy 432.76331 -36.512971) (xy 432.754278 -36.50869) (xy 432.714174 -36.491457)
			(xy 432.637231 -36.45023) (xy 432.564695 -36.401666) (xy 432.497264 -36.346232) (xy 432.435584 -36.284462)
			(xy 432.38025 -36.216948) (xy 432.331794 -36.144341) (xy 432.29068 -36.067337) (xy 432.257305 -35.986677)
			(xy 432.231988 -35.903137) (xy 432.214974 -35.817519) (xy 432.206426 -35.730646) (xy 432.205892 -35.687)
			(xy 424.041237 -35.687) (xy 424.032354 -35.696316) (xy 423.968326 -35.751797) (xy 423.899314 -35.80094)
			(xy 423.825944 -35.8433) (xy 423.748879 -35.878495) (xy 423.668817 -35.906204) (xy 423.586484 -35.926178)
			(xy 423.502625 -35.938235) (xy 423.418 -35.942267) (xy 423.333375 -35.938235) (xy 423.249516 -35.926178)
			(xy 423.167183 -35.906204) (xy 423.087121 -35.878495) (xy 423.010056 -35.8433) (xy 422.936686 -35.80094)
			(xy 422.867674 -35.751797) (xy 422.803646 -35.696316) (xy 422.745181 -35.635001) (xy 422.69281 -35.568405)
			(xy 422.647007 -35.497133) (xy 422.608185 -35.42183) (xy 422.576697 -35.343178) (xy 422.552829 -35.261888)
			(xy 422.536795 -35.178698) (xy 422.528742 -35.094361) (xy 422.148258 -35.094361) (xy 422.140205 -35.178698)
			(xy 422.124171 -35.261888) (xy 422.100303 -35.343178) (xy 422.068815 -35.42183) (xy 422.029993 -35.497133)
			(xy 421.98419 -35.568405) (xy 421.931819 -35.635001) (xy 421.873354 -35.696316) (xy 421.809326 -35.751797)
			(xy 421.740314 -35.80094) (xy 421.666944 -35.8433) (xy 421.589879 -35.878495) (xy 421.509817 -35.906204)
			(xy 421.427484 -35.926178) (xy 421.343625 -35.938235) (xy 421.259 -35.942267) (xy 421.174375 -35.938235)
			(xy 421.090516 -35.926178) (xy 421.008183 -35.906204) (xy 420.928121 -35.878495) (xy 420.851056 -35.8433)
			(xy 420.777686 -35.80094) (xy 420.708674 -35.751797) (xy 420.644646 -35.696316) (xy 420.586181 -35.635001)
			(xy 420.53381 -35.568405) (xy 420.488007 -35.497133) (xy 420.449185 -35.42183) (xy 420.417697 -35.343178)
			(xy 420.393829 -35.261888) (xy 420.377795 -35.178698) (xy 420.369742 -35.094361) (xy 393.368981 -35.094361)
			(xy 395.146981 -36.872361) (xy 404.774142 -36.872361) (xy 404.774142 -36.787639) (xy 404.782195 -36.703302)
			(xy 404.798229 -36.620112) (xy 404.822097 -36.538822) (xy 404.853585 -36.46017) (xy 404.892407 -36.384867)
			(xy 404.93821 -36.313595) (xy 404.990581 -36.246999) (xy 405.049046 -36.185684) (xy 405.113074 -36.130203)
			(xy 405.182086 -36.08106) (xy 405.255456 -36.0387) (xy 405.332521 -36.003505) (xy 405.412583 -35.975796)
			(xy 405.494916 -35.955822) (xy 405.578775 -35.943765) (xy 405.6634 -35.939734) (xy 405.748025 -35.943765)
			(xy 405.831884 -35.955822) (xy 405.914217 -35.975796) (xy 405.994279 -36.003505) (xy 406.071344 -36.0387)
			(xy 406.144714 -36.08106) (xy 406.213726 -36.130203) (xy 406.277754 -36.185684) (xy 406.336219 -36.246999)
			(xy 406.38859 -36.313595) (xy 406.434393 -36.384867) (xy 406.473215 -36.46017) (xy 406.504703 -36.538822)
			(xy 406.528571 -36.620112) (xy 406.544605 -36.703302) (xy 406.552658 -36.787639) (xy 406.553162 -36.83)
			(xy 406.552658 -36.872361) (xy 406.544605 -36.956698) (xy 406.528571 -37.039888) (xy 406.504703 -37.121178)
			(xy 406.473215 -37.19983) (xy 406.434393 -37.275133) (xy 406.38859 -37.346405) (xy 406.336219 -37.413001)
			(xy 406.277754 -37.474316) (xy 406.213726 -37.529797) (xy 406.144714 -37.57894) (xy 406.071344 -37.6213)
			(xy 405.994279 -37.656495) (xy 405.914217 -37.684204) (xy 405.831884 -37.704178) (xy 405.748025 -37.716235)
			(xy 405.6634 -37.720267) (xy 405.578775 -37.716235) (xy 405.494916 -37.704178) (xy 405.412583 -37.684204)
			(xy 405.332521 -37.656495) (xy 405.255456 -37.6213) (xy 405.182086 -37.57894) (xy 405.113074 -37.529797)
			(xy 405.049046 -37.474316) (xy 404.990581 -37.413001) (xy 404.93821 -37.346405) (xy 404.892407 -37.275133)
			(xy 404.853585 -37.19983) (xy 404.822097 -37.121178) (xy 404.798229 -37.039888) (xy 404.782195 -36.956698)
			(xy 404.774142 -36.872361) (xy 395.146981 -36.872361) (xy 396.101824 -37.827204) (xy 410.107892 -37.827204)
			(xy 410.107892 -37.82695) (xy 410.10846 -37.785845) (xy 410.11604 -37.703986) (xy 410.131138 -37.623176)
			(xy 410.153627 -37.544102) (xy 410.183315 -37.467441) (xy 410.219949 -37.393845) (xy 410.263216 -37.323943)
			(xy 410.312746 -37.25833) (xy 410.368119 -37.197567) (xy 410.428861 -37.14217) (xy 410.494454 -37.092614)
			(xy 410.564339 -37.049319) (xy 410.637921 -37.012657) (xy 410.71457 -36.982939) (xy 410.793635 -36.960418)
			(xy 410.87444 -36.945288) (xy 410.956296 -36.937676) (xy 410.9974 -36.937188) (xy 411.041554 -36.937734)
			(xy 411.129428 -36.946487) (xy 411.216001 -36.963906) (xy 411.300421 -36.98982) (xy 411.381857 -37.023974)
			(xy 411.459507 -37.066032) (xy 411.532606 -37.115579) (xy 411.566868 -37.143436) (xy 411.574458 -37.149318)
			(xy 411.592654 -37.155417) (xy 411.611818 -37.154415) (xy 411.620716 -37.150802) (xy 411.717236 -37.106352)
			(xy 411.733238 -37.081968) (xy 411.733492 -37.067236) (xy 411.734787 -37.025139) (xy 411.744319 -36.941451)
			(xy 411.76172 -36.85904) (xy 411.786834 -36.778642) (xy 411.819437 -36.700979) (xy 411.838902 -36.66363)
			(xy 411.84432 -36.652164) (xy 411.84432 -36.626836) (xy 411.838902 -36.61537) (xy 411.818699 -36.576575)
			(xy 411.785177 -36.495778) (xy 411.759741 -36.412082) (xy 411.742637 -36.326296) (xy 411.734027 -36.239245)
			(xy 411.733492 -36.195508) (xy 411.733492 -36.195) (xy 411.733996 -36.152652) (xy 411.742047 -36.068338)
			(xy 411.758076 -35.985172) (xy 411.781937 -35.903905) (xy 411.813416 -35.825275) (xy 411.852227 -35.749994)
			(xy 411.898017 -35.678742) (xy 411.950373 -35.612166) (xy 412.008821 -35.550868) (xy 412.072831 -35.495403)
			(xy 412.141823 -35.446274) (xy 412.215173 -35.403925) (xy 412.292216 -35.368741) (xy 412.372255 -35.341039)
			(xy 412.454564 -35.321071) (xy 412.538399 -35.309018) (xy 412.623 -35.304988) (xy 412.707601 -35.309018)
			(xy 412.791436 -35.321071) (xy 412.873745 -35.341039) (xy 412.953784 -35.368741) (xy 413.030827 -35.403925)
			(xy 413.104177 -35.446274) (xy 413.173169 -35.495403) (xy 413.237179 -35.550868) (xy 413.295627 -35.612166)
			(xy 413.347983 -35.678742) (xy 413.393773 -35.749994) (xy 413.432584 -35.825275) (xy 413.464063 -35.903905)
			(xy 413.487924 -35.985172) (xy 413.503953 -36.068338) (xy 413.512004 -36.152652) (xy 413.512508 -36.195)
			(xy 413.512508 -36.195508) (xy 413.511989 -36.239272) (xy 413.503414 -36.326378) (xy 413.486318 -36.412219)
			(xy 413.460867 -36.495965) (xy 413.427307 -36.576803) (xy 413.407098 -36.615624) (xy 413.401771 -36.626977)
			(xy 413.401771 -36.652023) (xy 413.407098 -36.663376) (xy 413.427292 -36.702204) (xy 413.460832 -36.783047)
			(xy 413.486277 -36.866792) (xy 413.503382 -36.952629) (xy 413.511981 -37.03973) (xy 413.512508 -37.083492)
			(xy 413.512508 -37.084) (xy 413.512033 -37.125102) (xy 413.504448 -37.206957) (xy 413.489343 -37.287762)
			(xy 413.466847 -37.366829) (xy 413.437151 -37.443483) (xy 413.400509 -37.51707) (xy 413.357234 -37.586962)
			(xy 413.307694 -37.652563) (xy 413.252313 -37.713313) (xy 413.191563 -37.768694) (xy 413.125962 -37.818234)
			(xy 413.05607 -37.861509) (xy 412.982483 -37.898151) (xy 412.905829 -37.927847) (xy 412.826762 -37.950343)
			(xy 412.745957 -37.965448) (xy 412.664102 -37.973033) (xy 412.623 -37.973508) (xy 412.622492 -37.973508)
			(xy 412.578382 -37.972948) (xy 412.490596 -37.964185) (xy 412.40411 -37.946775) (xy 412.319772 -37.92089)
			(xy 412.238409 -37.886784) (xy 412.160823 -37.844792) (xy 412.087774 -37.795326) (xy 412.053532 -37.767514)
			(xy 412.045943 -37.76163) (xy 412.027747 -37.755537) (xy 412.008583 -37.756538) (xy 411.999684 -37.760148)
			(xy 411.903164 -37.804598) (xy 411.887162 -37.828982) (xy 411.886908 -37.843714) (xy 411.885587 -37.886923)
			(xy 411.875568 -37.972794) (xy 411.85727 -38.057289) (xy 411.830864 -38.13961) (xy 411.796598 -38.218983)
			(xy 411.754797 -38.294659) (xy 411.705854 -38.365924) (xy 411.650231 -38.432107) (xy 411.6197 -38.462712)
			(xy 411.612773 -38.470152) (xy 411.604912 -38.488879) (xy 411.60446 -38.499034) (xy 411.604206 -38.581838)
			(xy 411.612334 -38.600888) (xy 411.6197 -38.608) (xy 411.647813 -38.636158) (xy 411.699451 -38.696703)
			(xy 411.722824 -38.728904) (xy 411.729221 -38.737098) (xy 411.746974 -38.747878) (xy 411.767545 -38.750744)
			(xy 411.777688 -38.748462) (xy 411.816148 -38.738345) (xy 411.894416 -38.724213) (xy 411.973633 -38.717137)
			(xy 412.0134 -38.716712) (xy 412.053666 -38.717185) (xy 412.133867 -38.724466) (xy 412.213082 -38.738968)
			(xy 412.290661 -38.760572) (xy 412.365969 -38.789102) (xy 412.43839 -38.824324) (xy 412.507329 -38.865949)
			(xy 412.572223 -38.913636) (xy 412.60268 -38.939978) (xy 412.609686 -38.945736) (xy 412.626579 -38.9523)
			(xy 412.6447 -38.952573) (xy 412.661784 -38.946521) (xy 412.668974 -38.940994) (xy 412.703274 -38.913119)
			(xy 412.776431 -38.863511) (xy 412.854146 -38.821399) (xy 412.935652 -38.787201) (xy 413.020148 -38.761251)
			(xy 413.1068 -38.743806) (xy 413.194755 -38.735038) (xy 413.23895 -38.734492) (xy 413.281301 -38.734978)
			(xy 413.365619 -38.743025) (xy 413.448791 -38.75905) (xy 413.530062 -38.78291) (xy 413.608698 -38.814387)
			(xy 413.683985 -38.853196) (xy 413.73396 -38.885311) (xy 414.400742 -38.885311) (xy 414.400742 -38.800589)
			(xy 414.408795 -38.716252) (xy 414.424829 -38.633062) (xy 414.448697 -38.551772) (xy 414.480185 -38.47312)
			(xy 414.519007 -38.397817) (xy 414.56481 -38.326545) (xy 414.617181 -38.259949) (xy 414.675646 -38.198634)
			(xy 414.739674 -38.143153) (xy 414.808686 -38.09401) (xy 414.882056 -38.05165) (xy 414.959121 -38.016455)
			(xy 415.039183 -37.988746) (xy 415.121516 -37.968772) (xy 415.205375 -37.956715) (xy 415.29 -37.952684)
			(xy 415.374625 -37.956715) (xy 415.458484 -37.968772) (xy 415.540817 -37.988746) (xy 415.620879 -38.016455)
			(xy 415.697944 -38.05165) (xy 415.771314 -38.09401) (xy 415.840326 -38.143153) (xy 415.904354 -38.198634)
			(xy 415.962819 -38.259949) (xy 416.01519 -38.326545) (xy 416.060993 -38.397817) (xy 416.099815 -38.47312)
			(xy 416.131303 -38.551772) (xy 416.155171 -38.633062) (xy 416.171205 -38.716252) (xy 416.179258 -38.800589)
			(xy 416.179762 -38.84295) (xy 416.179258 -38.885311) (xy 416.171205 -38.969648) (xy 416.155171 -39.052838)
			(xy 416.131303 -39.134128) (xy 416.099815 -39.21278) (xy 416.060993 -39.288083) (xy 416.01519 -39.359355)
			(xy 415.962819 -39.425951) (xy 415.904354 -39.487266) (xy 415.840326 -39.542747) (xy 415.771314 -39.59189)
			(xy 415.697944 -39.63425) (xy 415.620879 -39.669445) (xy 415.540817 -39.697154) (xy 415.458484 -39.717128)
			(xy 415.374625 -39.729185) (xy 415.29 -39.733217) (xy 415.205375 -39.729185) (xy 415.121516 -39.717128)
			(xy 415.039183 -39.697154) (xy 414.959121 -39.669445) (xy 414.882056 -39.63425) (xy 414.808686 -39.59189)
			(xy 414.739674 -39.542747) (xy 414.675646 -39.487266) (xy 414.617181 -39.425951) (xy 414.56481 -39.359355)
			(xy 414.519007 -39.288083) (xy 414.480185 -39.21278) (xy 414.448697 -39.134128) (xy 414.424829 -39.052838)
			(xy 414.408795 -38.969648) (xy 414.400742 -38.885311) (xy 413.73396 -38.885311) (xy 413.755242 -38.898987)
			(xy 413.821824 -38.951344) (xy 413.883127 -39.009793) (xy 413.938596 -39.073805) (xy 413.987729 -39.142799)
			(xy 414.030081 -39.216152) (xy 414.065269 -39.293199) (xy 414.092973 -39.373241) (xy 414.112943 -39.455555)
			(xy 414.124998 -39.539394) (xy 414.129028 -39.624) (xy 414.124998 -39.708606) (xy 414.112943 -39.792445)
			(xy 414.092973 -39.874759) (xy 414.065269 -39.954801) (xy 414.030081 -40.031848) (xy 413.987729 -40.105201)
			(xy 413.938596 -40.174195) (xy 413.883127 -40.238207) (xy 413.821824 -40.296656) (xy 413.755242 -40.349013)
			(xy 413.683985 -40.394804) (xy 413.608698 -40.433613) (xy 413.530062 -40.46509) (xy 413.448791 -40.48895)
			(xy 413.365619 -40.504975) (xy 413.281301 -40.513022) (xy 413.23895 -40.513508) (xy 413.238696 -40.513508)
			(xy 413.198453 -40.513042) (xy 413.118296 -40.505763) (xy 413.039124 -40.491273) (xy 412.961585 -40.469691)
			(xy 412.886312 -40.441193) (xy 412.813921 -40.406013) (xy 412.745004 -40.364438) (xy 412.680124 -40.316808)
			(xy 412.64967 -40.290496) (xy 412.642629 -40.284787) (xy 412.625752 -40.278219) (xy 412.607643 -40.277932)
			(xy 412.590567 -40.283964) (xy 412.583376 -40.28948) (xy 412.549106 -40.317404) (xy 412.475958 -40.367055)
			(xy 412.398247 -40.409206) (xy 412.316738 -40.443441) (xy 412.232235 -40.469422) (xy 412.145572 -40.486893)
			(xy 412.057603 -40.495681) (xy 412.0134 -40.496236) (xy 411.970907 -40.495762) (xy 411.886307 -40.487662)
			(xy 411.802867 -40.471527) (xy 411.721347 -40.447505) (xy 411.64249 -40.415813) (xy 411.567018 -40.376742)
			(xy 411.495618 -40.330648) (xy 411.428941 -40.277951) (xy 411.367597 -40.219133) (xy 411.312145 -40.15473)
			(xy 411.287214 -40.120316) (xy 411.280772 -40.112151) (xy 411.263065 -40.101292) (xy 411.24251 -40.098297)
			(xy 411.23235 -40.100504) (xy 411.19409 -40.110528) (xy 411.116242 -40.12454) (xy 411.037457 -40.131571)
			(xy 410.997908 -40.132) (xy 410.9974 -40.132) (xy 410.956321 -40.131526) (xy 410.874513 -40.123945)
			(xy 410.793754 -40.108849) (xy 410.714732 -40.086365) (xy 410.638122 -40.056686) (xy 410.564577 -40.020065)
			(xy 410.494725 -39.976815) (xy 410.429162 -39.927303) (xy 410.368446 -39.871954) (xy 410.313097 -39.811238)
			(xy 410.263585 -39.745675) (xy 410.220335 -39.675823) (xy 410.183714 -39.602278) (xy 410.154035 -39.525668)
			(xy 410.131551 -39.446646) (xy 410.116455 -39.365887) (xy 410.108874 -39.284079) (xy 410.1084 -39.243)
			(xy 410.108974 -39.198782) (xy 410.117757 -39.110783) (xy 410.135237 -39.024091) (xy 410.161241 -38.939564)
			(xy 410.195511 -38.858038) (xy 410.237709 -38.780319) (xy 410.287417 -38.707174) (xy 410.344144 -38.639329)
			(xy 410.375354 -38.608) (xy 410.382269 -38.600551) (xy 410.390138 -38.581831) (xy 410.390594 -38.571678)
			(xy 410.39034 -38.499034) (xy 410.389898 -38.488875) (xy 410.382045 -38.470139) (xy 410.3751 -38.462712)
			(xy 410.343853 -38.431366) (xy 410.287061 -38.363475) (xy 410.237296 -38.290277) (xy 410.195051 -38.212496)
			(xy 410.160744 -38.130902) (xy 410.134715 -38.046303) (xy 410.117221 -37.959536) (xy 410.108435 -37.87146)
			(xy 410.107892 -37.827204) (xy 396.101824 -37.827204) (xy 402.466556 -44.191936) (xy 402.489712 -44.215816)
			(xy 402.53022 -44.268579) (xy 402.563491 -44.32618) (xy 402.588956 -44.387632) (xy 402.606179 -44.451883)
			(xy 402.614866 -44.517832) (xy 402.6154 -44.551092) (xy 402.6154 -45.212) (xy 411.377892 -45.212)
			(xy 411.378395 -45.168516) (xy 411.38688 -45.081963) (xy 411.40377 -44.996652) (xy 411.428903 -44.913395)
			(xy 411.46204 -44.832988) (xy 411.502864 -44.756197) (xy 411.550986 -44.683756) (xy 411.605946 -44.616357)
			(xy 411.63621 -44.585128) (xy 411.636464 -44.584874) (xy 411.643046 -44.577496) (xy 411.650484 -44.559192)
			(xy 411.650942 -44.549314) (xy 411.650942 -44.477686) (xy 411.650508 -44.467805) (xy 411.643049 -44.449506)
			(xy 411.636464 -44.442126) (xy 411.63621 -44.441872) (xy 411.605945 -44.410646) (xy 411.55099 -44.343243)
			(xy 411.502874 -44.2708) (xy 411.462054 -44.194009) (xy 411.428921 -44.113602) (xy 411.40379 -44.030345)
			(xy 411.386902 -43.945035) (xy 411.378418 -43.858483) (xy 411.377892 -43.815) (xy 411.378407 -43.7718)
			(xy 411.386773 -43.685806) (xy 411.403435 -43.601028) (xy 411.428238 -43.518264) (xy 411.460946 -43.438295)
			(xy 411.501253 -43.361873) (xy 411.548778 -43.289718) (xy 411.603073 -43.22251) (xy 411.663628 -43.160881)
			(xy 411.729872 -43.105414) (xy 411.801181 -43.056629) (xy 411.876884 -43.014986) (xy 411.956266 -42.980878)
			(xy 412.038581 -42.954625) (xy 412.08071 -42.94505) (xy 412.091378 -42.942764) (xy 412.10865 -42.930318)
			(xy 412.157418 -42.846498) (xy 412.159704 -42.825162) (xy 412.156402 -42.815002) (xy 412.143099 -42.771289)
			(xy 412.124447 -42.681837) (xy 412.115074 -42.590942) (xy 412.114492 -42.545254) (xy 412.114492 -42.545)
			(xy 412.114995 -42.502685) (xy 412.123026 -42.418437) (xy 412.139024 -42.335334) (xy 412.162845 -42.254125)
			(xy 412.194272 -42.175548) (xy 412.233023 -42.100311) (xy 412.255462 -42.064432) (xy 412.260345 -42.056043)
			(xy 412.264017 -42.037) (xy 412.260345 -42.017957) (xy 412.255462 -42.009568) (xy 412.233016 -41.973694)
			(xy 412.194273 -41.898453) (xy 412.162849 -41.819874) (xy 412.13903 -41.738665) (xy 412.12303 -41.655562)
			(xy 412.114994 -41.571315) (xy 412.114492 -41.529) (xy 412.114996 -41.486652) (xy 412.123047 -41.402338)
			(xy 412.139076 -41.319172) (xy 412.162937 -41.237905) (xy 412.194416 -41.159275) (xy 412.233227 -41.083994)
			(xy 412.279017 -41.012742) (xy 412.331373 -40.946166) (xy 412.389821 -40.884868) (xy 412.453831 -40.829403)
			(xy 412.522823 -40.780274) (xy 412.596173 -40.737925) (xy 412.673216 -40.702741) (xy 412.753255 -40.675039)
			(xy 412.835564 -40.655071) (xy 412.919399 -40.643018) (xy 413.004 -40.638988) (xy 413.088601 -40.643018)
			(xy 413.172436 -40.655071) (xy 413.254745 -40.675039) (xy 413.334784 -40.702741) (xy 413.337002 -40.703754)
			(xy 424.903392 -40.703754) (xy 424.903849 -40.661101) (xy 424.912002 -40.576186) (xy 424.928247 -40.492441)
			(xy 424.952436 -40.410636) (xy 424.984346 -40.331523) (xy 425.023683 -40.255829) (xy 425.070087 -40.184248)
			(xy 425.123132 -40.11744) (xy 425.182329 -40.056017) (xy 425.247135 -40.000543) (xy 425.316954 -39.951529)
			(xy 425.391145 -39.909426) (xy 425.469027 -39.874618) (xy 425.549883 -39.847428) (xy 425.632972 -39.828103)
			(xy 425.717528 -39.816823) (xy 425.760134 -39.814754) (xy 425.76984 -39.813914) (xy 425.787603 -39.805957)
			(xy 425.794678 -39.79926) (xy 425.816014 -39.77767) (xy 425.822523 -39.770396) (xy 425.829961 -39.752365)
			(xy 425.830492 -39.742618) (xy 425.831369 -39.699212) (xy 425.840651 -39.612885) (xy 425.8583 -39.527873)
			(xy 425.884147 -39.444984) (xy 425.917946 -39.365008) (xy 425.959376 -39.288706) (xy 426.008043 -39.216802)
			(xy 426.063483 -39.149982) (xy 426.125169 -39.088881) (xy 426.192515 -39.034081) (xy 426.264879 -38.986102)
			(xy 426.341574 -38.945401) (xy 426.421868 -38.912366) (xy 426.504999 -38.887311) (xy 426.590176 -38.870474)
			(xy 426.676588 -38.862015) (xy 426.72 -38.861492) (xy 426.761294 -38.861939) (xy 426.843527 -38.869567)
			(xy 426.9247 -38.884786) (xy 427.004112 -38.907464) (xy 427.08108 -38.937407) (xy 427.15494 -38.974356)
			(xy 427.225057 -39.017993) (xy 427.258226 -39.042594) (xy 427.26736 -39.048852) (xy 427.28896 -39.053611)
			(xy 427.31056 -39.048852) (xy 427.319694 -39.042594) (xy 427.327822 -39.036498) (xy 427.337035 -39.028788)
			(xy 427.347786 -39.007345) (xy 427.348396 -38.99535) (xy 427.348396 -38.989) (xy 427.348898 -38.945516)
			(xy 427.357383 -38.858963) (xy 427.374273 -38.773652) (xy 427.399407 -38.690395) (xy 427.432544 -38.609987)
			(xy 427.473368 -38.533197) (xy 427.52149 -38.460756) (xy 427.57645 -38.393357) (xy 427.606714 -38.362128)
			(xy 427.613826 -38.354762) (xy 427.621446 -38.336474) (xy 427.621446 -38.244526) (xy 427.613826 -38.226238)
			(xy 427.606714 -38.218872) (xy 427.57645 -38.187645) (xy 427.521495 -38.120242) (xy 427.473378 -38.0478)
			(xy 427.432558 -37.971009) (xy 427.399425 -37.890602) (xy 427.374295 -37.807345) (xy 427.357406 -37.722035)
			(xy 427.348922 -37.635483) (xy 427.348396 -37.592) (xy 427.348865 -37.548682) (xy 427.357268 -37.462454)
			(xy 427.374014 -37.377452) (xy 427.398946 -37.294481) (xy 427.431825 -37.214327) (xy 427.472341 -37.137748)
			(xy 427.520111 -37.065472) (xy 427.57468 -36.998182) (xy 427.635533 -36.936516) (xy 427.702093 -36.881058)
			(xy 427.77373 -36.832334) (xy 427.849763 -36.790805) (xy 427.889416 -36.773358) (xy 427.899858 -36.768323)
			(xy 427.915071 -36.750864) (xy 427.918626 -36.73983) (xy 427.92998 -36.699895) (xy 427.959056 -36.622123)
			(xy 427.995253 -36.547399) (xy 428.038254 -36.476372) (xy 428.087686 -36.409661) (xy 428.143119 -36.347846)
			(xy 428.20407 -36.291465) (xy 428.270009 -36.241008) (xy 428.340363 -36.196914) (xy 428.414519 -36.159567)
			(xy 428.491832 -36.129292) (xy 428.571629 -36.106352) (xy 428.653217 -36.090947) (xy 428.735885 -36.083211)
			(xy 428.7774 -36.082732) (xy 428.818504 -36.083152) (xy 428.900362 -36.090738) (xy 428.981171 -36.105844)
			(xy 429.060241 -36.128342) (xy 429.136898 -36.15804) (xy 429.210488 -36.194685) (xy 429.280383 -36.237963)
			(xy 429.345986 -36.287506) (xy 429.406737 -36.342891) (xy 429.46212 -36.403645) (xy 429.51166 -36.46925)
			(xy 429.554935 -36.539147) (xy 429.591576 -36.612738) (xy 429.621271 -36.689397) (xy 429.643765 -36.768468)
			(xy 429.658868 -36.849277) (xy 429.66645 -36.931136) (xy 429.666908 -36.97224) (xy 429.666385 -37.015557)
			(xy 429.657987 -37.101782) (xy 429.641246 -37.186783) (xy 429.616321 -37.269754) (xy 429.583447 -37.349908)
			(xy 429.542936 -37.426486) (xy 429.495171 -37.498762) (xy 429.440606 -37.566053) (xy 429.379757 -37.62772)
			(xy 429.313202 -37.683179) (xy 429.241569 -37.731904) (xy 429.165539 -37.773434) (xy 429.125888 -37.790882)
			(xy 429.115436 -37.7959) (xy 429.100227 -37.813371) (xy 429.096678 -37.82441) (xy 429.084062 -37.868717)
			(xy 429.050928 -37.95468) (xy 429.009085 -38.036758) (xy 428.958979 -38.114069) (xy 428.901148 -38.185785)
			(xy 428.869094 -38.218872) (xy 428.861982 -38.226238) (xy 428.854362 -38.244526) (xy 428.854362 -38.336474)
			(xy 428.861982 -38.354762) (xy 428.869094 -38.362128) (xy 428.899358 -38.393357) (xy 428.954318 -38.460757)
			(xy 429.002439 -38.533197) (xy 429.043263 -38.609988) (xy 429.0764 -38.690395) (xy 429.101533 -38.773652)
			(xy 429.118423 -38.858964) (xy 429.126908 -38.945516) (xy 429.126908 -39.032484) (xy 429.118423 -39.119036)
			(xy 429.101533 -39.204348) (xy 429.0764 -39.287605) (xy 429.043263 -39.368012) (xy 429.002439 -39.444803)
			(xy 428.954318 -39.517243) (xy 428.899358 -39.584643) (xy 428.869094 -39.615872) (xy 428.861982 -39.623238)
			(xy 428.854362 -39.641526) (xy 428.854362 -39.733474) (xy 428.861982 -39.751762) (xy 428.869094 -39.759128)
			(xy 428.900151 -39.791182) (xy 428.956375 -39.860504) (xy 429.005378 -39.935106) (xy 429.046667 -40.014239)
			(xy 429.079828 -40.097107) (xy 429.104526 -40.182878) (xy 429.120514 -40.270691) (xy 429.124618 -40.315134)
			(xy 429.125764 -40.324043) (xy 429.133265 -40.340347) (xy 429.145884 -40.353107) (xy 429.153828 -40.357298)
			(xy 429.191716 -40.375504) (xy 429.264185 -40.418108) (xy 429.332312 -40.467359) (xy 429.395488 -40.522818)
			(xy 429.45315 -40.58399) (xy 429.504783 -40.65033) (xy 429.549927 -40.721245) (xy 429.588179 -40.796103)
			(xy 429.619197 -40.874237) (xy 429.642705 -40.954948) (xy 429.658494 -41.037517) (xy 429.666421 -41.121207)
			(xy 429.666908 -41.16324) (xy 429.666385 -41.206557) (xy 429.657987 -41.292782) (xy 429.641246 -41.377783)
			(xy 429.616321 -41.460754) (xy 429.583447 -41.540908) (xy 429.542936 -41.617486) (xy 429.495171 -41.689762)
			(xy 429.440606 -41.757053) (xy 429.379757 -41.81872) (xy 429.313202 -41.874179) (xy 429.241569 -41.922904)
			(xy 429.165539 -41.964434) (xy 429.125888 -41.981882) (xy 429.115436 -41.9869) (xy 429.100227 -42.004371)
			(xy 429.096678 -42.01541) (xy 429.084062 -42.059717) (xy 429.050928 -42.14568) (xy 429.009085 -42.227758)
			(xy 428.958979 -42.305069) (xy 428.901148 -42.376785) (xy 428.869094 -42.409872) (xy 428.861982 -42.417238)
			(xy 428.854362 -42.435526) (xy 428.854362 -42.527474) (xy 428.861982 -42.545762) (xy 428.869094 -42.553128)
			(xy 428.900151 -42.585182) (xy 428.956375 -42.654504) (xy 429.005378 -42.729106) (xy 429.046667 -42.808239)
			(xy 429.079828 -42.891107) (xy 429.104526 -42.976878) (xy 429.120514 -43.064691) (xy 429.124618 -43.109134)
			(xy 429.125764 -43.118043) (xy 429.133265 -43.134347) (xy 429.145884 -43.147107) (xy 429.153828 -43.151298)
			(xy 429.191716 -43.169504) (xy 429.264185 -43.212108) (xy 429.332312 -43.261359) (xy 429.395488 -43.316818)
			(xy 429.45315 -43.37799) (xy 429.504783 -43.44433) (xy 429.549927 -43.515245) (xy 429.588179 -43.590103)
			(xy 429.619197 -43.668237) (xy 429.642705 -43.748948) (xy 429.658494 -43.831517) (xy 429.666421 -43.915207)
			(xy 429.666908 -43.95724) (xy 429.666385 -44.000557) (xy 429.657987 -44.086782) (xy 429.641246 -44.171783)
			(xy 429.616321 -44.254754) (xy 429.583447 -44.334908) (xy 429.542936 -44.411486) (xy 429.495171 -44.483762)
			(xy 429.440606 -44.551053) (xy 429.379757 -44.61272) (xy 429.313202 -44.668179) (xy 429.241569 -44.716904)
			(xy 429.165539 -44.758434) (xy 429.125888 -44.775882) (xy 429.115436 -44.7809) (xy 429.100227 -44.798371)
			(xy 429.096678 -44.80941) (xy 429.084062 -44.853717) (xy 429.050928 -44.93968) (xy 429.009085 -45.021758)
			(xy 428.958979 -45.099069) (xy 428.901148 -45.170785) (xy 428.869094 -45.203872) (xy 428.861982 -45.211238)
			(xy 428.854362 -45.229526) (xy 428.854362 -45.321474) (xy 428.861982 -45.339762) (xy 428.869094 -45.347128)
			(xy 428.89936 -45.378354) (xy 428.954314 -45.445757) (xy 429.002431 -45.518199) (xy 429.04325 -45.594991)
			(xy 429.076383 -45.675398) (xy 429.101514 -45.758654) (xy 429.118402 -45.843965) (xy 429.126886 -45.930517)
			(xy 429.127412 -45.974) (xy 430.395888 -45.974) (xy 430.396394 -45.930494) (xy 430.404888 -45.843897)
			(xy 430.421796 -45.758543) (xy 430.446954 -45.675247) (xy 430.480124 -45.594806) (xy 430.520988 -45.517986)
			(xy 430.569157 -45.445522) (xy 430.624169 -45.378107) (xy 430.65446 -45.346874) (xy 430.661826 -45.339762)
			(xy 430.669192 -45.321474) (xy 430.669446 -45.229272) (xy 430.661826 -45.210984) (xy 430.65446 -45.203872)
			(xy 430.62424 -45.172612) (xy 430.569318 -45.105202) (xy 430.521233 -45.032757) (xy 430.480444 -44.955966)
			(xy 430.44734 -44.875563) (xy 430.422237 -44.792314) (xy 430.405374 -44.707014) (xy 430.396912 -44.620476)
			(xy 430.396396 -44.577) (xy 430.396898 -44.533516) (xy 430.405383 -44.446963) (xy 430.422273 -44.361652)
			(xy 430.447407 -44.278395) (xy 430.480544 -44.197987) (xy 430.521368 -44.121197) (xy 430.56949 -44.048756)
			(xy 430.62445 -43.981357) (xy 430.654714 -43.950128) (xy 430.661826 -43.942762) (xy 430.669446 -43.924474)
			(xy 430.669446 -43.832526) (xy 430.661826 -43.814238) (xy 430.654714 -43.806872) (xy 430.624453 -43.775642)
			(xy 430.569499 -43.70824) (xy 430.521382 -43.635798) (xy 430.480562 -43.559007) (xy 430.447429 -43.4786)
			(xy 430.422299 -43.395344) (xy 430.405411 -43.310034) (xy 430.396927 -43.223483) (xy 430.396927 -43.136517)
			(xy 430.405411 -43.049966) (xy 430.422299 -42.964656) (xy 430.447429 -42.8814) (xy 430.480562 -42.800993)
			(xy 430.521382 -42.724202) (xy 430.569499 -42.65176) (xy 430.624453 -42.584358) (xy 430.654714 -42.553128)
			(xy 430.661826 -42.545762) (xy 430.669446 -42.527474) (xy 430.669446 -42.435526) (xy 430.661826 -42.417238)
			(xy 430.654714 -42.409872) (xy 430.624453 -42.378642) (xy 430.569499 -42.31124) (xy 430.521382 -42.238798)
			(xy 430.480562 -42.162007) (xy 430.447429 -42.0816) (xy 430.422299 -41.998344) (xy 430.405411 -41.913034)
			(xy 430.396927 -41.826483) (xy 430.396927 -41.739517) (xy 430.405411 -41.652966) (xy 430.422299 -41.567656)
			(xy 430.447429 -41.4844) (xy 430.480562 -41.403993) (xy 430.521382 -41.327202) (xy 430.569499 -41.25476)
			(xy 430.624453 -41.187358) (xy 430.654714 -41.156128) (xy 430.661826 -41.148762) (xy 430.669446 -41.130474)
			(xy 430.669446 -41.038526) (xy 430.661826 -41.020238) (xy 430.654714 -41.012872) (xy 430.624453 -40.981642)
			(xy 430.569499 -40.91424) (xy 430.521382 -40.841798) (xy 430.480562 -40.765007) (xy 430.447429 -40.6846)
			(xy 430.422299 -40.601344) (xy 430.405411 -40.516034) (xy 430.396927 -40.429483) (xy 430.396927 -40.342517)
			(xy 430.405411 -40.255966) (xy 430.422299 -40.170656) (xy 430.447429 -40.0874) (xy 430.480562 -40.006993)
			(xy 430.521382 -39.930202) (xy 430.569499 -39.85776) (xy 430.624453 -39.790358) (xy 430.654714 -39.759128)
			(xy 430.661826 -39.751762) (xy 430.669446 -39.733474) (xy 430.669446 -39.641526) (xy 430.661826 -39.623238)
			(xy 430.654714 -39.615872) (xy 430.624453 -39.584642) (xy 430.569499 -39.51724) (xy 430.521382 -39.444798)
			(xy 430.480562 -39.368007) (xy 430.447429 -39.2876) (xy 430.422299 -39.204344) (xy 430.405411 -39.119034)
			(xy 430.396927 -39.032483) (xy 430.396927 -38.945517) (xy 430.405411 -38.858966) (xy 430.422299 -38.773656)
			(xy 430.447429 -38.6904) (xy 430.480562 -38.609993) (xy 430.521382 -38.533202) (xy 430.569499 -38.46076)
			(xy 430.624453 -38.393358) (xy 430.654714 -38.362128) (xy 430.661826 -38.354762) (xy 430.669446 -38.336474)
			(xy 430.669446 -38.244526) (xy 430.661826 -38.226238) (xy 430.654714 -38.218872) (xy 430.62445 -38.187645)
			(xy 430.569495 -38.120242) (xy 430.521378 -38.0478) (xy 430.480558 -37.971009) (xy 430.447425 -37.890602)
			(xy 430.422295 -37.807345) (xy 430.405406 -37.722035) (xy 430.396922 -37.635483) (xy 430.396396 -37.592)
			(xy 430.3969 -37.549652) (xy 430.404951 -37.465338) (xy 430.42098 -37.382172) (xy 430.444841 -37.300905)
			(xy 430.47632 -37.222275) (xy 430.515131 -37.146994) (xy 430.560921 -37.075742) (xy 430.613277 -37.009166)
			(xy 430.671725 -36.947868) (xy 430.735735 -36.892403) (xy 430.804727 -36.843274) (xy 430.878077 -36.800925)
			(xy 430.95512 -36.765741) (xy 431.035159 -36.738039) (xy 431.117468 -36.718071) (xy 431.201303 -36.706018)
			(xy 431.285904 -36.701988) (xy 431.370505 -36.706018) (xy 431.45434 -36.718071) (xy 431.536649 -36.738039)
			(xy 431.616688 -36.765741) (xy 431.693731 -36.800925) (xy 431.767081 -36.843274) (xy 431.836073 -36.892403)
			(xy 431.900083 -36.947868) (xy 431.958531 -37.009166) (xy 432.010887 -37.075742) (xy 432.056677 -37.146994)
			(xy 432.095488 -37.222275) (xy 432.126967 -37.300905) (xy 432.150828 -37.382172) (xy 432.166857 -37.465338)
			(xy 432.174908 -37.549652) (xy 432.175412 -37.592) (xy 432.174908 -37.635484) (xy 432.166423 -37.722036)
			(xy 432.149533 -37.807348) (xy 432.1244 -37.890605) (xy 432.091263 -37.971012) (xy 432.050439 -38.047803)
			(xy 432.002318 -38.120243) (xy 431.947358 -38.187643) (xy 431.917094 -38.218872) (xy 431.909982 -38.226238)
			(xy 431.902362 -38.244526) (xy 431.902362 -38.336474) (xy 431.909982 -38.354762) (xy 431.917094 -38.362128)
			(xy 431.94736 -38.393354) (xy 432.002314 -38.460757) (xy 432.050431 -38.533199) (xy 432.09125 -38.609991)
			(xy 432.124383 -38.690398) (xy 432.149514 -38.773654) (xy 432.166402 -38.858965) (xy 432.174886 -38.945517)
			(xy 432.175412 -38.989) (xy 432.17503 -39.027398) (xy 432.168422 -39.10391) (xy 432.155236 -39.179566)
			(xy 432.135572 -39.253802) (xy 432.109576 -39.326065) (xy 432.093878 -39.36111) (xy 432.088798 -39.372286)
			(xy 432.089814 -39.396162) (xy 432.140868 -39.489126) (xy 432.16068 -39.502588) (xy 432.172618 -39.504366)
			(xy 432.214775 -39.51063) (xy 432.297771 -39.530031) (xy 432.37853 -39.55728) (xy 432.456313 -39.592128)
			(xy 432.530407 -39.634256) (xy 432.600131 -39.683277) (xy 432.664847 -39.738743) (xy 432.723962 -39.800144)
			(xy 432.776933 -39.866917) (xy 432.823275 -39.93845) (xy 432.862562 -40.014088) (xy 432.894436 -40.093137)
			(xy 432.905926 -40.132) (xy 433.348892 -40.132) (xy 433.349462 -40.089647) (xy 433.357521 -40.005325)
			(xy 433.373557 -39.922151) (xy 433.397424 -39.840877) (xy 433.428907 -39.762239) (xy 433.46772 -39.686948)
			(xy 433.513512 -39.615687) (xy 433.565869 -39.5491) (xy 433.624317 -39.487789) (xy 433.688327 -39.432311)
			(xy 433.75732 -39.383166) (xy 433.83067 -39.340801) (xy 433.907714 -39.305597) (xy 433.94757 -39.29126)
			(xy 433.957476 -39.287958) (xy 433.972462 -39.274496) (xy 434.012594 -39.19093) (xy 434.01361 -39.17061)
			(xy 434.010054 -39.160958) (xy 433.99765 -39.124917) (xy 433.978312 -39.051183) (xy 433.965356 -38.976065)
			(xy 433.958875 -38.900114) (xy 433.958492 -38.862) (xy 433.958967 -38.820898) (xy 433.966552 -38.739043)
			(xy 433.981657 -38.658238) (xy 434.004153 -38.579171) (xy 434.033849 -38.502517) (xy 434.070491 -38.42893)
			(xy 434.113766 -38.359038) (xy 434.163306 -38.293437) (xy 434.218687 -38.232687) (xy 434.279437 -38.177306)
			(xy 434.345038 -38.127766) (xy 434.41493 -38.084491) (xy 434.488517 -38.047849) (xy 434.565171 -38.018153)
			(xy 434.644238 -37.995657) (xy 434.725043 -37.980552) (xy 434.806898 -37.972967) (xy 434.848 -37.972492)
			(xy 434.892139 -37.973032) (xy 434.979983 -37.981754) (xy 435.066531 -37.999141) (xy 435.150928 -38.025024)
			(xy 435.232344 -38.059145) (xy 435.271418 -38.07968) (xy 435.282949 -38.085107) (xy 435.308401 -38.085107)
			(xy 435.319932 -38.07968) (xy 435.359002 -38.059138) (xy 435.440426 -38.02504) (xy 435.524825 -37.999168)
			(xy 435.61137 -37.981776) (xy 435.699212 -37.973035) (xy 435.74335 -37.972492) (xy 435.784455 -37.97306)
			(xy 435.866314 -37.98064) (xy 435.947124 -37.995738) (xy 436.026198 -38.018227) (xy 436.102859 -38.047915)
			(xy 436.176455 -38.084549) (xy 436.246357 -38.127816) (xy 436.31197 -38.177346) (xy 436.372733 -38.232719)
			(xy 436.42813 -38.293461) (xy 436.477686 -38.359054) (xy 436.520981 -38.428939) (xy 436.557643 -38.502521)
			(xy 436.587361 -38.57917) (xy 436.609882 -38.658235) (xy 436.625012 -38.73904) (xy 436.632624 -38.820896)
			(xy 436.633112 -38.862) (xy 436.632616 -38.903508) (xy 436.624887 -38.986163) (xy 436.609496 -39.06774)
			(xy 436.586577 -39.147529) (xy 436.571898 -39.186358) (xy 436.568088 -39.195756) (xy 436.568342 -39.21506)
			(xy 436.60314 -39.298626) (xy 436.616602 -39.312342) (xy 436.625746 -39.316406) (xy 436.648352 -39.326566)
			(xy 436.658873 -39.33086) (xy 436.681569 -39.330715) (xy 436.701996 -39.320819) (xy 436.709566 -39.312342)
			(xy 436.737666 -39.278128) (xy 436.799612 -39.214862) (xy 436.867536 -39.158062) (xy 436.940766 -39.108289)
			(xy 437.018577 -39.066037) (xy 437.100201 -39.031722) (xy 437.184829 -39.005685) (xy 437.271625 -38.988182)
			(xy 437.35973 -38.979388) (xy 437.404002 -38.97884) (xy 437.434482 -38.979348) (xy 437.44515 -38.979602)
			(xy 437.4642 -38.972236) (xy 437.532018 -38.905688) (xy 437.539892 -38.886638) (xy 437.539638 -38.87597)
			(xy 437.539384 -38.862) (xy 437.539888 -38.819639) (xy 437.547941 -38.735302) (xy 437.563975 -38.652112)
			(xy 437.587843 -38.570822) (xy 437.619331 -38.49217) (xy 437.658153 -38.416867) (xy 437.703956 -38.345595)
			(xy 437.756327 -38.278999) (xy 437.814792 -38.217684) (xy 437.87882 -38.162203) (xy 437.947832 -38.11306)
			(xy 438.021202 -38.0707) (xy 438.098267 -38.035505) (xy 438.178329 -38.007796) (xy 438.260662 -37.987822)
			(xy 438.344521 -37.975765) (xy 438.429146 -37.971734) (xy 438.513771 -37.975765) (xy 438.59763 -37.987822)
			(xy 438.679963 -38.007796) (xy 438.760025 -38.035505) (xy 438.83709 -38.0707) (xy 438.91046 -38.11306)
			(xy 438.979472 -38.162203) (xy 439.0435 -38.217684) (xy 439.101965 -38.278999) (xy 439.154336 -38.345595)
			(xy 439.200139 -38.416867) (xy 439.238961 -38.49217) (xy 439.270449 -38.570822) (xy 439.294317 -38.652112)
			(xy 439.310351 -38.735302) (xy 439.318404 -38.819639) (xy 439.318908 -38.862) (xy 439.318482 -38.901272)
			(xy 439.311547 -38.97951) (xy 439.29774 -39.056832) (xy 439.277168 -39.132635) (xy 439.249992 -39.206328)
			(xy 439.216424 -39.277338) (xy 439.176725 -39.345112) (xy 439.154316 -39.377366) (xy 439.145934 -39.389304)
			(xy 439.144156 -39.418006) (xy 439.184406 -39.492936) (xy 447.147188 -39.492936) (xy 447.147701 -39.451842)
			(xy 447.155279 -39.370003) (xy 447.170376 -39.289213) (xy 447.192861 -39.21016) (xy 447.222544 -39.133518)
			(xy 447.25917 -39.059942) (xy 447.302428 -38.990058) (xy 447.351948 -38.924463) (xy 447.407308 -38.863716)
			(xy 447.468037 -38.808336) (xy 447.533616 -38.758794) (xy 447.603485 -38.715513) (xy 447.677049 -38.678862)
			(xy 447.753681 -38.649155) (xy 447.832727 -38.626643) (xy 447.913512 -38.61152) (xy 447.995348 -38.603914)
			(xy 448.036442 -38.603428) (xy 448.03695 -38.603428) (xy 448.076051 -38.60384) (xy 448.153949 -38.610713)
			(xy 448.230944 -38.624401) (xy 448.306438 -38.644798) (xy 448.379849 -38.671748) (xy 448.41541 -38.68801)
			(xy 448.425797 -38.692245) (xy 448.448203 -38.692245) (xy 448.45859 -38.68801) (xy 448.494158 -38.671767)
			(xy 448.567573 -38.644836) (xy 448.643066 -38.624445) (xy 448.720056 -38.610754) (xy 448.797951 -38.603866)
			(xy 448.83705 -38.603428) (xy 448.880623 -38.603997) (xy 448.967349 -38.612531) (xy 449.052826 -38.629502)
			(xy 449.136234 -38.654748) (xy 449.216775 -38.688026) (xy 449.293677 -38.729019) (xy 449.366204 -38.777333)
			(xy 449.433659 -38.832506) (xy 449.495399 -38.894008) (xy 449.55083 -38.961252) (xy 449.599422 -39.033592)
			(xy 449.64071 -39.110336) (xy 449.674297 -39.190749) (xy 449.699863 -39.27406) (xy 449.709032 -39.31666)
			(xy 449.712222 -39.328624) (xy 449.727909 -39.347734) (xy 449.739004 -39.353236) (xy 449.82765 -39.391082)
			(xy 449.852796 -39.38905) (xy 449.86321 -39.382192) (xy 449.898948 -39.359945) (xy 449.973876 -39.321561)
			(xy 450.052096 -39.290429) (xy 450.132908 -39.266828) (xy 450.215589 -39.250969) (xy 450.299398 -39.242993)
			(xy 450.341492 -39.242492) (xy 450.342 -39.242492) (xy 450.384348 -39.242996) (xy 450.468662 -39.251047)
			(xy 450.551828 -39.267076) (xy 450.633095 -39.290937) (xy 450.711725 -39.322416) (xy 450.787006 -39.361227)
			(xy 450.858258 -39.407017) (xy 450.924834 -39.459373) (xy 450.986132 -39.517821) (xy 451.041597 -39.581831)
			(xy 451.090726 -39.650823) (xy 451.133075 -39.724173) (xy 451.168259 -39.801216) (xy 451.195961 -39.881255)
			(xy 451.215929 -39.963564) (xy 451.227982 -40.047399) (xy 451.232013 -40.132) (xy 451.227982 -40.216601)
			(xy 451.215929 -40.300436) (xy 451.195961 -40.382745) (xy 451.168259 -40.462784) (xy 451.133075 -40.539827)
			(xy 451.090726 -40.613177) (xy 451.041597 -40.682169) (xy 450.986132 -40.746179) (xy 450.924834 -40.804627)
			(xy 450.858258 -40.856983) (xy 450.787006 -40.902773) (xy 450.711725 -40.941584) (xy 450.633095 -40.973063)
			(xy 450.551828 -40.996924) (xy 450.468662 -41.012953) (xy 450.384348 -41.021004) (xy 450.342 -41.021508)
			(xy 450.341492 -41.021508) (xy 450.300376 -41.021023) (xy 450.218496 -41.013418) (xy 450.137667 -40.99829)
			(xy 450.058578 -40.97577) (xy 449.981904 -40.94605) (xy 449.9083 -40.909382) (xy 449.838391 -40.866081)
			(xy 449.805298 -40.841676) (xy 449.796103 -40.835417) (xy 449.774391 -40.830712) (xy 449.752717 -40.835594)
			(xy 449.743576 -40.84193) (xy 449.710174 -40.867181) (xy 449.639436 -40.911999) (xy 449.564799 -40.949969)
			(xy 449.486924 -40.980757) (xy 449.4065 -41.00409) (xy 449.32424 -41.019761) (xy 449.24087 -41.027631)
			(xy 449.199 -41.028112) (xy 449.157488 -41.02762) (xy 449.074828 -41.019852) (xy 448.993252 -41.004412)
			(xy 448.913471 -40.981434) (xy 448.836179 -40.951119) (xy 448.76205 -40.91373) (xy 448.69173 -40.869593)
			(xy 448.658488 -40.844724) (xy 448.649289 -40.838381) (xy 448.6275 -40.83355) (xy 448.605711 -40.838381)
			(xy 448.596512 -40.844724) (xy 448.563254 -40.869568) (xy 448.492928 -40.91369) (xy 448.418799 -40.951069)
			(xy 448.34151 -40.981382) (xy 448.261734 -41.004365) (xy 448.180164 -41.019817) (xy 448.09751 -41.027605)
			(xy 448.056 -41.028112) (xy 448.014889 -41.027648) (xy 447.933019 -41.02006) (xy 447.852199 -41.004949)
			(xy 447.773118 -40.982444) (xy 447.696451 -40.952738) (xy 447.622853 -40.916082) (xy 447.552951 -40.872792)
			(xy 447.487343 -40.823235) (xy 447.426588 -40.767835) (xy 447.371205 -40.707065) (xy 447.321667 -40.641443)
			(xy 447.278396 -40.571529) (xy 447.241761 -40.49792) (xy 447.212076 -40.421245) (xy 447.189594 -40.342158)
			(xy 447.174506 -40.261333) (xy 447.166941 -40.179461) (xy 447.166492 -40.13835) (xy 447.167083 -40.090752)
			(xy 447.177179 -39.996095) (xy 447.197317 -39.903055) (xy 447.211704 -39.85768) (xy 447.214202 -39.849115)
			(xy 447.213673 -39.83129) (xy 447.210688 -39.822882) (xy 447.195473 -39.783451) (xy 447.171711 -39.702337)
			(xy 447.155739 -39.619337) (xy 447.147701 -39.535197) (xy 447.147188 -39.492936) (xy 439.184406 -39.492936)
			(xy 439.201052 -39.523924) (xy 439.225944 -39.538148) (xy 439.240422 -39.53764) (xy 439.270394 -39.537132)
			(xy 439.311508 -39.537619) (xy 439.393385 -39.545205) (xy 439.474213 -39.560314) (xy 439.553302 -39.582816)
			(xy 439.629978 -39.61252) (xy 439.703585 -39.649171) (xy 439.773497 -39.692458) (xy 439.839117 -39.742011)
			(xy 439.899884 -39.797407) (xy 439.955281 -39.858174) (xy 440.004835 -39.923793) (xy 440.048123 -39.993704)
			(xy 440.084775 -40.067312) (xy 440.11448 -40.143987) (xy 440.136983 -40.223075) (xy 440.152093 -40.303903)
			(xy 440.159681 -40.38578) (xy 440.160156 -40.426894) (xy 440.159715 -40.468897) (xy 440.15178 -40.552529)
			(xy 440.135998 -40.63504) (xy 440.112511 -40.715697) (xy 440.081528 -40.793782) (xy 440.043323 -40.868599)
			(xy 439.998238 -40.939483) (xy 439.946673 -41.005802) (xy 439.889088 -41.066967) (xy 439.825994 -41.122432)
			(xy 439.757955 -41.171705) (xy 439.685575 -41.214346) (xy 439.609498 -41.249977) (xy 439.570114 -41.264586)
			(xy 439.560208 -41.268142) (xy 439.545222 -41.282112) (xy 439.50636 -41.36771) (xy 439.506106 -41.388284)
			(xy 439.509916 -41.397936) (xy 439.525047 -41.437285) (xy 439.548666 -41.51822) (xy 439.564512 -41.601028)
			(xy 439.572441 -41.684964) (xy 439.572908 -41.72712) (xy 439.572404 -41.769468) (xy 439.564353 -41.853782)
			(xy 439.548324 -41.936948) (xy 439.524463 -42.018215) (xy 439.492984 -42.096845) (xy 439.454173 -42.172126)
			(xy 439.408383 -42.243378) (xy 439.356027 -42.309954) (xy 439.297579 -42.371252) (xy 439.233569 -42.426717)
			(xy 439.164577 -42.475846) (xy 439.091227 -42.518195) (xy 439.014184 -42.553379) (xy 438.934145 -42.581081)
			(xy 438.851836 -42.601049) (xy 438.768001 -42.613102) (xy 438.6834 -42.617133) (xy 438.598799 -42.613102)
			(xy 438.514964 -42.601049) (xy 438.432655 -42.581081) (xy 438.352616 -42.553379) (xy 438.275573 -42.518195)
			(xy 438.202223 -42.475846) (xy 438.133231 -42.426717) (xy 438.069221 -42.371252) (xy 438.010773 -42.309954)
			(xy 437.958417 -42.243378) (xy 437.912627 -42.172126) (xy 437.873816 -42.096845) (xy 437.842337 -42.018215)
			(xy 437.818476 -41.936948) (xy 437.802447 -41.853782) (xy 437.794396 -41.769468) (xy 437.793892 -41.72712)
			(xy 437.794341 -41.685123) (xy 437.802255 -41.601502) (xy 437.818014 -41.518999) (xy 437.84148 -41.438348)
			(xy 437.872441 -41.360268) (xy 437.910623 -41.285454) (xy 437.955686 -41.214571) (xy 438.007229 -41.14825)
			(xy 438.064793 -41.087082) (xy 438.127866 -41.031612) (xy 438.195885 -40.982332) (xy 438.268246 -40.939683)
			(xy 438.344305 -40.904043) (xy 438.38368 -40.889428) (xy 438.393586 -40.885872) (xy 438.408572 -40.871902)
			(xy 438.447434 -40.786304) (xy 438.447688 -40.76573) (xy 438.443878 -40.756078) (xy 438.428714 -40.716735)
			(xy 438.405041 -40.635805) (xy 438.389134 -40.552997) (xy 438.381136 -40.469055) (xy 438.380632 -40.426894)
			(xy 438.381066 -40.387622) (xy 438.388001 -40.309385) (xy 438.401808 -40.232063) (xy 438.422378 -40.156261)
			(xy 438.449553 -40.082567) (xy 438.483119 -40.011557) (xy 438.522816 -39.943783) (xy 438.545224 -39.911528)
			(xy 438.553606 -39.89959) (xy 438.555384 -39.870888) (xy 438.498488 -39.76497) (xy 438.473596 -39.750746)
			(xy 438.459118 -39.751254) (xy 438.429146 -39.751508) (xy 438.398666 -39.751) (xy 438.387998 -39.750746)
			(xy 438.368948 -39.758112) (xy 438.30113 -39.82466) (xy 438.293256 -39.84371) (xy 438.29351 -39.854378)
			(xy 438.293764 -39.868348) (xy 438.293393 -39.909461) (xy 438.285801 -39.991335) (xy 438.270685 -40.072159)
			(xy 438.248175 -40.151243) (xy 438.218462 -40.227913) (xy 438.181801 -40.301513) (xy 438.138504 -40.371416)
			(xy 438.088941 -40.437025) (xy 438.033535 -40.49778) (xy 437.972758 -40.553162) (xy 437.90713 -40.6027)
			(xy 437.83721 -40.645969) (xy 437.763596 -40.682602) (xy 437.686915 -40.712285) (xy 437.607822 -40.734764)
			(xy 437.526992 -40.749848) (xy 437.445115 -40.757409) (xy 437.404002 -40.757856) (xy 437.364965 -40.757435)
			(xy 437.287187 -40.750631) (xy 437.210305 -40.737039) (xy 437.134909 -40.716764) (xy 437.061578 -40.689963)
			(xy 437.02605 -40.673782) (xy 437.015524 -40.669507) (xy 436.992834 -40.669652) (xy 436.97241 -40.679536)
			(xy 436.964836 -40.688006) (xy 436.936721 -40.722208) (xy 436.874778 -40.785476) (xy 436.806857 -40.842278)
			(xy 436.733629 -40.892053) (xy 436.65582 -40.934307) (xy 436.574198 -40.968623) (xy 436.489571 -40.994661)
			(xy 436.402776 -41.012165) (xy 436.314671 -41.02096) (xy 436.2704 -41.021508) (xy 436.229298 -41.021033)
			(xy 436.147443 -41.013448) (xy 436.066638 -40.998343) (xy 435.987571 -40.975847) (xy 435.910917 -40.946151)
			(xy 435.83733 -40.909509) (xy 435.767438 -40.866234) (xy 435.701837 -40.816694) (xy 435.641087 -40.761313)
			(xy 435.585706 -40.700563) (xy 435.536166 -40.634962) (xy 435.492891 -40.56507) (xy 435.456249 -40.491483)
			(xy 435.426553 -40.414829) (xy 435.404057 -40.335762) (xy 435.388952 -40.254957) (xy 435.381367 -40.173102)
			(xy 435.380892 -40.132) (xy 435.381329 -40.090497) (xy 435.389007 -40.007848) (xy 435.404343 -39.926272)
			(xy 435.427203 -39.846476) (xy 435.441852 -39.807642) (xy 435.445662 -39.798244) (xy 435.445408 -39.77894)
			(xy 435.41061 -39.695374) (xy 435.397148 -39.681658) (xy 435.388004 -39.677594) (xy 435.370681 -39.669914)
			(xy 435.336632 -39.653273) (xy 435.319932 -39.64432) (xy 435.31236 -39.640531) (xy 435.295675 -39.637713)
			(xy 435.27899 -39.640531) (xy 435.271418 -39.64432) (xy 435.239359 -39.661282) (xy 435.172983 -39.690531)
			(xy 435.13883 -39.70274) (xy 435.128924 -39.706042) (xy 435.113938 -39.719504) (xy 435.073806 -39.80307)
			(xy 435.07279 -39.82339) (xy 435.076346 -39.833042) (xy 435.08875 -39.869083) (xy 435.108088 -39.942817)
			(xy 435.121044 -40.017935) (xy 435.127525 -40.093886) (xy 435.127908 -40.132) (xy 435.127404 -40.174348)
			(xy 435.119353 -40.258662) (xy 435.103324 -40.341828) (xy 435.079463 -40.423095) (xy 435.047984 -40.501725)
			(xy 435.009173 -40.577006) (xy 434.963383 -40.648258) (xy 434.911027 -40.714834) (xy 434.852579 -40.776132)
			(xy 434.788569 -40.831597) (xy 434.719577 -40.880726) (xy 434.646227 -40.923075) (xy 434.569184 -40.958259)
			(xy 434.489145 -40.985961) (xy 434.406836 -41.005929) (xy 434.323001 -41.017982) (xy 434.2384 -41.022013)
			(xy 434.153799 -41.017982) (xy 434.069964 -41.005929) (xy 433.987655 -40.985961) (xy 433.907616 -40.958259)
			(xy 433.830573 -40.923075) (xy 433.757223 -40.880726) (xy 433.688231 -40.831597) (xy 433.624221 -40.776132)
			(xy 433.565773 -40.714834) (xy 433.513417 -40.648258) (xy 433.467627 -40.577006) (xy 433.428816 -40.501725)
			(xy 433.397337 -40.423095) (xy 433.373476 -40.341828) (xy 433.357447 -40.258662) (xy 433.349396 -40.174348)
			(xy 433.348892 -40.132) (xy 432.905926 -40.132) (xy 432.918602 -40.174871) (xy 432.934841 -40.258543)
			(xy 432.943002 -40.343384) (xy 432.943508 -40.386) (xy 432.943005 -40.429484) (xy 432.93452 -40.516037)
			(xy 432.91763 -40.601348) (xy 432.892497 -40.684605) (xy 432.85936 -40.765012) (xy 432.818536 -40.841803)
			(xy 432.770414 -40.914244) (xy 432.715454 -40.981643) (xy 432.68519 -41.012872) (xy 432.678078 -41.020238)
			(xy 432.670458 -41.038526) (xy 432.670458 -41.130474) (xy 432.678078 -41.148762) (xy 432.68519 -41.156128)
			(xy 432.715455 -41.187354) (xy 432.77041 -41.254757) (xy 432.818526 -41.3272) (xy 432.859346 -41.403991)
			(xy 432.892479 -41.484398) (xy 432.91761 -41.567655) (xy 432.934498 -41.652965) (xy 432.942982 -41.739517)
			(xy 432.943508 -41.783) (xy 432.943036 -41.824964) (xy 432.93513 -41.90852) (xy 432.919389 -41.99096)
			(xy 432.895953 -42.07155) (xy 432.865029 -42.149574) (xy 432.826894 -42.224339) (xy 432.781886 -42.295179)
			(xy 432.730405 -42.361465) (xy 432.67291 -42.422606) (xy 432.60991 -42.47806) (xy 432.576224 -42.50309)
			(xy 432.563778 -42.512234) (xy 432.55311 -42.540682) (xy 432.580796 -42.661586) (xy 432.602894 -42.682668)
			(xy 432.61788 -42.685462) (xy 432.658446 -42.693258) (xy 432.738043 -42.715372) (xy 432.815246 -42.744771)
			(xy 432.889392 -42.781199) (xy 432.959842 -42.824344) (xy 432.982586 -42.841361) (xy 434.854092 -42.841361)
			(xy 434.854092 -42.756639) (xy 434.862145 -42.672302) (xy 434.878179 -42.589112) (xy 434.902047 -42.507822)
			(xy 434.933535 -42.42917) (xy 434.972357 -42.353867) (xy 435.01816 -42.282595) (xy 435.070531 -42.215999)
			(xy 435.128996 -42.154684) (xy 435.193024 -42.099203) (xy 435.262036 -42.05006) (xy 435.335406 -42.0077)
			(xy 435.412471 -41.972505) (xy 435.492533 -41.944796) (xy 435.574866 -41.924822) (xy 435.658725 -41.912765)
			(xy 435.74335 -41.908734) (xy 435.827975 -41.912765) (xy 435.911834 -41.924822) (xy 435.994167 -41.944796)
			(xy 436.074229 -41.972505) (xy 436.151294 -42.0077) (xy 436.224664 -42.05006) (xy 436.293676 -42.099203)
			(xy 436.357704 -42.154684) (xy 436.416169 -42.215999) (xy 436.46854 -42.282595) (xy 436.514343 -42.353867)
			(xy 436.553165 -42.42917) (xy 436.584653 -42.507822) (xy 436.608521 -42.589112) (xy 436.624555 -42.672302)
			(xy 436.632608 -42.756639) (xy 436.633112 -42.799) (xy 436.632608 -42.841361) (xy 436.624555 -42.925698)
			(xy 436.608521 -43.008888) (xy 436.584653 -43.090178) (xy 436.553165 -43.16883) (xy 436.514343 -43.244133)
			(xy 436.46854 -43.315405) (xy 436.416169 -43.382001) (xy 436.357704 -43.443316) (xy 436.293676 -43.498797)
			(xy 436.224664 -43.54794) (xy 436.151294 -43.5903) (xy 436.074229 -43.625495) (xy 435.994167 -43.653204)
			(xy 435.911834 -43.673178) (xy 435.827975 -43.685235) (xy 435.74335 -43.689267) (xy 435.658725 -43.685235)
			(xy 435.574866 -43.673178) (xy 435.492533 -43.653204) (xy 435.412471 -43.625495) (xy 435.335406 -43.5903)
			(xy 435.262036 -43.54794) (xy 435.193024 -43.498797) (xy 435.128996 -43.443316) (xy 435.070531 -43.382001)
			(xy 435.01816 -43.315405) (xy 434.972357 -43.244133) (xy 434.933535 -43.16883) (xy 434.902047 -43.090178)
			(xy 434.878179 -43.008888) (xy 434.862145 -42.925698) (xy 434.854092 -42.841361) (xy 432.982586 -42.841361)
			(xy 433.025989 -42.873834) (xy 433.087263 -42.929243) (xy 433.143137 -42.990093) (xy 433.193129 -43.055861)
			(xy 433.236809 -43.12598) (xy 433.273802 -43.199846) (xy 433.303787 -43.276824) (xy 433.326507 -43.35625)
			(xy 433.341767 -43.437439) (xy 433.349434 -43.519694) (xy 433.349908 -43.561) (xy 433.349427 -43.604607)
			(xy 433.340894 -43.691403) (xy 433.323909 -43.776948) (xy 433.298635 -43.86042) (xy 433.265316 -43.941018)
			(xy 433.224271 -44.017971) (xy 433.175893 -44.090537) (xy 433.120647 -44.158022) (xy 433.059063 -44.219778)
			(xy 432.991733 -44.275212) (xy 432.919301 -44.323792) (xy 432.842464 -44.365052) (xy 432.761959 -44.398596)
			(xy 432.678557 -44.424103) (xy 432.635914 -44.433236) (xy 432.620928 -44.436284) (xy 432.599592 -44.457366)
			(xy 432.573684 -44.57827) (xy 432.584352 -44.606464) (xy 432.596798 -44.615354) (xy 432.630864 -44.640375)
			(xy 432.694646 -44.695844) (xy 432.752879 -44.757114) (xy 432.805037 -44.82363) (xy 432.850651 -44.894795)
			(xy 432.889308 -44.969965) (xy 432.920661 -45.048464) (xy 432.944427 -45.129582) (xy 432.960391 -45.212589)
			(xy 432.968409 -45.296736) (xy 432.968908 -45.339) (xy 432.96842 -45.38279) (xy 432.959855 -45.469949)
			(xy 432.94276 -45.555843) (xy 432.93147 -45.593) (xy 436.015892 -45.593) (xy 436.016324 -45.551263)
			(xy 436.024115 -45.468153) (xy 436.039658 -45.386139) (xy 436.062814 -45.305941) (xy 436.093381 -45.228265)
			(xy 436.131089 -45.153794) (xy 436.175608 -45.083183) (xy 436.226545 -45.017052) (xy 436.254652 -44.986194)
			(xy 436.261907 -44.977668) (xy 436.268823 -44.956402) (xy 436.266005 -44.934218) (xy 436.260494 -44.924472)
			(xy 436.238672 -44.888926) (xy 436.201021 -44.814492) (xy 436.1705 -44.736861) (xy 436.147376 -44.656716)
			(xy 436.131853 -44.574758) (xy 436.124066 -44.491707) (xy 436.123588 -44.45) (xy 436.124092 -44.407652)
			(xy 436.132143 -44.323338) (xy 436.148172 -44.240172) (xy 436.172033 -44.158905) (xy 436.203512 -44.080275)
			(xy 436.242323 -44.004994) (xy 436.288113 -43.933742) (xy 436.340469 -43.867166) (xy 436.398917 -43.805868)
			(xy 436.462927 -43.750403) (xy 436.531919 -43.701274) (xy 436.605269 -43.658925) (xy 436.682312 -43.623741)
			(xy 436.762351 -43.596039) (xy 436.84466 -43.576071) (xy 436.928495 -43.564018) (xy 437.013096 -43.559988)
			(xy 437.097697 -43.564018) (xy 437.181532 -43.576071) (xy 437.263841 -43.596039) (xy 437.34388 -43.623741)
			(xy 437.420923 -43.658925) (xy 437.494273 -43.701274) (xy 437.563265 -43.750403) (xy 437.627275 -43.805868)
			(xy 437.685723 -43.867166) (xy 437.738079 -43.933742) (xy 437.783869 -44.004994) (xy 437.82268 -44.080275)
			(xy 437.854159 -44.158905) (xy 437.87802 -44.240172) (xy 437.894049 -44.323338) (xy 437.9021 -44.407652)
			(xy 437.902604 -44.45) (xy 438.142687 -44.45) (xy 438.146717 -44.365402) (xy 438.15877 -44.28157)
			(xy 438.178737 -44.199263) (xy 438.206436 -44.119227) (xy 438.241618 -44.042186) (xy 438.283964 -43.968838)
			(xy 438.33309 -43.899847) (xy 438.388551 -43.835839) (xy 438.449845 -43.777391) (xy 438.516417 -43.725035)
			(xy 438.587665 -43.679243) (xy 438.662942 -43.640431) (xy 438.741568 -43.60895) (xy 438.82283 -43.585086)
			(xy 438.905993 -43.569053) (xy 438.990303 -43.560998) (xy 439.03265 -43.560492) (xy 439.078005 -43.561066)
			(xy 439.168244 -43.570295) (xy 439.257077 -43.588653) (xy 439.343582 -43.615948) (xy 439.426864 -43.651898)
			(xy 439.466736 -43.673522) (xy 439.475346 -43.67781) (xy 439.494402 -43.6803) (xy 439.50382 -43.678348)
			(xy 439.53303 -43.671236) (xy 439.542271 -43.668587) (xy 439.557946 -43.657486) (xy 439.56351 -43.649646)
			(xy 439.588129 -43.61293) (xy 439.643482 -43.543998) (xy 439.705398 -43.480897) (xy 439.773269 -43.424249)
			(xy 439.846425 -43.374613) (xy 439.924143 -43.332479) (xy 440.005657 -43.298261) (xy 440.090164 -43.272298)
			(xy 440.176829 -43.254846) (xy 440.264798 -43.246077) (xy 440.309 -43.245532) (xy 440.35135 -43.245956)
			(xy 440.435668 -43.254007) (xy 440.518838 -43.270037) (xy 440.600108 -43.2939) (xy 440.678741 -43.32538)
			(xy 440.754026 -43.364192) (xy 440.825281 -43.409985) (xy 440.89186 -43.462343) (xy 440.953161 -43.520793)
			(xy 441.008629 -43.584806) (xy 441.05776 -43.653801) (xy 441.10011 -43.727154) (xy 441.135296 -43.804201)
			(xy 441.162999 -43.884243) (xy 441.182968 -43.966556) (xy 441.195022 -44.050395) (xy 441.199053 -44.135)
			(xy 441.195022 -44.219605) (xy 441.182968 -44.303444) (xy 441.162999 -44.385757) (xy 441.135296 -44.465799)
			(xy 441.10011 -44.542846) (xy 441.05776 -44.616199) (xy 441.008629 -44.685194) (xy 440.953161 -44.749207)
			(xy 440.89186 -44.807657) (xy 440.825281 -44.860015) (xy 440.754026 -44.905808) (xy 440.678741 -44.94462)
			(xy 440.600108 -44.9761) (xy 440.518838 -44.999963) (xy 440.435668 -45.015993) (xy 440.35135 -45.024044)
			(xy 440.309 -45.024548) (xy 440.263644 -45.024003) (xy 440.173404 -45.014768) (xy 440.084571 -44.996405)
			(xy 439.998066 -44.969103) (xy 439.914785 -44.933145) (xy 439.874914 -44.911518) (xy 439.866316 -44.907203)
			(xy 439.84725 -44.904732) (xy 439.83783 -44.906692) (xy 439.80862 -44.913804) (xy 439.799379 -44.916453)
			(xy 439.783706 -44.927556) (xy 439.77814 -44.935394) (xy 439.753568 -44.972143) (xy 439.698209 -45.041073)
			(xy 439.636286 -45.104172) (xy 439.568409 -45.160817) (xy 439.495248 -45.21045) (xy 439.417525 -45.252581)
			(xy 439.336006 -45.286795) (xy 439.251495 -45.312753) (xy 439.164826 -45.330201) (xy 439.076854 -45.338966)
			(xy 439.03265 -45.339508) (xy 438.990303 -45.339002) (xy 438.905993 -45.330947) (xy 438.82283 -45.314914)
			(xy 438.741568 -45.29105) (xy 438.662942 -45.259569) (xy 438.587665 -45.220757) (xy 438.516417 -45.174965)
			(xy 438.449845 -45.122609) (xy 438.388551 -45.064161) (xy 438.33309 -45.000153) (xy 438.283964 -44.931162)
			(xy 438.241618 -44.857814) (xy 438.206436 -44.780773) (xy 438.178737 -44.700737) (xy 438.15877 -44.61843)
			(xy 438.146717 -44.534598) (xy 438.142687 -44.45) (xy 437.902604 -44.45) (xy 437.902173 -44.491737)
			(xy 437.894382 -44.574847) (xy 437.878839 -44.656861) (xy 437.855683 -44.737059) (xy 437.825116 -44.814735)
			(xy 437.787407 -44.889206) (xy 437.742889 -44.959818) (xy 437.691951 -45.025948) (xy 437.663844 -45.056806)
			(xy 437.656589 -45.065332) (xy 437.649674 -45.086598) (xy 437.652492 -45.108782) (xy 437.658002 -45.118528)
			(xy 437.679823 -45.154075) (xy 437.717475 -45.228509) (xy 437.747996 -45.306139) (xy 437.77112 -45.386284)
			(xy 437.781408 -45.4406) (xy 446.130987 -45.4406) (xy 446.135017 -45.356002) (xy 446.14707 -45.27217)
			(xy 446.167037 -45.189863) (xy 446.194736 -45.109827) (xy 446.229918 -45.032786) (xy 446.272264 -44.959438)
			(xy 446.32139 -44.890447) (xy 446.376851 -44.826439) (xy 446.438145 -44.767991) (xy 446.504717 -44.715635)
			(xy 446.575965 -44.669843) (xy 446.651242 -44.631031) (xy 446.729868 -44.59955) (xy 446.81113 -44.575686)
			(xy 446.894293 -44.559653) (xy 446.978603 -44.551598) (xy 447.02095 -44.551092) (xy 447.060051 -44.551498)
			(xy 447.13795 -44.558372) (xy 447.214944 -44.572061) (xy 447.290439 -44.592459) (xy 447.363849 -44.619411)
			(xy 447.39941 -44.635674) (xy 447.409797 -44.639909) (xy 447.432203 -44.639909) (xy 447.44259 -44.635674)
			(xy 447.478157 -44.619429) (xy 447.551572 -44.592498) (xy 447.627066 -44.572108) (xy 447.704056 -44.558417)
			(xy 447.781951 -44.55153) (xy 447.82105 -44.551092) (xy 447.864585 -44.551601) (xy 447.951237 -44.560113)
			(xy 448.036644 -44.577051) (xy 448.119986 -44.602252) (xy 448.200468 -44.635477) (xy 448.277318 -44.676405)
			(xy 448.349802 -44.724647) (xy 448.417225 -44.77974) (xy 448.478942 -44.841157) (xy 448.534364 -44.908311)
			(xy 448.582959 -44.980558) (xy 448.624262 -45.057208) (xy 448.657879 -45.137526) (xy 448.671188 -45.17898)
			(xy 448.675118 -45.18985) (xy 448.690908 -45.206702) (xy 448.712469 -45.214975) (xy 448.72402 -45.21454)
			(xy 448.742655 -45.213096) (xy 448.780005 -45.211571) (xy 448.798696 -45.211492) (xy 448.79895 -45.211492)
			(xy 448.838051 -45.211898) (xy 448.91595 -45.218772) (xy 448.992944 -45.232461) (xy 449.068439 -45.252859)
			(xy 449.141849 -45.279811) (xy 449.17741 -45.296074) (xy 449.187816 -45.300269) (xy 449.210228 -45.300125)
			(xy 449.22059 -45.29582) (xy 449.24756 -45.283423) (xy 449.302851 -45.261816) (xy 449.33108 -45.25264)
			(xy 449.339712 -45.249426) (xy 449.354128 -45.23799) (xy 449.363591 -45.222208) (xy 449.366888 -45.204104)
			(xy 449.365624 -45.194982) (xy 449.358751 -45.155142) (xy 449.351374 -45.074626) (xy 449.350892 -45.0342)
			(xy 449.350892 -45.033438) (xy 449.351301 -44.995091) (xy 449.357933 -44.918683) (xy 449.371125 -44.843132)
			(xy 449.390778 -44.768998) (xy 449.416747 -44.696834) (xy 449.432426 -44.661836) (xy 449.43679 -44.650863)
			(xy 449.43598 -44.627287) (xy 449.430902 -44.616624) (xy 449.410674 -44.577756) (xy 449.377102 -44.496815)
			(xy 449.351646 -44.412966) (xy 449.334555 -44.327022) (xy 449.325992 -44.239814) (xy 449.325492 -44.196)
			(xy 449.325873 -44.157602) (xy 449.332482 -44.08109) (xy 449.345668 -44.005434) (xy 449.365332 -43.931198)
			(xy 449.391328 -43.858935) (xy 449.407026 -43.82389) (xy 449.407026 -43.823636) (xy 449.411348 -43.812584)
			(xy 449.410572 -43.788897) (xy 449.405502 -43.77817) (xy 449.365878 -43.706542) (xy 449.359675 -43.696419)
			(xy 449.340194 -43.682903) (xy 449.32854 -43.680634) (xy 449.328032 -43.680634) (xy 449.290779 -43.675223)
			(xy 449.217284 -43.658913) (xy 449.145429 -43.63645) (xy 449.07573 -43.607995) (xy 449.042028 -43.591226)
			(xy 449.041774 -43.591226) (xy 449.031342 -43.586556) (xy 449.008523 -43.585909) (xy 448.997832 -43.589956)
			(xy 448.915282 -43.627294) (xy 448.900296 -43.644566) (xy 448.897502 -43.655742) (xy 448.886478 -43.696025)
			(xy 448.85778 -43.774464) (xy 448.821858 -43.849867) (xy 448.779027 -43.921573) (xy 448.729664 -43.988949)
			(xy 448.674204 -44.051402) (xy 448.613135 -44.108383) (xy 448.546995 -44.15939) (xy 448.476366 -44.203974)
			(xy 448.40187 -44.241742) (xy 448.324162 -44.272363) (xy 448.243926 -44.295566) (xy 448.161868 -44.311148)
			(xy 448.078712 -44.318971) (xy 448.03695 -44.319444) (xy 447.994605 -44.318866) (xy 447.910298 -44.310811)
			(xy 447.827139 -44.294779) (xy 447.74588 -44.270916) (xy 447.667257 -44.239436) (xy 447.591983 -44.200626)
			(xy 447.520738 -44.154836) (xy 447.454169 -44.102481) (xy 447.392877 -44.044037) (xy 447.337418 -43.98003)
			(xy 447.288294 -43.911042) (xy 447.24595 -43.837697) (xy 447.21077 -43.76066) (xy 447.183071 -43.680627)
			(xy 447.163105 -43.598323) (xy 447.151053 -43.514495) (xy 447.147023 -43.4299) (xy 447.151053 -43.345305)
			(xy 447.163105 -43.261477) (xy 447.183071 -43.179173) (xy 447.21077 -43.09914) (xy 447.24595 -43.022103)
			(xy 447.288294 -42.948758) (xy 447.337418 -42.87977) (xy 447.392877 -42.815763) (xy 447.454169 -42.757319)
			(xy 447.520738 -42.704964) (xy 447.591983 -42.659174) (xy 447.667257 -42.620364) (xy 447.74588 -42.588884)
			(xy 447.827139 -42.565021) (xy 447.910298 -42.548989) (xy 447.994605 -42.540934) (xy 448.03695 -42.540428)
			(xy 448.037712 -42.540428) (xy 448.079675 -42.540911) (xy 448.163226 -42.548837) (xy 448.245657 -42.564607)
			(xy 448.326233 -42.588081) (xy 448.404237 -42.61905) (xy 448.441826 -42.63771) (xy 448.44208 -42.63771)
			(xy 448.452522 -42.642354) (xy 448.475333 -42.64302) (xy 448.486022 -42.63898) (xy 448.568572 -42.601642)
			(xy 448.583558 -42.58437) (xy 448.586352 -42.573194) (xy 448.597442 -42.53293) (xy 448.626135 -42.454493)
			(xy 448.662052 -42.37909) (xy 448.704878 -42.307386) (xy 448.754235 -42.24001) (xy 448.809689 -42.177556)
			(xy 448.870753 -42.120574) (xy 448.936887 -42.069566) (xy 449.007511 -42.02498) (xy 449.082003 -41.98721)
			(xy 449.159706 -41.956586) (xy 449.239938 -41.93338) (xy 449.321991 -41.917794) (xy 449.405144 -41.909967)
			(xy 449.446904 -41.909492) (xy 449.488007 -41.909963) (xy 449.569861 -41.917548) (xy 449.650666 -41.932654)
			(xy 449.729733 -41.95515) (xy 449.806387 -41.984847) (xy 449.879974 -42.021489) (xy 449.949866 -42.064764)
			(xy 450.015467 -42.114304) (xy 450.076217 -42.169686) (xy 450.131598 -42.230436) (xy 450.181138 -42.296037)
			(xy 450.224413 -42.365929) (xy 450.261055 -42.439517) (xy 450.290751 -42.516171) (xy 450.313247 -42.595238)
			(xy 450.328352 -42.676043) (xy 450.335937 -42.757897) (xy 450.336412 -42.799) (xy 450.336412 -42.799254)
			(xy 450.336021 -42.837627) (xy 450.329399 -42.914086) (xy 450.316209 -42.98969) (xy 450.296549 -43.063875)
			(xy 450.270567 -43.136088) (xy 450.254878 -43.17111) (xy 450.254878 -43.171364) (xy 450.250555 -43.182416)
			(xy 450.251331 -43.206103) (xy 450.256402 -43.21683) (xy 450.296026 -43.288458) (xy 450.302227 -43.298583)
			(xy 450.32171 -43.312098) (xy 450.333364 -43.314366) (xy 450.333872 -43.314366) (xy 450.376027 -43.320593)
			(xy 450.459002 -43.340021) (xy 450.539739 -43.367293) (xy 450.617498 -43.402161) (xy 450.691568 -43.444303)
			(xy 450.761268 -43.493335) (xy 450.82596 -43.548807) (xy 450.885053 -43.61021) (xy 450.938003 -43.676982)
			(xy 450.984326 -43.748511) (xy 451.023597 -43.824142) (xy 451.055457 -43.903181) (xy 451.079613 -43.984904)
			(xy 451.095845 -44.068563) (xy 451.104003 -44.153391) (xy 451.104508 -44.196) (xy 451.104508 -44.196762)
			(xy 451.104099 -44.235109) (xy 451.097467 -44.311517) (xy 451.084275 -44.387068) (xy 451.064622 -44.461202)
			(xy 451.038653 -44.533366) (xy 451.022974 -44.568364) (xy 451.01861 -44.579337) (xy 451.01942 -44.602913)
			(xy 451.024498 -44.613576) (xy 451.044682 -44.652352) (xy 451.078196 -44.733098) (xy 451.10363 -44.816741)
			(xy 451.120741 -44.902474) (xy 451.129363 -44.989472) (xy 451.129908 -45.033184) (xy 451.129908 -45.0342)
			(xy 451.129476 -45.07748) (xy 451.121079 -45.163632) (xy 451.104354 -45.248561) (xy 451.079461 -45.331465)
			(xy 451.046633 -45.411559) (xy 451.006182 -45.488086) (xy 450.95849 -45.560323) (xy 450.904008 -45.627587)
			(xy 450.843251 -45.689241) (xy 450.776793 -45.744703) (xy 450.705263 -45.793449) (xy 450.629337 -45.835017)
			(xy 450.549733 -45.869015) (xy 450.508624 -45.88256) (xy 450.499938 -45.885678) (xy 450.485461 -45.897103)
			(xy 450.475989 -45.912927) (xy 450.472758 -45.931083) (xy 450.47408 -45.940218) (xy 450.480948 -45.980059)
			(xy 450.488329 -46.060574) (xy 450.488812 -46.101) (xy 450.48834 -46.143697) (xy 450.480165 -46.2287)
			(xy 450.463881 -46.312527) (xy 450.439638 -46.394408) (xy 450.407658 -46.473588) (xy 450.368237 -46.549339)
			(xy 450.321737 -46.620963) (xy 450.268587 -46.687801) (xy 450.209275 -46.749237) (xy 450.144349 -46.804705)
			(xy 450.074405 -46.853695) (xy 450.000087 -46.895756) (xy 449.92208 -46.930501) (xy 449.881752 -46.944534)
			(xy 449.870989 -46.948746) (xy 449.854456 -46.964859) (xy 449.850002 -46.975522) (xy 449.819014 -47.061374)
			(xy 449.821554 -47.084488) (xy 449.82765 -47.094394) (xy 449.848966 -47.129617) (xy 449.885742 -47.203285)
			(xy 449.915559 -47.280034) (xy 449.938162 -47.359207) (xy 449.953358 -47.44013) (xy 449.961017 -47.52211)
			(xy 449.961508 -47.563278) (xy 449.961508 -47.56404) (xy 449.961004 -47.606388) (xy 449.952953 -47.690702)
			(xy 449.936924 -47.773868) (xy 449.913063 -47.855135) (xy 449.881584 -47.933765) (xy 449.842773 -48.009046)
			(xy 449.796983 -48.080298) (xy 449.744627 -48.146874) (xy 449.717464 -48.175361) (xy 450.722742 -48.175361)
			(xy 450.722742 -48.090639) (xy 450.730795 -48.006302) (xy 450.746829 -47.923112) (xy 450.770697 -47.841822)
			(xy 450.802185 -47.76317) (xy 450.841007 -47.687867) (xy 450.88681 -47.616595) (xy 450.939181 -47.549999)
			(xy 450.997646 -47.488684) (xy 451.061674 -47.433203) (xy 451.130686 -47.38406) (xy 451.204056 -47.3417)
			(xy 451.281121 -47.306505) (xy 451.361183 -47.278796) (xy 451.443516 -47.258822) (xy 451.527375 -47.246765)
			(xy 451.612 -47.242734) (xy 451.696625 -47.246765) (xy 451.780484 -47.258822) (xy 451.862817 -47.278796)
			(xy 451.942879 -47.306505) (xy 452.019944 -47.3417) (xy 452.093314 -47.38406) (xy 452.162326 -47.433203)
			(xy 452.226354 -47.488684) (xy 452.284819 -47.549999) (xy 452.33719 -47.616595) (xy 452.369815 -47.667361)
			(xy 456.336142 -47.667361) (xy 456.336142 -47.582639) (xy 456.344195 -47.498302) (xy 456.360229 -47.415112)
			(xy 456.384097 -47.333822) (xy 456.415585 -47.25517) (xy 456.454407 -47.179867) (xy 456.50021 -47.108595)
			(xy 456.552581 -47.041999) (xy 456.611046 -46.980684) (xy 456.675074 -46.925203) (xy 456.744086 -46.87606)
			(xy 456.817456 -46.8337) (xy 456.894521 -46.798505) (xy 456.974583 -46.770796) (xy 457.056916 -46.750822)
			(xy 457.140775 -46.738765) (xy 457.2254 -46.734734) (xy 457.310025 -46.738765) (xy 457.393884 -46.750822)
			(xy 457.476217 -46.770796) (xy 457.556279 -46.798505) (xy 457.633344 -46.8337) (xy 457.706714 -46.87606)
			(xy 457.775726 -46.925203) (xy 457.839754 -46.980684) (xy 457.898219 -47.041999) (xy 457.95059 -47.108595)
			(xy 457.996393 -47.179867) (xy 458.029456 -47.244) (xy 459.230988 -47.244) (xy 459.235018 -47.159399)
			(xy 459.247071 -47.075564) (xy 459.267039 -46.993255) (xy 459.294741 -46.913216) (xy 459.329925 -46.836173)
			(xy 459.372274 -46.762823) (xy 459.421403 -46.693831) (xy 459.476868 -46.629821) (xy 459.538166 -46.571373)
			(xy 459.604742 -46.519017) (xy 459.675994 -46.473227) (xy 459.751275 -46.434416) (xy 459.829905 -46.402937)
			(xy 459.911172 -46.379076) (xy 459.994338 -46.363047) (xy 460.078652 -46.354996) (xy 460.121 -46.354492)
			(xy 460.121254 -46.354492) (xy 460.164582 -46.355012) (xy 460.250826 -46.363468) (xy 460.335839 -46.380267)
			(xy 460.418817 -46.405248) (xy 460.498974 -46.438176) (xy 460.575551 -46.478739) (xy 460.647824 -46.526552)
			(xy 460.715107 -46.581163) (xy 460.776764 -46.642055) (xy 460.832211 -46.708651) (xy 460.880924 -46.780321)
			(xy 460.922439 -46.856386) (xy 460.956366 -46.936126) (xy 460.969868 -46.9773) (xy 460.973424 -46.988984)
			(xy 460.990442 -47.00651) (xy 461.092042 -47.040292) (xy 461.116172 -47.036482) (xy 461.125824 -47.02937)
			(xy 461.158179 -47.006665) (xy 461.226233 -46.966446) (xy 461.297588 -46.932426) (xy 461.371681 -46.904875)
			(xy 461.447927 -46.88401) (xy 461.525725 -46.869995) (xy 461.604459 -46.862941) (xy 461.643984 -46.862492)
			(xy 461.645 -46.862492) (xy 461.687348 -46.862996) (xy 461.771662 -46.871047) (xy 461.854828 -46.887076)
			(xy 461.936095 -46.910937) (xy 462.014725 -46.942416) (xy 462.090006 -46.981227) (xy 462.161258 -47.027017)
			(xy 462.227834 -47.079373) (xy 462.289132 -47.137821) (xy 462.344597 -47.201831) (xy 462.393726 -47.270823)
			(xy 462.436075 -47.344173) (xy 462.471259 -47.421216) (xy 462.498961 -47.501255) (xy 462.518929 -47.583564)
			(xy 462.530982 -47.667399) (xy 462.535013 -47.752) (xy 462.530982 -47.836601) (xy 462.518929 -47.920436)
			(xy 462.498961 -48.002745) (xy 462.471259 -48.082784) (xy 462.436075 -48.159827) (xy 462.393726 -48.233177)
			(xy 462.344597 -48.302169) (xy 462.289132 -48.366179) (xy 462.227834 -48.424627) (xy 462.161258 -48.476983)
			(xy 462.090006 -48.522773) (xy 462.014725 -48.561584) (xy 461.936095 -48.593063) (xy 461.854828 -48.616924)
			(xy 461.771662 -48.632953) (xy 461.687348 -48.641004) (xy 461.645 -48.641508) (xy 461.644746 -48.641508)
			(xy 461.601418 -48.640988) (xy 461.515174 -48.632532) (xy 461.430161 -48.615733) (xy 461.347183 -48.590752)
			(xy 461.267026 -48.557824) (xy 461.190449 -48.517261) (xy 461.118176 -48.469448) (xy 461.050893 -48.414837)
			(xy 460.989236 -48.353945) (xy 460.933789 -48.287349) (xy 460.885076 -48.215679) (xy 460.843561 -48.139614)
			(xy 460.809634 -48.059874) (xy 460.796132 -48.0187) (xy 460.792576 -48.007016) (xy 460.775558 -47.98949)
			(xy 460.673958 -47.955708) (xy 460.649828 -47.959518) (xy 460.640176 -47.96663) (xy 460.607821 -47.989335)
			(xy 460.539767 -48.029554) (xy 460.468412 -48.063574) (xy 460.394319 -48.091125) (xy 460.318073 -48.11199)
			(xy 460.240275 -48.126005) (xy 460.161541 -48.133059) (xy 460.122016 -48.133508) (xy 460.121 -48.133508)
			(xy 460.078652 -48.133004) (xy 459.994338 -48.124953) (xy 459.911172 -48.108924) (xy 459.829905 -48.085063)
			(xy 459.751275 -48.053584) (xy 459.675994 -48.014773) (xy 459.604742 -47.968983) (xy 459.538166 -47.916627)
			(xy 459.476868 -47.858179) (xy 459.421403 -47.794169) (xy 459.372274 -47.725177) (xy 459.329925 -47.651827)
			(xy 459.294741 -47.574784) (xy 459.267039 -47.494745) (xy 459.247071 -47.412436) (xy 459.235018 -47.328601)
			(xy 459.230988 -47.244) (xy 458.029456 -47.244) (xy 458.035215 -47.25517) (xy 458.066703 -47.333822)
			(xy 458.090571 -47.415112) (xy 458.106605 -47.498302) (xy 458.114658 -47.582639) (xy 458.115162 -47.625)
			(xy 458.114658 -47.667361) (xy 458.106605 -47.751698) (xy 458.090571 -47.834888) (xy 458.066703 -47.916178)
			(xy 458.035215 -47.99483) (xy 457.996393 -48.070133) (xy 457.95059 -48.141405) (xy 457.898219 -48.208001)
			(xy 457.839754 -48.269316) (xy 457.775726 -48.324797) (xy 457.706714 -48.37394) (xy 457.633344 -48.4163)
			(xy 457.556279 -48.451495) (xy 457.476217 -48.479204) (xy 457.393884 -48.499178) (xy 457.310025 -48.511235)
			(xy 457.2254 -48.515267) (xy 457.140775 -48.511235) (xy 457.056916 -48.499178) (xy 456.974583 -48.479204)
			(xy 456.894521 -48.451495) (xy 456.817456 -48.4163) (xy 456.744086 -48.37394) (xy 456.675074 -48.324797)
			(xy 456.611046 -48.269316) (xy 456.552581 -48.208001) (xy 456.50021 -48.141405) (xy 456.454407 -48.070133)
			(xy 456.415585 -47.99483) (xy 456.384097 -47.916178) (xy 456.360229 -47.834888) (xy 456.344195 -47.751698)
			(xy 456.336142 -47.667361) (xy 452.369815 -47.667361) (xy 452.382993 -47.687867) (xy 452.421815 -47.76317)
			(xy 452.453303 -47.841822) (xy 452.477171 -47.923112) (xy 452.493205 -48.006302) (xy 452.501258 -48.090639)
			(xy 452.501762 -48.133) (xy 452.501258 -48.175361) (xy 452.493205 -48.259698) (xy 452.477171 -48.342888)
			(xy 452.453303 -48.424178) (xy 452.421815 -48.50283) (xy 452.382993 -48.578133) (xy 452.33719 -48.649405)
			(xy 452.284819 -48.716001) (xy 452.226354 -48.777316) (xy 452.162326 -48.832797) (xy 452.093314 -48.88194)
			(xy 452.019944 -48.9243) (xy 451.942879 -48.959495) (xy 451.862817 -48.987204) (xy 451.780484 -49.007178)
			(xy 451.696625 -49.019235) (xy 451.612 -49.023267) (xy 451.527375 -49.019235) (xy 451.443516 -49.007178)
			(xy 451.361183 -48.987204) (xy 451.281121 -48.959495) (xy 451.204056 -48.9243) (xy 451.130686 -48.88194)
			(xy 451.061674 -48.832797) (xy 450.997646 -48.777316) (xy 450.939181 -48.716001) (xy 450.88681 -48.649405)
			(xy 450.841007 -48.578133) (xy 450.802185 -48.50283) (xy 450.770697 -48.424178) (xy 450.746829 -48.342888)
			(xy 450.730795 -48.259698) (xy 450.722742 -48.175361) (xy 449.717464 -48.175361) (xy 449.686179 -48.208172)
			(xy 449.622169 -48.263637) (xy 449.553177 -48.312766) (xy 449.479827 -48.355115) (xy 449.402784 -48.390299)
			(xy 449.322745 -48.418001) (xy 449.240436 -48.437969) (xy 449.156601 -48.450022) (xy 449.072 -48.454053)
			(xy 448.987399 -48.450022) (xy 448.903564 -48.437969) (xy 448.821255 -48.418001) (xy 448.741216 -48.390299)
			(xy 448.664173 -48.355115) (xy 448.590823 -48.312766) (xy 448.521831 -48.263637) (xy 448.457821 -48.208172)
			(xy 448.399373 -48.146874) (xy 448.347017 -48.080298) (xy 448.301227 -48.009046) (xy 448.262416 -47.933765)
			(xy 448.230937 -47.855135) (xy 448.207076 -47.773868) (xy 448.191047 -47.690702) (xy 448.182996 -47.606388)
			(xy 448.182492 -47.56404) (xy 448.182492 -47.563786) (xy 448.182977 -47.52157) (xy 448.191003 -47.437519)
			(xy 448.206953 -47.354606) (xy 448.230683 -47.273576) (xy 448.261981 -47.195158) (xy 448.300564 -47.120056)
			(xy 448.346087 -47.048946) (xy 448.371722 -47.0154) (xy 448.37858 -47.006764) (xy 448.38366 -46.985682)
			(xy 448.367658 -46.899576) (xy 448.365202 -46.889121) (xy 448.352975 -46.871491) (xy 448.344036 -46.86554)
			(xy 448.343782 -46.865286) (xy 448.308929 -46.843927) (xy 448.242837 -46.795816) (xy 448.181436 -46.741847)
			(xy 448.125243 -46.682474) (xy 448.074731 -46.618198) (xy 448.030327 -46.549561) (xy 447.992405 -46.477141)
			(xy 447.961284 -46.401548) (xy 447.948812 -46.36262) (xy 447.944882 -46.35175) (xy 447.929092 -46.334898)
			(xy 447.907531 -46.326625) (xy 447.89598 -46.32706) (xy 447.877345 -46.328504) (xy 447.839995 -46.330029)
			(xy 447.821304 -46.330108) (xy 447.82105 -46.330108) (xy 447.781949 -46.329702) (xy 447.70405 -46.322828)
			(xy 447.627056 -46.309139) (xy 447.551561 -46.288741) (xy 447.478151 -46.261789) (xy 447.44259 -46.245526)
			(xy 447.432203 -46.241291) (xy 447.409797 -46.241291) (xy 447.39941 -46.245526) (xy 447.363843 -46.261771)
			(xy 447.290428 -46.288702) (xy 447.214934 -46.309092) (xy 447.137944 -46.322783) (xy 447.060049 -46.32967)
			(xy 447.02095 -46.330108) (xy 446.978603 -46.329602) (xy 446.894293 -46.321547) (xy 446.81113 -46.305514)
			(xy 446.729868 -46.28165) (xy 446.651242 -46.250169) (xy 446.575965 -46.211357) (xy 446.504717 -46.165565)
			(xy 446.438145 -46.113209) (xy 446.376851 -46.054761) (xy 446.32139 -45.990753) (xy 446.272264 -45.921762)
			(xy 446.229918 -45.848414) (xy 446.194736 -45.771373) (xy 446.167037 -45.691337) (xy 446.14707 -45.60903)
			(xy 446.135017 -45.525198) (xy 446.130987 -45.4406) (xy 437.781408 -45.4406) (xy 437.786643 -45.468242)
			(xy 437.79443 -45.551293) (xy 437.794908 -45.593) (xy 437.794404 -45.635348) (xy 437.786353 -45.719662)
			(xy 437.770324 -45.802828) (xy 437.746463 -45.884095) (xy 437.714984 -45.962725) (xy 437.676173 -46.038006)
			(xy 437.630383 -46.109258) (xy 437.578027 -46.175834) (xy 437.519579 -46.237132) (xy 437.455569 -46.292597)
			(xy 437.386577 -46.341726) (xy 437.313227 -46.384075) (xy 437.236184 -46.419259) (xy 437.156145 -46.446961)
			(xy 437.073836 -46.466929) (xy 436.990001 -46.478982) (xy 436.9054 -46.483013) (xy 436.820799 -46.478982)
			(xy 436.736964 -46.466929) (xy 436.654655 -46.446961) (xy 436.574616 -46.419259) (xy 436.497573 -46.384075)
			(xy 436.424223 -46.341726) (xy 436.355231 -46.292597) (xy 436.291221 -46.237132) (xy 436.232773 -46.175834)
			(xy 436.180417 -46.109258) (xy 436.134627 -46.038006) (xy 436.095816 -45.962725) (xy 436.064337 -45.884095)
			(xy 436.040476 -45.802828) (xy 436.024447 -45.719662) (xy 436.016396 -45.635348) (xy 436.015892 -45.593)
			(xy 432.93147 -45.593) (xy 432.917299 -45.63964) (xy 432.88372 -45.720526) (xy 432.863498 -45.75937)
			(xy 432.85808 -45.770836) (xy 432.85808 -45.796164) (xy 432.863498 -45.80763) (xy 432.883723 -45.846471)
			(xy 432.917274 -45.927366) (xy 432.94272 -46.011164) (xy 432.959816 -46.097056) (xy 432.968395 -46.184212)
			(xy 432.968908 -46.228) (xy 432.968501 -46.266451) (xy 432.961878 -46.343066) (xy 432.948656 -46.418822)
			(xy 432.93919 -46.456092) (xy 432.93538 -46.470824) (xy 432.944524 -46.499018) (xy 433.03952 -46.576742)
			(xy 433.06873 -46.580044) (xy 433.082446 -46.57344) (xy 433.119254 -46.555791) (xy 433.195459 -46.526512)
			(xy 433.274024 -46.504333) (xy 433.35429 -46.48944) (xy 433.435582 -46.481957) (xy 433.4764 -46.481492)
			(xy 433.518534 -46.48201) (xy 433.602424 -46.489977) (xy 433.685186 -46.50584) (xy 433.766077 -46.529457)
			(xy 433.844372 -46.560616) (xy 433.919371 -46.599038) (xy 433.990401 -46.644378) (xy 434.056827 -46.696232)
			(xy 434.087778 -46.724824) (xy 434.096076 -46.732055) (xy 434.116892 -46.739147) (xy 434.138762 -46.736847)
			(xy 434.148484 -46.731682) (xy 434.182739 -46.712004) (xy 434.254089 -46.678079) (xy 434.328166 -46.650618)
			(xy 434.404388 -46.629835) (xy 434.482153 -46.615896) (xy 434.560848 -46.60891) (xy 434.60035 -46.608492)
			(xy 434.639444 -46.608895) (xy 434.717333 -46.61573) (xy 434.794322 -46.629371) (xy 434.869819 -46.64971)
			(xy 434.94324 -46.676593) (xy 434.97881 -46.69282) (xy 434.989197 -46.697055) (xy 435.011603 -46.697055)
			(xy 435.02199 -46.69282) (xy 435.057561 -46.676594) (xy 435.130977 -46.649695) (xy 435.206473 -46.629348)
			(xy 435.283464 -46.615712) (xy 435.361355 -46.608892) (xy 435.40045 -46.608492) (xy 435.442801 -46.608978)
			(xy 435.527119 -46.617025) (xy 435.610291 -46.63305) (xy 435.672661 -46.651361) (xy 438.276742 -46.651361)
			(xy 438.276742 -46.566639) (xy 438.284795 -46.482302) (xy 438.300829 -46.399112) (xy 438.324697 -46.317822)
			(xy 438.356185 -46.23917) (xy 438.395007 -46.163867) (xy 438.44081 -46.092595) (xy 438.493181 -46.025999)
			(xy 438.551646 -45.964684) (xy 438.615674 -45.909203) (xy 438.684686 -45.86006) (xy 438.758056 -45.8177)
			(xy 438.835121 -45.782505) (xy 438.915183 -45.754796) (xy 438.997516 -45.734822) (xy 439.081375 -45.722765)
			(xy 439.166 -45.718734) (xy 439.250625 -45.722765) (xy 439.334484 -45.734822) (xy 439.416817 -45.754796)
			(xy 439.496879 -45.782505) (xy 439.573944 -45.8177) (xy 439.647314 -45.86006) (xy 439.716326 -45.909203)
			(xy 439.780354 -45.964684) (xy 439.838819 -46.025999) (xy 439.89119 -46.092595) (xy 439.936993 -46.163867)
			(xy 439.975815 -46.23917) (xy 440.007303 -46.317822) (xy 440.031171 -46.399112) (xy 440.047205 -46.482302)
			(xy 440.055258 -46.566639) (xy 440.055762 -46.609) (xy 440.055258 -46.651361) (xy 440.047205 -46.735698)
			(xy 440.031171 -46.818888) (xy 440.007303 -46.900178) (xy 439.975815 -46.97883) (xy 439.936993 -47.054133)
			(xy 439.89119 -47.125405) (xy 439.838819 -47.192001) (xy 439.780354 -47.253316) (xy 439.716326 -47.308797)
			(xy 439.647314 -47.35794) (xy 439.573944 -47.4003) (xy 439.496879 -47.435495) (xy 439.416817 -47.463204)
			(xy 439.334484 -47.483178) (xy 439.250625 -47.495235) (xy 439.166 -47.499267) (xy 439.081375 -47.495235)
			(xy 438.997516 -47.483178) (xy 438.915183 -47.463204) (xy 438.835121 -47.435495) (xy 438.758056 -47.4003)
			(xy 438.684686 -47.35794) (xy 438.615674 -47.308797) (xy 438.551646 -47.253316) (xy 438.493181 -47.192001)
			(xy 438.44081 -47.125405) (xy 438.395007 -47.054133) (xy 438.356185 -46.97883) (xy 438.324697 -46.900178)
			(xy 438.300829 -46.818888) (xy 438.284795 -46.735698) (xy 438.276742 -46.651361) (xy 435.672661 -46.651361)
			(xy 435.691562 -46.65691) (xy 435.770198 -46.688387) (xy 435.845485 -46.727196) (xy 435.916742 -46.772987)
			(xy 435.983324 -46.825344) (xy 436.044627 -46.883793) (xy 436.100096 -46.947805) (xy 436.149229 -47.016799)
			(xy 436.191581 -47.090152) (xy 436.226769 -47.167199) (xy 436.254473 -47.247241) (xy 436.274443 -47.329555)
			(xy 436.286498 -47.413394) (xy 436.290528 -47.498) (xy 436.286498 -47.582606) (xy 436.283077 -47.606401)
			(xy 444.692782 -47.606401) (xy 444.692782 -47.521679) (xy 444.700835 -47.437342) (xy 444.716869 -47.354152)
			(xy 444.740737 -47.272862) (xy 444.772225 -47.19421) (xy 444.811047 -47.118907) (xy 444.85685 -47.047635)
			(xy 444.909221 -46.981039) (xy 444.967686 -46.919724) (xy 445.031714 -46.864243) (xy 445.100726 -46.8151)
			(xy 445.174096 -46.77274) (xy 445.251161 -46.737545) (xy 445.331223 -46.709836) (xy 445.413556 -46.689862)
			(xy 445.497415 -46.677805) (xy 445.58204 -46.673774) (xy 445.666665 -46.677805) (xy 445.750524 -46.689862)
			(xy 445.832857 -46.709836) (xy 445.912919 -46.737545) (xy 445.989984 -46.77274) (xy 446.063354 -46.8151)
			(xy 446.132366 -46.864243) (xy 446.196394 -46.919724) (xy 446.254859 -46.981039) (xy 446.30723 -47.047635)
			(xy 446.353033 -47.118907) (xy 446.391855 -47.19421) (xy 446.423343 -47.272862) (xy 446.447211 -47.354152)
			(xy 446.463245 -47.437342) (xy 446.471298 -47.521679) (xy 446.471802 -47.56404) (xy 446.471298 -47.606401)
			(xy 446.463245 -47.690738) (xy 446.447211 -47.773928) (xy 446.423343 -47.855218) (xy 446.391855 -47.93387)
			(xy 446.353033 -48.009173) (xy 446.30723 -48.080445) (xy 446.254859 -48.147041) (xy 446.196394 -48.208356)
			(xy 446.132366 -48.263837) (xy 446.063354 -48.31298) (xy 445.989984 -48.35534) (xy 445.912919 -48.390535)
			(xy 445.832857 -48.418244) (xy 445.750524 -48.438218) (xy 445.666665 -48.450275) (xy 445.58204 -48.454307)
			(xy 445.497415 -48.450275) (xy 445.413556 -48.438218) (xy 445.331223 -48.418244) (xy 445.251161 -48.390535)
			(xy 445.174096 -48.35534) (xy 445.100726 -48.31298) (xy 445.031714 -48.263837) (xy 444.967686 -48.208356)
			(xy 444.909221 -48.147041) (xy 444.85685 -48.080445) (xy 444.811047 -48.009173) (xy 444.772225 -47.93387)
			(xy 444.740737 -47.855218) (xy 444.716869 -47.773928) (xy 444.700835 -47.690738) (xy 444.692782 -47.606401)
			(xy 436.283077 -47.606401) (xy 436.274443 -47.666445) (xy 436.254473 -47.748759) (xy 436.226769 -47.828801)
			(xy 436.191581 -47.905848) (xy 436.149229 -47.979201) (xy 436.100096 -48.048195) (xy 436.044627 -48.112207)
			(xy 435.983324 -48.170656) (xy 435.916742 -48.223013) (xy 435.845485 -48.268804) (xy 435.770198 -48.307613)
			(xy 435.691562 -48.33909) (xy 435.610291 -48.36295) (xy 435.527119 -48.378975) (xy 435.442801 -48.387022)
			(xy 435.40045 -48.387508) (xy 435.361356 -48.387105) (xy 435.283467 -48.38027) (xy 435.206478 -48.366629)
			(xy 435.130981 -48.34629) (xy 435.05756 -48.319407) (xy 435.02199 -48.30318) (xy 435.011603 -48.298945)
			(xy 434.989197 -48.298945) (xy 434.97881 -48.30318) (xy 434.943239 -48.319406) (xy 434.869823 -48.346305)
			(xy 434.794327 -48.366652) (xy 434.717336 -48.380288) (xy 434.639445 -48.387108) (xy 434.60035 -48.387508)
			(xy 434.558215 -48.387022) (xy 434.474324 -48.37905) (xy 434.391562 -48.363183) (xy 434.310671 -48.339561)
			(xy 434.232375 -48.308398) (xy 434.157377 -48.269972) (xy 434.086347 -48.224627) (xy 434.019923 -48.17277)
			(xy 433.988972 -48.144176) (xy 433.980643 -48.136987) (xy 433.959845 -48.129883) (xy 433.937987 -48.132164)
			(xy 433.928266 -48.137318) (xy 433.894023 -48.157017) (xy 433.82267 -48.190938) (xy 433.74859 -48.218396)
			(xy 433.672366 -48.239175) (xy 433.594599 -48.25311) (xy 433.515903 -48.260092) (xy 433.4764 -48.260508)
			(xy 433.435298 -48.260033) (xy 433.353443 -48.252448) (xy 433.272638 -48.237343) (xy 433.193571 -48.214847)
			(xy 433.116917 -48.185151) (xy 433.04333 -48.148509) (xy 432.973438 -48.105234) (xy 432.907837 -48.055694)
			(xy 432.847087 -48.000313) (xy 432.791706 -47.939563) (xy 432.742166 -47.873962) (xy 432.698891 -47.80407)
			(xy 432.662249 -47.730483) (xy 432.632553 -47.653829) (xy 432.610057 -47.574762) (xy 432.594952 -47.493957)
			(xy 432.587367 -47.412102) (xy 432.586892 -47.371) (xy 432.587299 -47.332549) (xy 432.593922 -47.255934)
			(xy 432.607144 -47.180178) (xy 432.61661 -47.142908) (xy 432.62042 -47.128176) (xy 432.611276 -47.099982)
			(xy 432.51628 -47.022258) (xy 432.48707 -47.018956) (xy 432.473354 -47.02556) (xy 432.436546 -47.043209)
			(xy 432.360341 -47.072488) (xy 432.281776 -47.094667) (xy 432.20151 -47.10956) (xy 432.120218 -47.117043)
			(xy 432.0794 -47.117508) (xy 432.036653 -47.117036) (xy 431.951552 -47.108861) (xy 431.867628 -47.092558)
			(xy 431.785656 -47.068278) (xy 431.706391 -47.036244) (xy 431.630566 -46.996752) (xy 431.558881 -46.950167)
			(xy 431.491996 -46.896918) (xy 431.46091 -46.867572) (xy 431.452062 -46.859827) (xy 431.429685 -46.852684)
			(xy 431.417984 -46.853856) (xy 431.385093 -46.858429) (xy 431.318857 -46.863257) (xy 431.28565 -46.863508)
			(xy 431.244545 -46.86294) (xy 431.162686 -46.85536) (xy 431.081876 -46.840262) (xy 431.002802 -46.817773)
			(xy 430.926141 -46.788085) (xy 430.852545 -46.751451) (xy 430.782643 -46.708184) (xy 430.71703 -46.658654)
			(xy 430.656267 -46.603281) (xy 430.60087 -46.542539) (xy 430.551314 -46.476946) (xy 430.508019 -46.407061)
			(xy 430.471357 -46.333479) (xy 430.441639 -46.25683) (xy 430.419118 -46.177765) (xy 430.403988 -46.09696)
			(xy 430.396376 -46.015104) (xy 430.395888 -45.974) (xy 429.127412 -45.974) (xy 429.166969 -45.991478)
			(xy 429.242797 -46.033071) (xy 429.314231 -46.081827) (xy 429.380597 -46.137285) (xy 429.441267 -46.198921)
			(xy 429.495669 -46.266154) (xy 429.54329 -46.33835) (xy 429.583679 -46.414826) (xy 429.616457 -46.494861)
			(xy 429.641313 -46.577699) (xy 429.658012 -46.662558) (xy 429.666397 -46.748637) (xy 429.666908 -46.79188)
			(xy 429.666357 -46.835803) (xy 429.657711 -46.923222) (xy 429.640492 -47.009363) (xy 429.614866 -47.093387)
			(xy 429.581084 -47.174477) (xy 429.539475 -47.251843) (xy 429.490443 -47.324731) (xy 429.434467 -47.392433)
			(xy 429.372091 -47.454287) (xy 429.303922 -47.509693) (xy 429.230624 -47.558111) (xy 429.152911 -47.599069)
			(xy 429.112426 -47.61611) (xy 429.10233 -47.62075) (xy 429.08718 -47.636971) (xy 429.083216 -47.647352)
			(xy 429.069395 -47.688012) (xy 429.034956 -47.76669) (xy 428.993096 -47.841683) (xy 428.944205 -47.912294)
			(xy 428.888737 -47.977864) (xy 428.827208 -48.037784) (xy 428.760192 -48.091497) (xy 428.688312 -48.138501)
			(xy 428.612237 -48.17836) (xy 428.532674 -48.210703) (xy 428.450366 -48.235228) (xy 428.366077 -48.251708)
			(xy 428.280592 -48.259989) (xy 428.23765 -48.260508) (xy 428.196545 -48.25994) (xy 428.114686 -48.25236)
			(xy 428.033876 -48.237262) (xy 427.954802 -48.214773) (xy 427.878141 -48.185085) (xy 427.804545 -48.148451)
			(xy 427.734643 -48.105184) (xy 427.66903 -48.055654) (xy 427.608267 -48.000281) (xy 427.55287 -47.939539)
			(xy 427.503314 -47.873946) (xy 427.460019 -47.804061) (xy 427.423357 -47.730479) (xy 427.393639 -47.65383)
			(xy 427.371118 -47.574765) (xy 427.355988 -47.49396) (xy 427.348376 -47.412104) (xy 427.347888 -47.371)
			(xy 427.348394 -47.327494) (xy 427.356888 -47.240897) (xy 427.373796 -47.155543) (xy 427.398954 -47.072247)
			(xy 427.432124 -46.991806) (xy 427.472988 -46.914986) (xy 427.521157 -46.842522) (xy 427.576169 -46.775107)
			(xy 427.60646 -46.743874) (xy 427.613826 -46.736762) (xy 427.621192 -46.718474) (xy 427.621446 -46.626272)
			(xy 427.613826 -46.607984) (xy 427.60646 -46.600872) (xy 427.57624 -46.569612) (xy 427.521318 -46.502202)
			(xy 427.473233 -46.429757) (xy 427.432444 -46.352966) (xy 427.39934 -46.272563) (xy 427.374237 -46.189314)
			(xy 427.357374 -46.104014) (xy 427.348912 -46.017476) (xy 427.348396 -45.974) (xy 427.348898 -45.930516)
			(xy 427.357383 -45.843963) (xy 427.374273 -45.758652) (xy 427.399407 -45.675395) (xy 427.432544 -45.594987)
			(xy 427.473368 -45.518197) (xy 427.52149 -45.445756) (xy 427.57645 -45.378357) (xy 427.606714 -45.347128)
			(xy 427.613826 -45.339762) (xy 427.621446 -45.321474) (xy 427.621446 -45.229526) (xy 427.613826 -45.211238)
			(xy 427.606714 -45.203872) (xy 427.576453 -45.172642) (xy 427.521499 -45.10524) (xy 427.473382 -45.032798)
			(xy 427.432562 -44.956007) (xy 427.399429 -44.8756) (xy 427.374299 -44.792344) (xy 427.357411 -44.707034)
			(xy 427.348927 -44.620483) (xy 427.348927 -44.533517) (xy 427.357411 -44.446966) (xy 427.374299 -44.361656)
			(xy 427.399429 -44.2784) (xy 427.432562 -44.197993) (xy 427.473382 -44.121202) (xy 427.521499 -44.04876)
			(xy 427.576453 -43.981358) (xy 427.606714 -43.950128) (xy 427.613826 -43.942762) (xy 427.621446 -43.924474)
			(xy 427.621446 -43.832526) (xy 427.613826 -43.814238) (xy 427.606714 -43.806872) (xy 427.576453 -43.775642)
			(xy 427.521499 -43.70824) (xy 427.473382 -43.635798) (xy 427.432562 -43.559007) (xy 427.399429 -43.4786)
			(xy 427.374299 -43.395344) (xy 427.357411 -43.310034) (xy 427.348927 -43.223483) (xy 427.348927 -43.136517)
			(xy 427.357411 -43.049966) (xy 427.374299 -42.964656) (xy 427.399429 -42.8814) (xy 427.432562 -42.800993)
			(xy 427.473382 -42.724202) (xy 427.521499 -42.65176) (xy 427.576453 -42.584358) (xy 427.606714 -42.553128)
			(xy 427.613826 -42.545762) (xy 427.621446 -42.527474) (xy 427.621446 -42.435526) (xy 427.613826 -42.417238)
			(xy 427.606714 -42.409872) (xy 427.576453 -42.378642) (xy 427.521499 -42.31124) (xy 427.473382 -42.238798)
			(xy 427.432562 -42.162007) (xy 427.399429 -42.0816) (xy 427.374299 -41.998344) (xy 427.357411 -41.913034)
			(xy 427.348927 -41.826483) (xy 427.348927 -41.739517) (xy 427.357411 -41.652966) (xy 427.374299 -41.567656)
			(xy 427.399429 -41.4844) (xy 427.432562 -41.403993) (xy 427.473382 -41.327202) (xy 427.521499 -41.25476)
			(xy 427.576453 -41.187358) (xy 427.606714 -41.156128) (xy 427.613826 -41.148762) (xy 427.621446 -41.130474)
			(xy 427.621446 -41.038526) (xy 427.613826 -41.020238) (xy 427.606714 -41.012872) (xy 427.57805 -40.983374)
			(xy 427.525714 -40.919915) (xy 427.479457 -40.851897) (xy 427.439673 -40.779901) (xy 427.406704 -40.704541)
			(xy 427.380829 -40.62646) (xy 427.362269 -40.546325) (xy 427.35627 -40.505634) (xy 427.35441 -40.495471)
			(xy 427.343784 -40.477774) (xy 427.335696 -40.471344) (xy 427.319694 -40.459406) (xy 427.31056 -40.453148)
			(xy 427.28896 -40.448389) (xy 427.26736 -40.453148) (xy 427.258226 -40.459406) (xy 427.221701 -40.486456)
			(xy 427.144079 -40.533749) (xy 427.062043 -40.572888) (xy 426.976446 -40.603465) (xy 426.888179 -40.625162)
			(xy 426.798161 -40.637754) (xy 426.752766 -40.64) (xy 426.743057 -40.640825) (xy 426.725294 -40.648791)
			(xy 426.718222 -40.655494) (xy 426.696886 -40.677084) (xy 426.690397 -40.684373) (xy 426.682948 -40.702392)
			(xy 426.682408 -40.712136) (xy 426.681553 -40.75555) (xy 426.672291 -40.841896) (xy 426.65466 -40.926928)
			(xy 426.628827 -41.009838) (xy 426.595038 -41.089836) (xy 426.553615 -41.166161) (xy 426.504951 -41.238086)
			(xy 426.449511 -41.304927) (xy 426.387822 -41.366048) (xy 426.32047 -41.420867) (xy 426.248098 -41.468862)
			(xy 426.171393 -41.509577) (xy 426.091085 -41.542623) (xy 426.00794 -41.567688) (xy 425.922748 -41.584531)
			(xy 425.83632 -41.592993) (xy 425.7929 -41.593516) (xy 425.75179 -41.593048) (xy 425.66992 -41.58546)
			(xy 425.589099 -41.570349) (xy 425.510018 -41.547845) (xy 425.433352 -41.518138) (xy 425.359754 -41.481483)
			(xy 425.289852 -41.438193) (xy 425.224244 -41.388636) (xy 425.16349 -41.333236) (xy 425.108107 -41.272466)
			(xy 425.058568 -41.206845) (xy 425.015297 -41.136931) (xy 424.978663 -41.063323) (xy 424.948977 -40.986648)
			(xy 424.926494 -40.907561) (xy 424.911406 -40.826737) (xy 424.903841 -40.744865) (xy 424.903392 -40.703754)
			(xy 413.337002 -40.703754) (xy 413.411827 -40.737925) (xy 413.485177 -40.780274) (xy 413.554169 -40.829403)
			(xy 413.618179 -40.884868) (xy 413.676627 -40.946166) (xy 413.728983 -41.012742) (xy 413.774773 -41.083994)
			(xy 413.813584 -41.159275) (xy 413.845063 -41.237905) (xy 413.868924 -41.319172) (xy 413.884953 -41.402338)
			(xy 413.893004 -41.486652) (xy 413.893508 -41.529) (xy 413.893005 -41.571315) (xy 413.884974 -41.655563)
			(xy 413.868976 -41.738666) (xy 413.845155 -41.819875) (xy 413.813728 -41.898452) (xy 413.774977 -41.973689)
			(xy 413.752538 -42.009568) (xy 413.747655 -42.017957) (xy 413.743983 -42.037) (xy 413.747655 -42.056043)
			(xy 413.752538 -42.064432) (xy 413.774984 -42.100306) (xy 413.813727 -42.175547) (xy 413.845151 -42.254126)
			(xy 413.86897 -42.335335) (xy 413.88497 -42.418438) (xy 413.893006 -42.502685) (xy 413.893508 -42.545)
			(xy 413.892993 -42.5882) (xy 413.884627 -42.674194) (xy 413.867965 -42.758972) (xy 413.843162 -42.841736)
			(xy 413.810454 -42.921705) (xy 413.770147 -42.998127) (xy 413.722622 -43.070282) (xy 413.668327 -43.13749)
			(xy 413.607772 -43.199119) (xy 413.541528 -43.254586) (xy 413.470219 -43.303371) (xy 413.394516 -43.345014)
			(xy 413.315134 -43.379122) (xy 413.232819 -43.405375) (xy 413.19069 -43.41495) (xy 413.180022 -43.417236)
			(xy 413.16275 -43.429682) (xy 413.113982 -43.513502) (xy 413.111696 -43.534838) (xy 413.114998 -43.544998)
			(xy 413.121742 -43.566575) (xy 413.133304 -43.610284) (xy 413.138112 -43.632374) (xy 413.140652 -43.644566)
			(xy 413.1564 -43.663616) (xy 413.244792 -43.701208) (xy 413.256366 -43.705263) (xy 413.280771 -43.703284)
			(xy 413.291528 -43.697398) (xy 413.291782 -43.697398) (xy 413.327317 -43.675598) (xy 413.401707 -43.637955)
			(xy 413.479293 -43.607436) (xy 413.559394 -43.58431) (xy 413.641307 -43.568779) (xy 413.724314 -43.560979)
			(xy 413.766 -43.560492) (xy 413.808348 -43.560996) (xy 413.892662 -43.569047) (xy 413.975828 -43.585076)
			(xy 414.057095 -43.608937) (xy 414.135725 -43.640416) (xy 414.211006 -43.679227) (xy 414.282258 -43.725017)
			(xy 414.348834 -43.777373) (xy 414.410132 -43.835821) (xy 414.465597 -43.899831) (xy 414.514726 -43.968823)
			(xy 414.557075 -44.042173) (xy 414.588672 -44.111361) (xy 414.807142 -44.111361) (xy 414.807142 -44.026639)
			(xy 414.815195 -43.942302) (xy 414.831229 -43.859112) (xy 414.855097 -43.777822) (xy 414.886585 -43.69917)
			(xy 414.925407 -43.623867) (xy 414.97121 -43.552595) (xy 415.023581 -43.485999) (xy 415.082046 -43.424684)
			(xy 415.146074 -43.369203) (xy 415.215086 -43.32006) (xy 415.288456 -43.2777) (xy 415.365521 -43.242505)
			(xy 415.445583 -43.214796) (xy 415.527916 -43.194822) (xy 415.611775 -43.182765) (xy 415.6964 -43.178734)
			(xy 415.781025 -43.182765) (xy 415.864884 -43.194822) (xy 415.947217 -43.214796) (xy 416.027279 -43.242505)
			(xy 416.104344 -43.2777) (xy 416.177714 -43.32006) (xy 416.246726 -43.369203) (xy 416.310754 -43.424684)
			(xy 416.369219 -43.485999) (xy 416.42159 -43.552595) (xy 416.467393 -43.623867) (xy 416.506215 -43.69917)
			(xy 416.537703 -43.777822) (xy 416.561571 -43.859112) (xy 416.577605 -43.942302) (xy 416.585658 -44.026639)
			(xy 416.586162 -44.069) (xy 416.585658 -44.111361) (xy 416.577605 -44.195698) (xy 416.561571 -44.278888)
			(xy 416.537703 -44.360178) (xy 416.506215 -44.43883) (xy 416.467393 -44.514133) (xy 416.42159 -44.585405)
			(xy 416.369219 -44.652001) (xy 416.310754 -44.713316) (xy 416.246726 -44.768797) (xy 416.177714 -44.81794)
			(xy 416.104344 -44.8603) (xy 416.027279 -44.895495) (xy 415.947217 -44.923204) (xy 415.864884 -44.943178)
			(xy 415.781025 -44.955235) (xy 415.6964 -44.959267) (xy 415.611775 -44.955235) (xy 415.527916 -44.943178)
			(xy 415.445583 -44.923204) (xy 415.365521 -44.895495) (xy 415.288456 -44.8603) (xy 415.215086 -44.81794)
			(xy 415.146074 -44.768797) (xy 415.082046 -44.713316) (xy 415.023581 -44.652001) (xy 414.97121 -44.585405)
			(xy 414.925407 -44.514133) (xy 414.886585 -44.43883) (xy 414.855097 -44.360178) (xy 414.831229 -44.278888)
			(xy 414.815195 -44.195698) (xy 414.807142 -44.111361) (xy 414.588672 -44.111361) (xy 414.592259 -44.119216)
			(xy 414.619961 -44.199255) (xy 414.639929 -44.281564) (xy 414.651982 -44.365399) (xy 414.656013 -44.45)
			(xy 414.651982 -44.534601) (xy 414.639929 -44.618436) (xy 414.619961 -44.700745) (xy 414.592259 -44.780784)
			(xy 414.557075 -44.857827) (xy 414.514726 -44.931177) (xy 414.465597 -45.000169) (xy 414.410132 -45.064179)
			(xy 414.348834 -45.122627) (xy 414.282258 -45.174983) (xy 414.211006 -45.220773) (xy 414.135725 -45.259584)
			(xy 414.057095 -45.291063) (xy 413.975828 -45.314924) (xy 413.892662 -45.330953) (xy 413.808348 -45.339004)
			(xy 413.766 -45.339508) (xy 413.765492 -45.339508) (xy 413.725368 -45.339032) (xy 413.645447 -45.331785)
			(xy 413.566504 -45.317367) (xy 413.489181 -45.295897) (xy 413.414106 -45.267549) (xy 413.34189 -45.232553)
			(xy 413.307276 -45.212254) (xy 413.299722 -45.208112) (xy 413.282877 -45.204576) (xy 413.265817 -45.20686)
			(xy 413.258 -45.210476) (xy 413.169354 -45.255688) (xy 413.154876 -45.277024) (xy 413.153606 -45.290232)
			(xy 413.149558 -45.331263) (xy 413.134727 -45.412375) (xy 413.112454 -45.491767) (xy 413.08293 -45.568757)
			(xy 413.046408 -45.642685) (xy 413.003202 -45.712915) (xy 412.953682 -45.778846) (xy 412.898273 -45.839912)
			(xy 412.837451 -45.895588) (xy 412.771738 -45.945397) (xy 412.701698 -45.988911) (xy 412.627931 -46.025757)
			(xy 412.551072 -46.055618) (xy 412.471779 -46.078239) (xy 412.390732 -46.093426) (xy 412.308628 -46.101047)
			(xy 412.2674 -46.101508) (xy 412.226298 -46.101033) (xy 412.144443 -46.093448) (xy 412.063638 -46.078343)
			(xy 411.984571 -46.055847) (xy 411.907917 -46.026151) (xy 411.83433 -45.989509) (xy 411.764438 -45.946234)
			(xy 411.698837 -45.896694) (xy 411.638087 -45.841313) (xy 411.582706 -45.780563) (xy 411.533166 -45.714962)
			(xy 411.489891 -45.64507) (xy 411.453249 -45.571483) (xy 411.423553 -45.494829) (xy 411.401057 -45.415762)
			(xy 411.385952 -45.334957) (xy 411.378367 -45.253102) (xy 411.377892 -45.212) (xy 402.6154 -45.212)
			(xy 402.6154 -46.863) (xy 416.177988 -46.863) (xy 416.182018 -46.778399) (xy 416.194071 -46.694564)
			(xy 416.214039 -46.612255) (xy 416.241741 -46.532216) (xy 416.276925 -46.455173) (xy 416.319274 -46.381823)
			(xy 416.368403 -46.312831) (xy 416.423868 -46.248821) (xy 416.485166 -46.190373) (xy 416.551742 -46.138017)
			(xy 416.622994 -46.092227) (xy 416.698275 -46.053416) (xy 416.776905 -46.021937) (xy 416.858172 -45.998076)
			(xy 416.941338 -45.982047) (xy 417.025652 -45.973996) (xy 417.068 -45.973492) (xy 417.068508 -45.973492)
			(xy 417.11484 -45.974098) (xy 417.206998 -45.983769) (xy 417.297652 -46.002965) (xy 417.385821 -46.031477)
			(xy 417.428426 -46.049692) (xy 417.438368 -46.053498) (xy 417.459632 -46.053498) (xy 417.469574 -46.049692)
			(xy 417.512236 -46.031447) (xy 417.600529 -46.002903) (xy 417.691314 -45.98371) (xy 417.783604 -45.974077)
			(xy 417.83 -45.973492) (xy 417.867812 -45.973862) (xy 417.943167 -45.980241) (xy 418.017707 -45.993004)
			(xy 418.090891 -46.012059) (xy 418.126672 -46.024292) (xy 418.126926 -46.024292) (xy 418.135499 -46.026993)
			(xy 418.153464 -46.02675) (xy 418.170233 -46.0203) (xy 418.177218 -46.01464) (xy 418.254434 -45.947076)
			(xy 418.26307 -45.92066) (xy 418.260022 -45.907198) (xy 418.250668 -45.860964) (xy 418.240615 -45.767167)
			(xy 418.239956 -45.72) (xy 418.240446 -45.678974) (xy 418.248011 -45.59727) (xy 418.263067 -45.516611)
			(xy 418.285487 -45.43768) (xy 418.315081 -45.36115) (xy 418.351596 -45.28767) (xy 418.394722 -45.217864)
			(xy 418.444093 -45.152327) (xy 418.499289 -45.091614) (xy 418.559841 -45.036242) (xy 418.592254 -45.011086)
			(xy 418.602668 -45.003212) (xy 418.613336 -44.979082) (xy 418.602668 -44.866814) (xy 418.587936 -44.845224)
			(xy 418.575998 -44.839382) (xy 418.539474 -44.820596) (xy 418.46966 -44.777322) (xy 418.404133 -44.727795)
			(xy 418.343452 -44.672437) (xy 418.288134 -44.61172) (xy 418.23865 -44.546161) (xy 418.195421 -44.476318)
			(xy 418.158816 -44.402788) (xy 418.129147 -44.326195) (xy 418.106667 -44.247194) (xy 418.091566 -44.166455)
			(xy 418.083974 -44.084669) (xy 418.083492 -44.0436) (xy 418.083492 -44.043092) (xy 418.083996 -44.000744)
			(xy 418.092047 -43.91643) (xy 418.108076 -43.833264) (xy 418.131937 -43.751997) (xy 418.163416 -43.673367)
			(xy 418.202227 -43.598086) (xy 418.248017 -43.526834) (xy 418.300373 -43.460258) (xy 418.358821 -43.39896)
			(xy 418.422831 -43.343495) (xy 418.491823 -43.294366) (xy 418.565173 -43.252017) (xy 418.642216 -43.216833)
			(xy 418.722255 -43.189131) (xy 418.804564 -43.169163) (xy 418.888399 -43.15711) (xy 418.973 -43.15308)
			(xy 419.057601 -43.15711) (xy 419.141436 -43.169163) (xy 419.223745 -43.189131) (xy 419.303784 -43.216833)
			(xy 419.380827 -43.252017) (xy 419.454177 -43.294366) (xy 419.523169 -43.343495) (xy 419.587179 -43.39896)
			(xy 419.645627 -43.460258) (xy 419.697983 -43.526834) (xy 419.743773 -43.598086) (xy 419.782584 -43.673367)
			(xy 419.814063 -43.751997) (xy 419.837924 -43.833264) (xy 419.853953 -43.91643) (xy 419.862004 -44.000744)
			(xy 419.862508 -44.043092) (xy 419.862066 -44.084113) (xy 419.854514 -44.165806) (xy 419.839473 -44.246457)
			(xy 419.817071 -44.325381) (xy 419.787498 -44.401907) (xy 419.751006 -44.475386) (xy 419.707904 -44.545193)
			(xy 419.658559 -44.610736) (xy 419.603389 -44.671458) (xy 419.542863 -44.726842) (xy 419.510464 -44.752006)
			(xy 419.50005 -44.75988) (xy 419.489382 -44.78401) (xy 419.50005 -44.896278) (xy 419.514782 -44.917868)
			(xy 419.52672 -44.92371) (xy 419.563288 -44.942468) (xy 419.633148 -44.98577) (xy 419.698717 -45.03533)
			(xy 419.759436 -45.090726) (xy 419.814787 -45.151485) (xy 419.864299 -45.217091) (xy 419.907549 -45.286983)
			(xy 419.94417 -45.360565) (xy 419.973847 -45.437212) (xy 419.99633 -45.516269) (xy 420.011426 -45.597063)
			(xy 420.014973 -45.635361) (xy 420.242742 -45.635361) (xy 420.242742 -45.550639) (xy 420.250795 -45.466302)
			(xy 420.266829 -45.383112) (xy 420.290697 -45.301822) (xy 420.322185 -45.22317) (xy 420.361007 -45.147867)
			(xy 420.40681 -45.076595) (xy 420.459181 -45.009999) (xy 420.517646 -44.948684) (xy 420.581674 -44.893203)
			(xy 420.650686 -44.84406) (xy 420.724056 -44.8017) (xy 420.801121 -44.766505) (xy 420.881183 -44.738796)
			(xy 420.963516 -44.718822) (xy 421.047375 -44.706765) (xy 421.132 -44.702734) (xy 421.216625 -44.706765)
			(xy 421.300484 -44.718822) (xy 421.382817 -44.738796) (xy 421.462879 -44.766505) (xy 421.539944 -44.8017)
			(xy 421.613314 -44.84406) (xy 421.682326 -44.893203) (xy 421.746354 -44.948684) (xy 421.804819 -45.009999)
			(xy 421.85719 -45.076595) (xy 421.902993 -45.147867) (xy 421.941815 -45.22317) (xy 421.973303 -45.301822)
			(xy 421.997171 -45.383112) (xy 422.013205 -45.466302) (xy 422.021258 -45.550639) (xy 422.021762 -45.593)
			(xy 422.021258 -45.635361) (xy 422.013205 -45.719698) (xy 421.997171 -45.802888) (xy 421.973303 -45.884178)
			(xy 421.941815 -45.96283) (xy 421.902993 -46.038133) (xy 421.85719 -46.109405) (xy 421.8205 -46.156061)
			(xy 423.811442 -46.156061) (xy 423.811442 -46.071339) (xy 423.819495 -45.987002) (xy 423.835529 -45.903812)
			(xy 423.859397 -45.822522) (xy 423.890885 -45.74387) (xy 423.929707 -45.668567) (xy 423.97551 -45.597295)
			(xy 424.027881 -45.530699) (xy 424.086346 -45.469384) (xy 424.150374 -45.413903) (xy 424.219386 -45.36476)
			(xy 424.292756 -45.3224) (xy 424.369821 -45.287205) (xy 424.449883 -45.259496) (xy 424.532216 -45.239522)
			(xy 424.616075 -45.227465) (xy 424.7007 -45.223434) (xy 424.785325 -45.227465) (xy 424.869184 -45.239522)
			(xy 424.951517 -45.259496) (xy 425.031579 -45.287205) (xy 425.108644 -45.3224) (xy 425.182014 -45.36476)
			(xy 425.251026 -45.413903) (xy 425.315054 -45.469384) (xy 425.373519 -45.530699) (xy 425.42589 -45.597295)
			(xy 425.471693 -45.668567) (xy 425.510515 -45.74387) (xy 425.542003 -45.822522) (xy 425.565871 -45.903812)
			(xy 425.581905 -45.987002) (xy 425.589958 -46.071339) (xy 425.590462 -46.1137) (xy 425.589958 -46.156061)
			(xy 425.581905 -46.240398) (xy 425.565871 -46.323588) (xy 425.542003 -46.404878) (xy 425.510515 -46.48353)
			(xy 425.471693 -46.558833) (xy 425.42589 -46.630105) (xy 425.373519 -46.696701) (xy 425.315054 -46.758016)
			(xy 425.251026 -46.813497) (xy 425.182014 -46.86264) (xy 425.108644 -46.905) (xy 425.031579 -46.940195)
			(xy 424.951517 -46.967904) (xy 424.869184 -46.987878) (xy 424.785325 -46.999935) (xy 424.7007 -47.003967)
			(xy 424.616075 -46.999935) (xy 424.532216 -46.987878) (xy 424.449883 -46.967904) (xy 424.369821 -46.940195)
			(xy 424.292756 -46.905) (xy 424.219386 -46.86264) (xy 424.150374 -46.813497) (xy 424.086346 -46.758016)
			(xy 424.027881 -46.696701) (xy 423.97551 -46.630105) (xy 423.929707 -46.558833) (xy 423.890885 -46.48353)
			(xy 423.859397 -46.404878) (xy 423.835529 -46.323588) (xy 423.819495 -46.240398) (xy 423.811442 -46.156061)
			(xy 421.8205 -46.156061) (xy 421.804819 -46.176001) (xy 421.746354 -46.237316) (xy 421.682326 -46.292797)
			(xy 421.613314 -46.34194) (xy 421.539944 -46.3843) (xy 421.462879 -46.419495) (xy 421.382817 -46.447204)
			(xy 421.300484 -46.467178) (xy 421.216625 -46.479235) (xy 421.132 -46.483267) (xy 421.047375 -46.479235)
			(xy 420.963516 -46.467178) (xy 420.881183 -46.447204) (xy 420.801121 -46.419495) (xy 420.724056 -46.3843)
			(xy 420.650686 -46.34194) (xy 420.581674 -46.292797) (xy 420.517646 -46.237316) (xy 420.459181 -46.176001)
			(xy 420.40681 -46.109405) (xy 420.361007 -46.038133) (xy 420.322185 -45.96283) (xy 420.290697 -45.884178)
			(xy 420.266829 -45.802888) (xy 420.250795 -45.719698) (xy 420.242742 -45.635361) (xy 420.014973 -45.635361)
			(xy 420.019006 -45.678904) (xy 420.01948 -45.72) (xy 420.019048 -45.761111) (xy 420.011459 -45.842983)
			(xy 419.996348 -45.923806) (xy 419.973842 -46.002889) (xy 419.944134 -46.079557) (xy 419.907477 -46.153157)
			(xy 419.864185 -46.223059) (xy 419.814626 -46.288668) (xy 419.759224 -46.349423) (xy 419.698451 -46.404806)
			(xy 419.632826 -46.454344) (xy 419.56291 -46.497615) (xy 419.489299 -46.534248) (xy 419.412621 -46.563932)
			(xy 419.333531 -46.586413) (xy 419.252704 -46.601498) (xy 419.17083 -46.609061) (xy 419.129718 -46.609508)
			(xy 419.091906 -46.609133) (xy 419.016551 -46.602756) (xy 418.942011 -46.589994) (xy 418.868827 -46.570941)
			(xy 418.833046 -46.558708) (xy 418.832792 -46.558708) (xy 418.824215 -46.556021) (xy 418.806253 -46.556259)
			(xy 418.789485 -46.562703) (xy 418.7825 -46.56836) (xy 418.705284 -46.635924) (xy 418.696648 -46.66234)
			(xy 418.699696 -46.675802) (xy 418.708949 -46.721791) (xy 418.718876 -46.815078) (xy 418.719508 -46.861984)
			(xy 418.719508 -46.863) (xy 418.719033 -46.904102) (xy 418.711448 -46.985957) (xy 418.696343 -47.066762)
			(xy 418.673847 -47.145829) (xy 418.644151 -47.222483) (xy 418.607509 -47.29607) (xy 418.564234 -47.365962)
			(xy 418.514694 -47.431563) (xy 418.459313 -47.492313) (xy 418.398563 -47.547694) (xy 418.332962 -47.597234)
			(xy 418.26307 -47.640509) (xy 418.189483 -47.677151) (xy 418.112829 -47.706847) (xy 418.033762 -47.729343)
			(xy 417.952957 -47.744448) (xy 417.871102 -47.752033) (xy 417.83 -47.752508) (xy 417.829492 -47.752508)
			(xy 417.78316 -47.751902) (xy 417.691002 -47.742231) (xy 417.600348 -47.723035) (xy 417.512179 -47.694523)
			(xy 417.469574 -47.676308) (xy 417.459632 -47.672502) (xy 417.438368 -47.672502) (xy 417.428426 -47.676308)
			(xy 417.385823 -47.69453) (xy 417.297656 -47.723048) (xy 417.207 -47.74224) (xy 417.11484 -47.7519)
			(xy 417.068508 -47.752508) (xy 417.068 -47.752508) (xy 417.025652 -47.752004) (xy 416.941338 -47.743953)
			(xy 416.858172 -47.727924) (xy 416.776905 -47.704063) (xy 416.698275 -47.672584) (xy 416.622994 -47.633773)
			(xy 416.551742 -47.587983) (xy 416.485166 -47.535627) (xy 416.423868 -47.477179) (xy 416.368403 -47.413169)
			(xy 416.319274 -47.344177) (xy 416.276925 -47.270827) (xy 416.241741 -47.193784) (xy 416.214039 -47.113745)
			(xy 416.194071 -47.031436) (xy 416.182018 -46.947601) (xy 416.177988 -46.863) (xy 402.6154 -46.863)
			(xy 402.6154 -48.048361) (xy 411.606742 -48.048361) (xy 411.606742 -47.963639) (xy 411.614795 -47.879302)
			(xy 411.630829 -47.796112) (xy 411.654697 -47.714822) (xy 411.686185 -47.63617) (xy 411.725007 -47.560867)
			(xy 411.77081 -47.489595) (xy 411.823181 -47.422999) (xy 411.881646 -47.361684) (xy 411.945674 -47.306203)
			(xy 412.014686 -47.25706) (xy 412.088056 -47.2147) (xy 412.165121 -47.179505) (xy 412.245183 -47.151796)
			(xy 412.327516 -47.131822) (xy 412.411375 -47.119765) (xy 412.496 -47.115734) (xy 412.580625 -47.119765)
			(xy 412.664484 -47.131822) (xy 412.746817 -47.151796) (xy 412.826879 -47.179505) (xy 412.903944 -47.2147)
			(xy 412.977314 -47.25706) (xy 413.046326 -47.306203) (xy 413.110354 -47.361684) (xy 413.168819 -47.422999)
			(xy 413.22119 -47.489595) (xy 413.266993 -47.560867) (xy 413.305815 -47.63617) (xy 413.337303 -47.714822)
			(xy 413.361171 -47.796112) (xy 413.377205 -47.879302) (xy 413.385258 -47.963639) (xy 413.385592 -47.991719)
			(xy 413.533332 -47.991719) (xy 413.533332 -47.906997) (xy 413.541385 -47.82266) (xy 413.557419 -47.73947)
			(xy 413.581287 -47.65818) (xy 413.612775 -47.579528) (xy 413.651597 -47.504225) (xy 413.6974 -47.432953)
			(xy 413.749771 -47.366357) (xy 413.808236 -47.305042) (xy 413.872264 -47.249561) (xy 413.941276 -47.200418)
			(xy 414.014646 -47.158058) (xy 414.091711 -47.122863) (xy 414.171773 -47.095154) (xy 414.254106 -47.07518)
			(xy 414.337965 -47.063123) (xy 414.42259 -47.059092) (xy 414.507215 -47.063123) (xy 414.591074 -47.07518)
			(xy 414.673407 -47.095154) (xy 414.753469 -47.122863) (xy 414.830534 -47.158058) (xy 414.903904 -47.200418)
			(xy 414.972916 -47.249561) (xy 415.036944 -47.305042) (xy 415.095409 -47.366357) (xy 415.14778 -47.432953)
			(xy 415.193583 -47.504225) (xy 415.232405 -47.579528) (xy 415.263893 -47.65818) (xy 415.287761 -47.73947)
			(xy 415.303795 -47.82266) (xy 415.311848 -47.906997) (xy 415.312352 -47.949358) (xy 415.311848 -47.991719)
			(xy 415.303795 -48.076056) (xy 415.287761 -48.159246) (xy 415.263893 -48.240536) (xy 415.232405 -48.319188)
			(xy 415.193583 -48.394491) (xy 415.14778 -48.465763) (xy 415.095409 -48.532359) (xy 415.036944 -48.593674)
			(xy 414.972916 -48.649155) (xy 414.903904 -48.698298) (xy 414.830534 -48.740658) (xy 414.753469 -48.775853)
			(xy 414.673407 -48.803562) (xy 414.591074 -48.823536) (xy 414.507215 -48.835593) (xy 414.42259 -48.839625)
			(xy 414.337965 -48.835593) (xy 414.254106 -48.823536) (xy 414.171773 -48.803562) (xy 414.091711 -48.775853)
			(xy 414.014646 -48.740658) (xy 413.941276 -48.698298) (xy 413.872264 -48.649155) (xy 413.808236 -48.593674)
			(xy 413.749771 -48.532359) (xy 413.6974 -48.465763) (xy 413.651597 -48.394491) (xy 413.612775 -48.319188)
			(xy 413.581287 -48.240536) (xy 413.557419 -48.159246) (xy 413.541385 -48.076056) (xy 413.533332 -47.991719)
			(xy 413.385592 -47.991719) (xy 413.385762 -48.006) (xy 413.385258 -48.048361) (xy 413.377205 -48.132698)
			(xy 413.361171 -48.215888) (xy 413.337303 -48.297178) (xy 413.305815 -48.37583) (xy 413.266993 -48.451133)
			(xy 413.22119 -48.522405) (xy 413.168819 -48.589001) (xy 413.110354 -48.650316) (xy 413.046326 -48.705797)
			(xy 412.977314 -48.75494) (xy 412.903944 -48.7973) (xy 412.826879 -48.832495) (xy 412.746817 -48.860204)
			(xy 412.664484 -48.880178) (xy 412.580625 -48.892235) (xy 412.522592 -48.895) (xy 419.225988 -48.895)
			(xy 419.230018 -48.810399) (xy 419.242071 -48.726564) (xy 419.262039 -48.644255) (xy 419.289741 -48.564216)
			(xy 419.324925 -48.487173) (xy 419.367274 -48.413823) (xy 419.416403 -48.344831) (xy 419.471868 -48.280821)
			(xy 419.533166 -48.222373) (xy 419.599742 -48.170017) (xy 419.670994 -48.124227) (xy 419.746275 -48.085416)
			(xy 419.824905 -48.053937) (xy 419.906172 -48.030076) (xy 419.989338 -48.014047) (xy 420.073652 -48.005996)
			(xy 420.116 -48.005492) (xy 420.116254 -48.005492) (xy 420.168635 -48.006265) (xy 420.272666 -48.018617)
			(xy 420.323772 -48.03013) (xy 420.33234 -48.031758) (xy 420.349665 -48.029875) (xy 420.365378 -48.022337)
			(xy 420.371778 -48.016414) (xy 420.403115 -47.985451) (xy 420.470886 -47.929158) (xy 420.543886 -47.879836)
			(xy 420.621403 -47.837968) (xy 420.702676 -47.803962) (xy 420.786911 -47.778153) (xy 420.873284 -47.760791)
			(xy 420.96095 -47.752048) (xy 421.005 -47.751492) (xy 421.046587 -47.751959) (xy 421.129397 -47.759724)
			(xy 421.211121 -47.775184) (xy 421.291045 -47.798207) (xy 421.368471 -47.828589) (xy 421.442723 -47.866067)
			(xy 421.513151 -47.910312) (xy 421.579142 -47.960939) (xy 421.640119 -48.017504) (xy 421.695549 -48.079515)
			(xy 421.744948 -48.14643) (xy 421.762386 -48.175361) (xy 422.801792 -48.175361) (xy 422.801792 -48.090639)
			(xy 422.809845 -48.006302) (xy 422.825879 -47.923112) (xy 422.849747 -47.841822) (xy 422.881235 -47.76317)
			(xy 422.920057 -47.687867) (xy 422.96586 -47.616595) (xy 423.018231 -47.549999) (xy 423.076696 -47.488684)
			(xy 423.140724 -47.433203) (xy 423.209736 -47.38406) (xy 423.283106 -47.3417) (xy 423.360171 -47.306505)
			(xy 423.440233 -47.278796) (xy 423.522566 -47.258822) (xy 423.606425 -47.246765) (xy 423.69105 -47.242734)
			(xy 423.775675 -47.246765) (xy 423.859534 -47.258822) (xy 423.941867 -47.278796) (xy 424.021929 -47.306505)
			(xy 424.098994 -47.3417) (xy 424.172364 -47.38406) (xy 424.241376 -47.433203) (xy 424.305404 -47.488684)
			(xy 424.363869 -47.549999) (xy 424.41624 -47.616595) (xy 424.462043 -47.687867) (xy 424.500865 -47.76317)
			(xy 424.532353 -47.841822) (xy 424.556221 -47.923112) (xy 424.572255 -48.006302) (xy 424.580308 -48.090639)
			(xy 424.580812 -48.133) (xy 424.580308 -48.175361) (xy 424.572255 -48.259698) (xy 424.556221 -48.342888)
			(xy 424.532353 -48.424178) (xy 424.500865 -48.50283) (xy 424.462043 -48.578133) (xy 424.41624 -48.649405)
			(xy 424.363869 -48.716001) (xy 424.305404 -48.777316) (xy 424.241376 -48.832797) (xy 424.172364 -48.88194)
			(xy 424.098994 -48.9243) (xy 424.021929 -48.959495) (xy 423.941867 -48.987204) (xy 423.859534 -49.007178)
			(xy 423.775675 -49.019235) (xy 423.69105 -49.023267) (xy 423.606425 -49.019235) (xy 423.522566 -49.007178)
			(xy 423.440233 -48.987204) (xy 423.360171 -48.959495) (xy 423.283106 -48.9243) (xy 423.209736 -48.88194)
			(xy 423.140724 -48.832797) (xy 423.076696 -48.777316) (xy 423.018231 -48.716001) (xy 422.96586 -48.649405)
			(xy 422.920057 -48.578133) (xy 422.881235 -48.50283) (xy 422.849747 -48.424178) (xy 422.825879 -48.342888)
			(xy 422.809845 -48.259698) (xy 422.801792 -48.175361) (xy 421.762386 -48.175361) (xy 421.787885 -48.217664)
			(xy 421.80637 -48.25492) (xy 421.811929 -48.264841) (xy 421.829733 -48.278946) (xy 421.84066 -48.282098)
			(xy 421.882137 -48.292216) (xy 421.963083 -48.319377) (xy 422.041054 -48.354168) (xy 422.115334 -48.396267)
			(xy 422.18524 -48.445288) (xy 422.25013 -48.50078) (xy 422.309405 -48.562232) (xy 422.362521 -48.629079)
			(xy 422.40899 -48.700707) (xy 422.448384 -48.776457) (xy 422.480341 -48.855632) (xy 422.504567 -48.937504)
			(xy 422.52084 -49.02132) (xy 422.529009 -49.106309) (xy 422.529508 -49.149) (xy 422.529508 -49.149508)
			(xy 422.529025 -49.19045) (xy 422.521487 -49.271988) (xy 422.506483 -49.352486) (xy 422.484142 -49.431265)
			(xy 422.454653 -49.507655) (xy 422.452795 -49.511401) (xy 425.621446 -49.511401) (xy 425.621446 -49.426679)
			(xy 425.629499 -49.342342) (xy 425.645533 -49.259152) (xy 425.669401 -49.177862) (xy 425.700889 -49.09921)
			(xy 425.739711 -49.023907) (xy 425.785514 -48.952635) (xy 425.837885 -48.886039) (xy 425.89635 -48.824724)
			(xy 425.960378 -48.769243) (xy 426.02939 -48.7201) (xy 426.10276 -48.67774) (xy 426.179825 -48.642545)
			(xy 426.259887 -48.614836) (xy 426.34222 -48.594862) (xy 426.426079 -48.582805) (xy 426.510704 -48.578774)
			(xy 426.595329 -48.582805) (xy 426.679188 -48.594862) (xy 426.761521 -48.614836) (xy 426.841583 -48.642545)
			(xy 426.918648 -48.67774) (xy 426.992018 -48.7201) (xy 427.06103 -48.769243) (xy 427.125058 -48.824724)
			(xy 427.183523 -48.886039) (xy 427.235894 -48.952635) (xy 427.281697 -49.023907) (xy 427.320519 -49.09921)
			(xy 427.352007 -49.177862) (xy 427.375875 -49.259152) (xy 427.391909 -49.342342) (xy 427.399962 -49.426679)
			(xy 427.400466 -49.46904) (xy 427.399962 -49.511401) (xy 427.391909 -49.595738) (xy 427.375875 -49.678928)
			(xy 427.352007 -49.760218) (xy 427.320519 -49.83887) (xy 427.281697 -49.914173) (xy 427.235894 -49.985445)
			(xy 427.183523 -50.052041) (xy 427.125058 -50.113356) (xy 427.06103 -50.168837) (xy 426.992018 -50.21798)
			(xy 426.918648 -50.26034) (xy 426.841583 -50.295535) (xy 426.761521 -50.323244) (xy 426.679188 -50.343218)
			(xy 426.595329 -50.355275) (xy 426.510704 -50.359307) (xy 426.426079 -50.355275) (xy 426.34222 -50.343218)
			(xy 426.259887 -50.323244) (xy 426.179825 -50.295535) (xy 426.10276 -50.26034) (xy 426.02939 -50.21798)
			(xy 425.960378 -50.168837) (xy 425.89635 -50.113356) (xy 425.837885 -50.052041) (xy 425.785514 -49.985445)
			(xy 425.739711 -49.914173) (xy 425.700889 -49.83887) (xy 425.669401 -49.760218) (xy 425.645533 -49.678928)
			(xy 425.629499 -49.595738) (xy 425.621446 -49.511401) (xy 422.452795 -49.511401) (xy 422.418265 -49.581011)
			(xy 422.397174 -49.616106) (xy 422.391586 -49.62525) (xy 422.388538 -49.645824) (xy 422.413684 -49.738026)
			(xy 422.426892 -49.754282) (xy 422.43629 -49.759108) (xy 422.468951 -49.776799) (xy 422.531526 -49.81683)
			(xy 422.590547 -49.861938) (xy 422.645605 -49.911806) (xy 422.67124 -49.938686) (xy 422.679114 -49.947322)
			(xy 422.700958 -49.955704) (xy 422.791636 -49.948338) (xy 422.803155 -49.946873) (xy 422.823142 -49.935108)
			(xy 422.82999 -49.925732) (xy 422.854672 -49.889634) (xy 422.910069 -49.821965) (xy 422.97184 -49.76006)
			(xy 423.03939 -49.704517) (xy 423.112066 -49.655873) (xy 423.189165 -49.614597) (xy 423.269943 -49.581089)
			(xy 423.353621 -49.555672) (xy 423.439389 -49.538591) (xy 423.52642 -49.530011) (xy 423.570146 -49.529492)
			(xy 423.5704 -49.529492) (xy 423.611502 -49.529967) (xy 423.693357 -49.537552) (xy 423.774162 -49.552657)
			(xy 423.853229 -49.575153) (xy 423.929883 -49.604849) (xy 424.00347 -49.641491) (xy 424.073362 -49.684766)
			(xy 424.138963 -49.734306) (xy 424.199713 -49.789687) (xy 424.255094 -49.850437) (xy 424.304634 -49.916038)
			(xy 424.347909 -49.98593) (xy 424.384551 -50.059517) (xy 424.414247 -50.136171) (xy 424.436743 -50.215238)
			(xy 424.451848 -50.296043) (xy 424.459433 -50.377898) (xy 424.459908 -50.419) (xy 424.459437 -50.460531)
			(xy 424.451712 -50.543232) (xy 424.436309 -50.624852) (xy 424.413363 -50.704681) (xy 424.383074 -50.782023)
			(xy 424.345707 -50.856204) (xy 424.301585 -50.926578) (xy 424.251095 -50.992532) (xy 424.194675 -51.05349)
			(xy 424.132817 -51.108923) (xy 424.06606 -51.158347) (xy 423.994986 -51.201331) (xy 423.920214 -51.237502)
			(xy 423.842396 -51.266543) (xy 423.762208 -51.288203) (xy 423.68035 -51.302292) (xy 423.63898 -51.305968)
			(xy 423.629074 -51.30673) (xy 423.611802 -51.315366) (xy 423.558208 -51.374802) (xy 423.55208 -51.382214)
			(xy 423.54542 -51.400238) (xy 423.545254 -51.409854) (xy 423.545254 -51.410108) (xy 423.545508 -51.435)
			(xy 423.545033 -51.476102) (xy 423.537448 -51.557957) (xy 423.522343 -51.638762) (xy 423.499847 -51.717829)
			(xy 423.470151 -51.794483) (xy 423.433509 -51.86807) (xy 423.390234 -51.937962) (xy 423.340694 -52.003563)
			(xy 423.285313 -52.064313) (xy 423.224563 -52.119694) (xy 423.158962 -52.169234) (xy 423.114118 -52.197)
			(xy 431.437288 -52.197) (xy 431.437757 -52.154008) (xy 431.446047 -52.068424) (xy 431.462559 -51.98404)
			(xy 431.487139 -51.901644) (xy 431.519557 -51.822005) (xy 431.559511 -51.745867) (xy 431.606627 -51.673941)
			(xy 431.660466 -51.606898) (xy 431.720525 -51.545366) (xy 431.786242 -51.489917) (xy 431.857005 -51.441071)
			(xy 431.932152 -51.399283) (xy 432.010981 -51.364944) (xy 432.051714 -51.35118) (xy 432.062722 -51.346919)
			(xy 432.079515 -51.330374) (xy 432.087185 -51.308082) (xy 432.086258 -51.296316) (xy 432.082774 -51.267615)
			(xy 432.07909 -51.209911) (xy 432.078892 -51.181) (xy 432.079396 -51.138652) (xy 432.087447 -51.054338)
			(xy 432.103476 -50.971172) (xy 432.127337 -50.889905) (xy 432.158816 -50.811275) (xy 432.197627 -50.735994)
			(xy 432.243417 -50.664742) (xy 432.295773 -50.598166) (xy 432.354221 -50.536868) (xy 432.418231 -50.481403)
			(xy 432.487223 -50.432274) (xy 432.560573 -50.389925) (xy 432.637616 -50.354741) (xy 432.717655 -50.327039)
			(xy 432.799964 -50.307071) (xy 432.883799 -50.295018) (xy 432.9684 -50.290988) (xy 433.053001 -50.295018)
			(xy 433.136836 -50.307071) (xy 433.219145 -50.327039) (xy 433.299184 -50.354741) (xy 433.376227 -50.389925)
			(xy 433.449577 -50.432274) (xy 433.518569 -50.481403) (xy 433.582579 -50.536868) (xy 433.641027 -50.598166)
			(xy 433.693383 -50.664742) (xy 433.739173 -50.735994) (xy 433.777984 -50.811275) (xy 433.809463 -50.889905)
			(xy 433.833324 -50.971172) (xy 433.849353 -51.054338) (xy 433.857404 -51.138652) (xy 433.857908 -51.181)
			(xy 433.857388 -51.223981) (xy 433.849095 -51.309543) (xy 433.832586 -51.393906) (xy 433.808016 -51.476283)
			(xy 433.775613 -51.555905) (xy 433.73568 -51.63203) (xy 433.68859 -51.703947) (xy 433.634781 -51.770986)
			(xy 433.574755 -51.832521) (xy 433.509074 -51.887979) (xy 433.438348 -51.936841) (xy 433.363239 -51.978652)
			(xy 433.284446 -52.013023) (xy 433.243736 -52.02682) (xy 433.232719 -52.031059) (xy 433.215932 -52.047617)
			(xy 433.208264 -52.069915) (xy 433.208271 -52.07) (xy 436.371492 -52.07) (xy 436.371921 -52.029564)
			(xy 436.379252 -51.949025) (xy 436.393863 -51.869485) (xy 436.415633 -51.791598) (xy 436.444382 -51.716009)
			(xy 436.479874 -51.643342) (xy 436.521814 -51.574195) (xy 436.569858 -51.509141) (xy 436.623607 -51.448716)
			(xy 436.682619 -51.393419) (xy 436.746407 -51.343706) (xy 436.780178 -51.321462) (xy 436.790846 -51.314604)
			(xy 436.803292 -51.292252) (xy 436.80507 -51.18227) (xy 436.793132 -51.159664) (xy 436.782718 -51.152298)
			(xy 436.74747 -51.127481) (xy 436.681478 -51.072008) (xy 436.62116 -51.010413) (xy 436.567082 -50.943274)
			(xy 436.51975 -50.871219) (xy 436.47961 -50.794924) (xy 436.447036 -50.715104) (xy 436.422335 -50.632509)
			(xy 436.405737 -50.547911) (xy 436.3974 -50.462105) (xy 436.396892 -50.419) (xy 436.397293 -50.379744)
			(xy 436.404188 -50.301535) (xy 436.41795 -50.224238) (xy 436.438473 -50.148455) (xy 436.465596 -50.074777)
			(xy 436.499109 -50.003776) (xy 436.518558 -49.969674) (xy 436.52277 -49.961721) (xy 436.525927 -49.944017)
			(xy 436.522782 -49.926311) (xy 436.518558 -49.918366) (xy 436.4991 -49.88427) (xy 436.465598 -49.813265)
			(xy 436.438483 -49.739584) (xy 436.417965 -49.663801) (xy 436.404206 -49.586504) (xy 436.397311 -49.508296)
			(xy 436.396892 -49.46904) (xy 436.397396 -49.426692) (xy 436.405447 -49.342378) (xy 436.421476 -49.259212)
			(xy 436.445337 -49.177945) (xy 436.476816 -49.099315) (xy 436.515627 -49.024034) (xy 436.561417 -48.952782)
			(xy 436.613773 -48.886206) (xy 436.672221 -48.824908) (xy 436.736231 -48.769443) (xy 436.805223 -48.720314)
			(xy 436.878573 -48.677965) (xy 436.955616 -48.642781) (xy 437.035655 -48.615079) (xy 437.117964 -48.595111)
			(xy 437.201799 -48.583058) (xy 437.2864 -48.579028) (xy 437.371001 -48.583058) (xy 437.454836 -48.595111)
			(xy 437.537145 -48.615079) (xy 437.612038 -48.641) (xy 440.749987 -48.641) (xy 440.754017 -48.556401)
			(xy 440.76607 -48.472569) (xy 440.786037 -48.390261) (xy 440.813737 -48.310225) (xy 440.84892 -48.233183)
			(xy 440.891266 -48.159835) (xy 440.940392 -48.090844) (xy 440.995854 -48.026835) (xy 441.057149 -47.968388)
			(xy 441.123722 -47.916031) (xy 441.194971 -47.87024) (xy 441.270249 -47.831428) (xy 441.348876 -47.799948)
			(xy 441.430139 -47.776084) (xy 441.513302 -47.760052) (xy 441.597613 -47.751997) (xy 441.63996 -47.751492)
			(xy 441.682994 -47.751994) (xy 441.768661 -47.760295) (xy 441.853126 -47.776832) (xy 441.935598 -47.801451)
			(xy 442.015307 -47.833922) (xy 442.091505 -47.873941) (xy 442.163482 -47.921133) (xy 442.230564 -47.975058)
			(xy 442.292122 -48.03521) (xy 442.347582 -48.101028) (xy 442.396425 -48.171895) (xy 442.438193 -48.247149)
			(xy 442.455808 -48.286416) (xy 442.46154 -48.29867) (xy 442.478503 -48.319739) (xy 442.5004 -48.335619)
			(xy 442.525697 -48.345195) (xy 442.552621 -48.347797) (xy 442.579284 -48.343242) (xy 442.603816 -48.33185)
			(xy 442.6245 -48.314418) (xy 442.639884 -48.29217) (xy 442.644784 -48.279558) (xy 442.659282 -48.239954)
			(xy 442.694709 -48.163412) (xy 442.737221 -48.090566) (xy 442.786435 -48.02207) (xy 442.841911 -47.958539)
			(xy 442.90315 -47.900543) (xy 442.969602 -47.848602) (xy 443.040672 -47.803183) (xy 443.115721 -47.764694)
			(xy 443.194075 -47.73348) (xy 443.275032 -47.70982) (xy 443.357864 -47.693929) (xy 443.441828 -47.685947)
			(xy 443.484 -47.685452) (xy 443.526347 -47.686036) (xy 443.610656 -47.694086) (xy 443.693819 -47.710114)
			(xy 443.775081 -47.733975) (xy 443.853708 -47.765453) (xy 443.928986 -47.804261) (xy 444.000235 -47.85005)
			(xy 444.066808 -47.902404) (xy 444.128103 -47.960849) (xy 444.183566 -48.024856) (xy 444.232693 -48.093845)
			(xy 444.275039 -48.167191) (xy 444.310222 -48.244231) (xy 444.337922 -48.324266) (xy 444.35789 -48.406572)
			(xy 444.369943 -48.490403) (xy 444.373973 -48.575) (xy 444.369943 -48.659597) (xy 444.35789 -48.743428)
			(xy 444.337922 -48.825734) (xy 444.310222 -48.905769) (xy 444.275039 -48.982809) (xy 444.232693 -49.056155)
			(xy 444.183566 -49.125144) (xy 444.128103 -49.189151) (xy 444.066808 -49.247596) (xy 444.000235 -49.29995)
			(xy 443.928986 -49.345739) (xy 443.853708 -49.384547) (xy 443.775081 -49.416025) (xy 443.693819 -49.439886)
			(xy 443.610656 -49.455914) (xy 443.526347 -49.463964) (xy 443.484 -49.464468) (xy 443.440966 -49.463937)
			(xy 443.355299 -49.455642) (xy 443.270834 -49.43911) (xy 443.188362 -49.414494) (xy 443.108653 -49.382027)
			(xy 443.032454 -49.342011) (xy 442.960476 -49.294821) (xy 442.893394 -49.240899) (xy 442.831836 -49.180748)
			(xy 442.776376 -49.114931) (xy 442.727534 -49.044065) (xy 442.685766 -48.968811) (xy 442.668152 -48.929544)
			(xy 442.662318 -48.917345) (xy 442.645366 -48.896291) (xy 442.623485 -48.880423) (xy 442.598207 -48.870851)
			(xy 442.571303 -48.868246) (xy 442.544658 -48.872791) (xy 442.520139 -48.884166) (xy 442.499463 -48.901576)
			(xy 442.484079 -48.923801) (xy 442.479176 -48.936402) (xy 442.464661 -48.975999) (xy 442.429232 -49.052539)
			(xy 442.38672 -49.125382) (xy 442.337505 -49.193876) (xy 442.28203 -49.257405) (xy 442.220793 -49.3154)
			(xy 442.154342 -49.36734) (xy 442.083275 -49.412759) (xy 442.008228 -49.45125) (xy 441.929877 -49.482466)
			(xy 441.848923 -49.506128) (xy 441.766093 -49.522024) (xy 441.682131 -49.53001) (xy 441.63996 -49.530508)
			(xy 441.597613 -49.530003) (xy 441.513302 -49.521948) (xy 441.430139 -49.505916) (xy 441.348876 -49.482052)
			(xy 441.270249 -49.450572) (xy 441.194971 -49.41176) (xy 441.123722 -49.365969) (xy 441.057149 -49.313612)
			(xy 440.995854 -49.255165) (xy 440.940392 -49.191156) (xy 440.891266 -49.122165) (xy 440.84892 -49.048817)
			(xy 440.813737 -48.971775) (xy 440.786037 -48.891739) (xy 440.76607 -48.809431) (xy 440.754017 -48.725599)
			(xy 440.749987 -48.641) (xy 437.612038 -48.641) (xy 437.617184 -48.642781) (xy 437.694227 -48.677965)
			(xy 437.767577 -48.720314) (xy 437.836569 -48.769443) (xy 437.900579 -48.824908) (xy 437.959027 -48.886206)
			(xy 438.011383 -48.952782) (xy 438.057173 -49.024034) (xy 438.095984 -49.099315) (xy 438.127463 -49.177945)
			(xy 438.151324 -49.259212) (xy 438.167353 -49.342378) (xy 438.175404 -49.426692) (xy 438.175908 -49.46904)
			(xy 438.175479 -49.508296) (xy 438.16859 -49.586504) (xy 438.154833 -49.6638) (xy 438.134315 -49.739583)
			(xy 438.107197 -49.813262) (xy 438.073688 -49.884263) (xy 438.054242 -49.918366) (xy 438.049998 -49.926304)
			(xy 438.046853 -49.944017) (xy 438.05001 -49.961729) (xy 438.054242 -49.969674) (xy 438.073676 -50.003784)
			(xy 438.107181 -50.074786) (xy 438.134301 -50.148463) (xy 438.154822 -50.224244) (xy 438.168587 -50.301538)
			(xy 438.175487 -50.379745) (xy 438.175908 -50.419) (xy 438.175383 -50.461647) (xy 438.167221 -50.546548)
			(xy 438.159107 -50.588361) (xy 439.019692 -50.588361) (xy 439.019692 -50.503639) (xy 439.027745 -50.419302)
			(xy 439.043779 -50.336112) (xy 439.067647 -50.254822) (xy 439.099135 -50.17617) (xy 439.137957 -50.100867)
			(xy 439.18376 -50.029595) (xy 439.236131 -49.962999) (xy 439.294596 -49.901684) (xy 439.358624 -49.846203)
			(xy 439.427636 -49.79706) (xy 439.501006 -49.7547) (xy 439.578071 -49.719505) (xy 439.658133 -49.691796)
			(xy 439.740466 -49.671822) (xy 439.824325 -49.659765) (xy 439.90895 -49.655734) (xy 439.993575 -49.659765)
			(xy 440.077434 -49.671822) (xy 440.159767 -49.691796) (xy 440.239829 -49.719505) (xy 440.316894 -49.7547)
			(xy 440.390264 -49.79706) (xy 440.459276 -49.846203) (xy 440.523304 -49.901684) (xy 440.581769 -49.962999)
			(xy 440.63414 -50.029595) (xy 440.679943 -50.100867) (xy 440.718765 -50.17617) (xy 440.750253 -50.254822)
			(xy 440.774121 -50.336112) (xy 440.790155 -50.419302) (xy 440.798208 -50.503639) (xy 440.798712 -50.546)
			(xy 440.798208 -50.588361) (xy 440.790155 -50.672698) (xy 440.774121 -50.755888) (xy 440.750253 -50.837178)
			(xy 440.718765 -50.91583) (xy 440.679943 -50.991133) (xy 440.63414 -51.062405) (xy 440.581769 -51.129001)
			(xy 440.523304 -51.190316) (xy 440.459276 -51.245797) (xy 440.390264 -51.29494) (xy 440.316894 -51.3373)
			(xy 440.239829 -51.372495) (xy 440.159767 -51.400204) (xy 440.077434 -51.420178) (xy 439.993575 -51.432235)
			(xy 439.90895 -51.436267) (xy 439.824325 -51.432235) (xy 439.740466 -51.420178) (xy 439.658133 -51.400204)
			(xy 439.578071 -51.372495) (xy 439.501006 -51.3373) (xy 439.427636 -51.29494) (xy 439.358624 -51.245797)
			(xy 439.294596 -51.190316) (xy 439.236131 -51.129001) (xy 439.18376 -51.062405) (xy 439.137957 -50.991133)
			(xy 439.099135 -50.91583) (xy 439.067647 -50.837178) (xy 439.043779 -50.755888) (xy 439.027745 -50.672698)
			(xy 439.019692 -50.588361) (xy 438.159107 -50.588361) (xy 438.150972 -50.630279) (xy 438.126786 -50.712071)
			(xy 438.094883 -50.791173) (xy 438.055558 -50.866859) (xy 438.00917 -50.938435) (xy 437.956146 -51.005243)
			(xy 437.896973 -51.066671) (xy 437.832192 -51.122154) (xy 437.7624 -51.171184) (xy 437.725566 -51.192684)
			(xy 437.718078 -51.19736) (xy 437.706638 -51.210793) (xy 437.700417 -51.227303) (xy 437.699912 -51.236118)
			(xy 437.699404 -51.26609) (xy 437.699601 -51.274927) (xy 437.705346 -51.291631) (xy 437.716432 -51.305384)
			(xy 437.723788 -51.310286) (xy 437.726074 -51.311556) (xy 437.736606 -51.317274) (xy 437.760459 -51.31926)
			(xy 437.771794 -51.315366) (xy 437.811614 -51.299839) (xy 437.893571 -51.275569) (xy 437.977476 -51.259271)
			(xy 438.062559 -51.251093) (xy 438.105296 -51.250596) (xy 438.147646 -51.251076) (xy 438.231961 -51.259127)
			(xy 438.31513 -51.275156) (xy 438.396398 -51.299018) (xy 438.47503 -51.330497) (xy 438.550314 -51.369308)
			(xy 438.621567 -51.4151) (xy 438.688145 -51.467457) (xy 438.749445 -51.525906) (xy 438.804911 -51.589917)
			(xy 438.854042 -51.658911) (xy 438.896391 -51.732263) (xy 438.931577 -51.809308) (xy 438.933893 -51.816)
			(xy 443.083188 -51.816) (xy 443.083671 -51.77414) (xy 443.091519 -51.69079) (xy 443.107166 -51.608546)
			(xy 443.130472 -51.528136) (xy 443.161231 -51.450272) (xy 443.199171 -51.375643) (xy 443.243956 -51.30491)
			(xy 443.29519 -51.238698) (xy 443.35242 -51.177594) (xy 443.415138 -51.122138) (xy 443.48279 -51.072822)
			(xy 443.554777 -51.030081) (xy 443.630462 -50.994294) (xy 443.709175 -50.965778) (xy 443.790219 -50.944785)
			(xy 443.831472 -50.937668) (xy 443.844172 -50.935636) (xy 443.864492 -50.919888) (xy 443.904116 -50.829972)
			(xy 443.907286 -50.822092) (xy 443.908671 -50.805169) (xy 443.904462 -50.788719) (xy 443.900052 -50.781458)
			(xy 443.876713 -50.745099) (xy 443.836369 -50.668694) (xy 443.803629 -50.588734) (xy 443.778802 -50.505975)
			(xy 443.762123 -50.421197) (xy 443.753749 -50.335201) (xy 443.75324 -50.292) (xy 443.753744 -50.249639)
			(xy 443.761797 -50.165302) (xy 443.777831 -50.082112) (xy 443.801699 -50.000822) (xy 443.833187 -49.92217)
			(xy 443.872009 -49.846867) (xy 443.917812 -49.775595) (xy 443.970183 -49.708999) (xy 444.028648 -49.647684)
			(xy 444.092676 -49.592203) (xy 444.161688 -49.54306) (xy 444.235058 -49.5007) (xy 444.312123 -49.465505)
			(xy 444.392185 -49.437796) (xy 444.474518 -49.417822) (xy 444.558377 -49.405765) (xy 444.643002 -49.401734)
			(xy 444.727627 -49.405765) (xy 444.811486 -49.417822) (xy 444.893819 -49.437796) (xy 444.973881 -49.465505)
			(xy 445.050946 -49.5007) (xy 445.124316 -49.54306) (xy 445.165464 -49.572361) (xy 458.749142 -49.572361)
			(xy 458.749142 -49.487639) (xy 458.757195 -49.403302) (xy 458.773229 -49.320112) (xy 458.797097 -49.238822)
			(xy 458.828585 -49.16017) (xy 458.867407 -49.084867) (xy 458.91321 -49.013595) (xy 458.965581 -48.946999)
			(xy 459.024046 -48.885684) (xy 459.088074 -48.830203) (xy 459.157086 -48.78106) (xy 459.230456 -48.7387)
			(xy 459.307521 -48.703505) (xy 459.387583 -48.675796) (xy 459.469916 -48.655822) (xy 459.553775 -48.643765)
			(xy 459.6384 -48.639734) (xy 459.723025 -48.643765) (xy 459.806884 -48.655822) (xy 459.889217 -48.675796)
			(xy 459.969279 -48.703505) (xy 460.046344 -48.7387) (xy 460.119714 -48.78106) (xy 460.188726 -48.830203)
			(xy 460.252754 -48.885684) (xy 460.311219 -48.946999) (xy 460.36359 -49.013595) (xy 460.409393 -49.084867)
			(xy 460.448215 -49.16017) (xy 460.479703 -49.238822) (xy 460.503571 -49.320112) (xy 460.519605 -49.403302)
			(xy 460.527658 -49.487639) (xy 460.528162 -49.53) (xy 460.527658 -49.572361) (xy 460.519605 -49.656698)
			(xy 460.503571 -49.739888) (xy 460.479703 -49.821178) (xy 460.448215 -49.89983) (xy 460.409393 -49.975133)
			(xy 460.36359 -50.046405) (xy 460.311219 -50.113001) (xy 460.252754 -50.174316) (xy 460.188726 -50.229797)
			(xy 460.119714 -50.27894) (xy 460.046344 -50.3213) (xy 459.969279 -50.356495) (xy 459.889217 -50.384204)
			(xy 459.806884 -50.404178) (xy 459.723025 -50.416235) (xy 459.6384 -50.420267) (xy 459.553775 -50.416235)
			(xy 459.469916 -50.404178) (xy 459.387583 -50.384204) (xy 459.307521 -50.356495) (xy 459.230456 -50.3213)
			(xy 459.157086 -50.27894) (xy 459.088074 -50.229797) (xy 459.024046 -50.174316) (xy 458.965581 -50.113001)
			(xy 458.91321 -50.046405) (xy 458.867407 -49.975133) (xy 458.828585 -49.89983) (xy 458.797097 -49.821178)
			(xy 458.773229 -49.739888) (xy 458.757195 -49.656698) (xy 458.749142 -49.572361) (xy 445.165464 -49.572361)
			(xy 445.193328 -49.592203) (xy 445.257356 -49.647684) (xy 445.315821 -49.708999) (xy 445.368192 -49.775595)
			(xy 445.413995 -49.846867) (xy 445.452817 -49.92217) (xy 445.484305 -50.000822) (xy 445.508173 -50.082112)
			(xy 445.524207 -50.165302) (xy 445.53226 -50.249639) (xy 445.532764 -50.292) (xy 445.53219 -50.336316)
			(xy 445.52331 -50.424504) (xy 445.505698 -50.51137) (xy 445.49314 -50.553874) (xy 445.49314 -50.554128)
			(xy 445.490922 -50.562451) (xy 445.491587 -50.579654) (xy 445.497916 -50.595664) (xy 445.5033 -50.602388)
			(xy 445.560196 -50.667412) (xy 445.566137 -50.673668) (xy 445.581144 -50.682159) (xy 445.598113 -50.685211)
			(xy 445.606678 -50.684176) (xy 445.642241 -50.678719) (xy 445.713957 -50.67287) (xy 445.749934 -50.672492)
			(xy 445.75095 -50.672492) (xy 445.793301 -50.672978) (xy 445.877619 -50.681025) (xy 445.960791 -50.69705)
			(xy 446.042062 -50.72091) (xy 446.120698 -50.752387) (xy 446.195985 -50.791196) (xy 446.267242 -50.836987)
			(xy 446.333824 -50.889344) (xy 446.395127 -50.947793) (xy 446.450596 -51.011805) (xy 446.499729 -51.080799)
			(xy 446.542081 -51.154152) (xy 446.577269 -51.231199) (xy 446.604973 -51.311241) (xy 446.624943 -51.393555)
			(xy 446.636998 -51.477394) (xy 446.641028 -51.562) (xy 446.63901 -51.604361) (xy 448.544692 -51.604361)
			(xy 448.544692 -51.519639) (xy 448.552745 -51.435302) (xy 448.568779 -51.352112) (xy 448.592647 -51.270822)
			(xy 448.624135 -51.19217) (xy 448.662957 -51.116867) (xy 448.70876 -51.045595) (xy 448.761131 -50.978999)
			(xy 448.819596 -50.917684) (xy 448.883624 -50.862203) (xy 448.952636 -50.81306) (xy 449.026006 -50.7707)
			(xy 449.103071 -50.735505) (xy 449.183133 -50.707796) (xy 449.265466 -50.687822) (xy 449.349325 -50.675765)
			(xy 449.43395 -50.671734) (xy 449.518575 -50.675765) (xy 449.602434 -50.687822) (xy 449.684767 -50.707796)
			(xy 449.764829 -50.735505) (xy 449.841894 -50.7707) (xy 449.915264 -50.81306) (xy 449.984276 -50.862203)
			(xy 450.048304 -50.917684) (xy 450.106769 -50.978999) (xy 450.15914 -51.045595) (xy 450.204943 -51.116867)
			(xy 450.243765 -51.19217) (xy 450.275253 -51.270822) (xy 450.299121 -51.352112) (xy 450.315155 -51.435302)
			(xy 450.323208 -51.519639) (xy 450.323712 -51.562) (xy 450.323208 -51.604361) (xy 450.315155 -51.688698)
			(xy 450.299121 -51.771888) (xy 450.275253 -51.853178) (xy 450.243765 -51.93183) (xy 450.204943 -52.007133)
			(xy 450.15914 -52.078405) (xy 450.106769 -52.145001) (xy 450.048304 -52.206316) (xy 449.984276 -52.261797)
			(xy 449.915264 -52.31094) (xy 449.841894 -52.3533) (xy 449.764829 -52.388495) (xy 449.684767 -52.416204)
			(xy 449.602434 -52.436178) (xy 449.518575 -52.448235) (xy 449.43395 -52.452267) (xy 449.349325 -52.448235)
			(xy 449.265466 -52.436178) (xy 449.183133 -52.416204) (xy 449.103071 -52.388495) (xy 449.026006 -52.3533)
			(xy 448.952636 -52.31094) (xy 448.883624 -52.261797) (xy 448.819596 -52.206316) (xy 448.761131 -52.145001)
			(xy 448.70876 -52.078405) (xy 448.662957 -52.007133) (xy 448.624135 -51.93183) (xy 448.592647 -51.853178)
			(xy 448.568779 -51.771888) (xy 448.552745 -51.688698) (xy 448.544692 -51.604361) (xy 446.63901 -51.604361)
			(xy 446.636998 -51.646606) (xy 446.624943 -51.730445) (xy 446.604973 -51.812759) (xy 446.577269 -51.892801)
			(xy 446.542081 -51.969848) (xy 446.499729 -52.043201) (xy 446.450596 -52.112195) (xy 446.395127 -52.176207)
			(xy 446.333824 -52.234656) (xy 446.267242 -52.287013) (xy 446.195985 -52.332804) (xy 446.120698 -52.371613)
			(xy 446.042062 -52.40309) (xy 445.960791 -52.42695) (xy 445.877619 -52.442975) (xy 445.793301 -52.451022)
			(xy 445.75095 -52.451508) (xy 445.750442 -52.451508) (xy 445.706344 -52.450996) (xy 445.618583 -52.442226)
			(xy 445.532121 -52.424818) (xy 445.447804 -52.398943) (xy 445.366461 -52.364854) (xy 445.288889 -52.322886)
			(xy 445.215848 -52.27345) (xy 445.148057 -52.217031) (xy 445.086178 -52.154184) (xy 445.03082 -52.085523)
			(xy 445.006222 -52.048918) (xy 444.998094 -52.036472) (xy 444.971424 -52.02428) (xy 444.865506 -52.039266)
			(xy 444.856023 -52.041031) (xy 444.839313 -52.050643) (xy 444.827307 -52.065726) (xy 444.824104 -52.074826)
			(xy 444.810878 -52.116429) (xy 444.777408 -52.197062) (xy 444.736201 -52.274029) (xy 444.687651 -52.346589)
			(xy 444.632228 -52.414044) (xy 444.570463 -52.475745) (xy 444.502951 -52.531098) (xy 444.430342 -52.579573)
			(xy 444.353333 -52.620701) (xy 444.272665 -52.654087) (xy 444.189115 -52.679411) (xy 444.103486 -52.696429)
			(xy 444.016602 -52.704976) (xy 443.97295 -52.705508) (xy 443.931845 -52.70494) (xy 443.849986 -52.69736)
			(xy 443.769176 -52.682262) (xy 443.690102 -52.659773) (xy 443.613441 -52.630085) (xy 443.539845 -52.593451)
			(xy 443.469943 -52.550184) (xy 443.40433 -52.500654) (xy 443.343567 -52.445281) (xy 443.28817 -52.384539)
			(xy 443.238614 -52.318946) (xy 443.195319 -52.249061) (xy 443.158657 -52.175479) (xy 443.128939 -52.09883)
			(xy 443.106418 -52.019765) (xy 443.091288 -51.93896) (xy 443.083676 -51.857104) (xy 443.083188 -51.816)
			(xy 438.933893 -51.816) (xy 438.959279 -51.889348) (xy 438.979248 -51.97166) (xy 438.991302 -52.055497)
			(xy 438.995332 -52.1401) (xy 438.991302 -52.224703) (xy 438.979248 -52.30854) (xy 438.959279 -52.390852)
			(xy 438.931577 -52.470892) (xy 438.896391 -52.547937) (xy 438.854042 -52.621289) (xy 438.804911 -52.690283)
			(xy 438.749445 -52.754294) (xy 438.688145 -52.812743) (xy 438.621567 -52.8651) (xy 438.550314 -52.910892)
			(xy 438.47503 -52.949703) (xy 438.396398 -52.981182) (xy 438.31513 -53.005044) (xy 438.231961 -53.021073)
			(xy 438.147646 -53.029124) (xy 438.105296 -53.029612) (xy 438.06451 -53.02916) (xy 437.983277 -53.021733)
			(xy 437.903067 -53.006895) (xy 437.824553 -52.984771) (xy 437.748396 -52.955547) (xy 437.675236 -52.919469)
			(xy 437.640222 -52.898548) (xy 437.629691 -52.892827) (xy 437.605837 -52.890843) (xy 437.594502 -52.894738)
			(xy 437.554682 -52.910267) (xy 437.472726 -52.934536) (xy 437.38882 -52.950834) (xy 437.303737 -52.959011)
			(xy 437.261 -52.959508) (xy 437.219898 -52.959033) (xy 437.138043 -52.951448) (xy 437.057238 -52.936343)
			(xy 436.978171 -52.913847) (xy 436.901517 -52.884151) (xy 436.82793 -52.847509) (xy 436.758038 -52.804234)
			(xy 436.692437 -52.754694) (xy 436.631687 -52.699313) (xy 436.576306 -52.638563) (xy 436.526766 -52.572962)
			(xy 436.483491 -52.50307) (xy 436.446849 -52.429483) (xy 436.417153 -52.352829) (xy 436.394657 -52.273762)
			(xy 436.379552 -52.192957) (xy 436.371967 -52.111102) (xy 436.371492 -52.07) (xy 433.208271 -52.07)
			(xy 433.209192 -52.081684) (xy 433.212748 -52.110381) (xy 433.216558 -52.168085) (xy 433.216812 -52.197)
			(xy 433.216308 -52.239361) (xy 433.208255 -52.323698) (xy 433.192221 -52.406888) (xy 433.168353 -52.488178)
			(xy 433.136865 -52.56683) (xy 433.098043 -52.642133) (xy 433.05224 -52.713405) (xy 432.999869 -52.780001)
			(xy 432.941404 -52.841316) (xy 432.877376 -52.896797) (xy 432.808364 -52.94594) (xy 432.734994 -52.9883)
			(xy 432.657929 -53.023495) (xy 432.577867 -53.051204) (xy 432.495534 -53.071178) (xy 432.411675 -53.083235)
			(xy 432.32705 -53.087267) (xy 432.242425 -53.083235) (xy 432.158566 -53.071178) (xy 432.076233 -53.051204)
			(xy 431.996171 -53.023495) (xy 431.919106 -52.9883) (xy 431.845736 -52.94594) (xy 431.776724 -52.896797)
			(xy 431.712696 -52.841316) (xy 431.654231 -52.780001) (xy 431.60186 -52.713405) (xy 431.556057 -52.642133)
			(xy 431.517235 -52.56683) (xy 431.485747 -52.488178) (xy 431.461879 -52.406888) (xy 431.445845 -52.323698)
			(xy 431.437792 -52.239361) (xy 431.437288 -52.197) (xy 423.114118 -52.197) (xy 423.08907 -52.212509)
			(xy 423.015483 -52.249151) (xy 422.938829 -52.278847) (xy 422.859762 -52.301343) (xy 422.778957 -52.316448)
			(xy 422.697102 -52.324033) (xy 422.656 -52.324508) (xy 422.614905 -52.324034) (xy 422.533065 -52.316452)
			(xy 422.452274 -52.301352) (xy 422.373221 -52.278864) (xy 422.296579 -52.249178) (xy 422.223002 -52.212549)
			(xy 422.153118 -52.169289) (xy 422.087523 -52.119766) (xy 422.026777 -52.064403) (xy 421.971397 -52.003672)
			(xy 421.921855 -51.938091) (xy 421.878575 -51.86822) (xy 421.841924 -51.794654) (xy 421.812217 -51.71802)
			(xy 421.789706 -51.638973) (xy 421.774584 -51.558186) (xy 421.766978 -51.476349) (xy 421.766492 -51.435254)
			(xy 421.766492 -51.434746) (xy 421.767 -51.398678) (xy 421.728109 -51.386621) (xy 421.652528 -51.356316)
			(xy 421.580033 -51.319232) (xy 421.511229 -51.275679) (xy 421.446692 -51.226022) (xy 421.386963 -51.170676)
			(xy 421.33254 -51.110104) (xy 421.283879 -51.044813) (xy 421.241387 -50.975348) (xy 421.20542 -50.902292)
			(xy 421.176279 -50.826256) (xy 421.154207 -50.747874) (xy 421.139389 -50.667804) (xy 421.131948 -50.586715)
			(xy 421.131492 -50.546) (xy 421.131492 -50.545492) (xy 421.131975 -50.50455) (xy 421.139513 -50.423012)
			(xy 421.154517 -50.342514) (xy 421.176858 -50.263735) (xy 421.206347 -50.187345) (xy 421.242735 -50.113989)
			(xy 421.263826 -50.078894) (xy 421.269414 -50.06975) (xy 421.272462 -50.049176) (xy 421.247316 -49.956974)
			(xy 421.234108 -49.940718) (xy 421.22471 -49.935892) (xy 421.189175 -49.916589) (xy 421.121391 -49.87248)
			(xy 421.05789 -49.8224) (xy 420.999197 -49.766765) (xy 420.945794 -49.706031) (xy 420.898124 -49.640702)
			(xy 420.85658 -49.571317) (xy 420.83863 -49.53508) (xy 420.833187 -49.525019) (xy 420.815355 -49.51073)
			(xy 420.80434 -49.507648) (xy 420.797482 -49.506124) (xy 420.788876 -49.504361) (xy 420.771417 -49.50617)
			(xy 420.755617 -49.513817) (xy 420.749222 -49.51984) (xy 420.71791 -49.550821) (xy 420.650126 -49.607083)
			(xy 420.577115 -49.656371) (xy 420.499591 -49.698205) (xy 420.418313 -49.732174) (xy 420.334076 -49.757945)
			(xy 420.247705 -49.775268) (xy 420.160045 -49.783972) (xy 420.116 -49.784508) (xy 420.073652 -49.784004)
			(xy 419.989338 -49.775953) (xy 419.906172 -49.759924) (xy 419.824905 -49.736063) (xy 419.746275 -49.704584)
			(xy 419.670994 -49.665773) (xy 419.599742 -49.619983) (xy 419.533166 -49.567627) (xy 419.471868 -49.509179)
			(xy 419.416403 -49.445169) (xy 419.367274 -49.376177) (xy 419.324925 -49.302827) (xy 419.289741 -49.225784)
			(xy 419.262039 -49.145745) (xy 419.242071 -49.063436) (xy 419.230018 -48.979601) (xy 419.225988 -48.895)
			(xy 412.522592 -48.895) (xy 412.496 -48.896267) (xy 412.411375 -48.892235) (xy 412.327516 -48.880178)
			(xy 412.245183 -48.860204) (xy 412.165121 -48.832495) (xy 412.088056 -48.7973) (xy 412.014686 -48.75494)
			(xy 411.945674 -48.705797) (xy 411.881646 -48.650316) (xy 411.823181 -48.589001) (xy 411.77081 -48.522405)
			(xy 411.725007 -48.451133) (xy 411.686185 -48.37583) (xy 411.654697 -48.297178) (xy 411.630829 -48.215888)
			(xy 411.614795 -48.132698) (xy 411.606742 -48.048361) (xy 402.6154 -48.048361) (xy 402.6154 -53.890361)
			(xy 418.871142 -53.890361) (xy 418.871142 -53.805639) (xy 418.879195 -53.721302) (xy 418.895229 -53.638112)
			(xy 418.919097 -53.556822) (xy 418.950585 -53.47817) (xy 418.989407 -53.402867) (xy 419.03521 -53.331595)
			(xy 419.087581 -53.264999) (xy 419.146046 -53.203684) (xy 419.210074 -53.148203) (xy 419.279086 -53.09906)
			(xy 419.352456 -53.0567) (xy 419.429521 -53.021505) (xy 419.509583 -52.993796) (xy 419.591916 -52.973822)
			(xy 419.675775 -52.961765) (xy 419.7604 -52.957734) (xy 419.845025 -52.961765) (xy 419.928884 -52.973822)
			(xy 420.011217 -52.993796) (xy 420.091279 -53.021505) (xy 420.168344 -53.0567) (xy 420.241714 -53.09906)
			(xy 420.310726 -53.148203) (xy 420.374754 -53.203684) (xy 420.433219 -53.264999) (xy 420.48559 -53.331595)
			(xy 420.531393 -53.402867) (xy 420.570215 -53.47817) (xy 420.601703 -53.556822) (xy 420.625571 -53.638112)
			(xy 420.641605 -53.721302) (xy 420.649658 -53.805639) (xy 420.650162 -53.848) (xy 420.649658 -53.890361)
			(xy 420.641605 -53.974698) (xy 420.625571 -54.057888) (xy 420.601703 -54.139178) (xy 420.570215 -54.21783)
			(xy 420.531393 -54.293133) (xy 420.48559 -54.364405) (xy 420.433219 -54.431001) (xy 420.374754 -54.492316)
			(xy 420.310726 -54.547797) (xy 420.241714 -54.59694) (xy 420.168344 -54.6393) (xy 420.091279 -54.674495)
			(xy 420.011217 -54.702204) (xy 419.928884 -54.722178) (xy 419.845025 -54.734235) (xy 419.7604 -54.738267)
			(xy 419.675775 -54.734235) (xy 419.591916 -54.722178) (xy 419.509583 -54.702204) (xy 419.429521 -54.674495)
			(xy 419.352456 -54.6393) (xy 419.279086 -54.59694) (xy 419.210074 -54.547797) (xy 419.146046 -54.492316)
			(xy 419.087581 -54.431001) (xy 419.03521 -54.364405) (xy 418.989407 -54.293133) (xy 418.950585 -54.21783)
			(xy 418.919097 -54.139178) (xy 418.895229 -54.057888) (xy 418.879195 -53.974698) (xy 418.871142 -53.890361)
			(xy 402.6154 -53.890361) (xy 402.6154 -60.099956) (xy 419.2359 -60.099956) (xy 419.239883 -59.885707)
			(xy 419.251827 -59.671755) (xy 419.271716 -59.458394) (xy 419.299521 -59.24592) (xy 419.335205 -59.034627)
			(xy 419.378718 -58.824805) (xy 419.43 -58.616747) (xy 419.48898 -58.410738) (xy 419.555576 -58.207063)
			(xy 419.629697 -58.006005) (xy 419.711241 -57.807841) (xy 419.800093 -57.612845) (xy 419.896133 -57.421286)
			(xy 419.999226 -57.233429) (xy 420.109231 -57.049535) (xy 420.225995 -56.869856) (xy 420.349357 -56.694641)
			(xy 420.479146 -56.524133) (xy 420.615184 -56.358567) (xy 420.757281 -56.198172) (xy 420.905243 -56.043169)
			(xy 421.058863 -55.893774) (xy 421.217931 -55.750191) (xy 421.382225 -55.612621) (xy 421.55152 -55.481252)
			(xy 421.72558 -55.356267) (xy 421.904166 -55.237838) (xy 422.08703 -55.126129) (xy 422.273921 -55.021294)
			(xy 422.464578 -54.923479) (xy 422.65874 -54.832817) (xy 422.856138 -54.749436) (xy 423.056499 -54.673449)
			(xy 423.259545 -54.604962) (xy 423.464997 -54.54407) (xy 423.67257 -54.490856) (xy 423.881978 -54.445395)
			(xy 424.092931 -54.407749) (xy 424.305137 -54.37797) (xy 424.518304 -54.356099) (xy 424.732136 -54.342167)
			(xy 424.946338 -54.336193) (xy 425.160615 -54.338185) (xy 425.374669 -54.34814) (xy 425.588205 -54.366044)
			(xy 425.800928 -54.391873) (xy 426.012545 -54.425592) (xy 426.222761 -54.467153) (xy 426.431288 -54.516498)
			(xy 426.637836 -54.573561) (xy 426.84212 -54.638262) (xy 427.043859 -54.710511) (xy 427.242772 -54.790209)
			(xy 427.438586 -54.877246) (xy 427.631029 -54.9715) (xy 427.819836 -55.072843) (xy 428.004745 -55.181134)
			(xy 428.185501 -55.296223) (xy 428.361855 -55.417951) (xy 428.533562 -55.54615) (xy 428.700385 -55.680643)
			(xy 428.862094 -55.821243) (xy 429.018465 -55.967758) (xy 429.169282 -56.119983) (xy 429.314337 -56.277709)
			(xy 429.453429 -56.440718) (xy 429.586365 -56.608784) (xy 429.712963 -56.781675) (xy 429.833046 -56.959153)
			(xy 429.94645 -57.140971) (xy 430.053018 -57.326879) (xy 430.152601 -57.516619) (xy 430.245063 -57.70993)
			(xy 430.330276 -57.906544) (xy 430.408122 -58.10619) (xy 430.478493 -58.308591) (xy 430.541292 -58.513468)
			(xy 430.596432 -58.720538) (xy 430.643838 -58.929514) (xy 430.683443 -59.140108) (xy 430.715193 -59.352028)
			(xy 430.739044 -59.564982) (xy 430.754963 -59.778676) (xy 430.762928 -59.992813) (xy 430.763426 -60.099956)
			(xy 430.762928 -60.207099) (xy 430.754963 -60.421236) (xy 430.739044 -60.63493) (xy 430.715193 -60.847884)
			(xy 430.683443 -61.059804) (xy 430.678328 -61.087) (xy 441.222892 -61.087) (xy 441.222892 -61.086238)
			(xy 441.2233 -61.048018) (xy 441.229865 -60.971859) (xy 441.242949 -60.896547) (xy 441.262456 -60.822637)
			(xy 441.274962 -60.786518) (xy 441.277548 -60.778202) (xy 441.277548 -60.760798) (xy 441.274962 -60.752482)
			(xy 441.262442 -60.716268) (xy 441.24292 -60.642168) (xy 441.229835 -60.566664) (xy 441.223286 -60.490315)
			(xy 441.222892 -60.452) (xy 441.22326 -60.413684) (xy 441.229792 -60.33733) (xy 441.242877 -60.261823)
			(xy 441.262417 -60.187724) (xy 441.274962 -60.151518) (xy 441.277548 -60.143202) (xy 441.277548 -60.125798)
			(xy 441.274962 -60.117482) (xy 441.262442 -60.081268) (xy 441.24292 -60.007168) (xy 441.229835 -59.931664)
			(xy 441.223286 -59.855315) (xy 441.222892 -59.817) (xy 441.22326 -59.778684) (xy 441.229792 -59.70233)
			(xy 441.242877 -59.626823) (xy 441.262417 -59.552724) (xy 441.274962 -59.516518) (xy 441.277548 -59.508202)
			(xy 441.277548 -59.490798) (xy 441.274962 -59.482482) (xy 441.262471 -59.446359) (xy 441.242981 -59.372447)
			(xy 441.229897 -59.297136) (xy 441.223315 -59.220981) (xy 441.222892 -59.182762) (xy 441.222892 -59.182)
			(xy 441.223396 -59.139652) (xy 441.231447 -59.055338) (xy 441.247476 -58.972172) (xy 441.271337 -58.890905)
			(xy 441.302816 -58.812275) (xy 441.341627 -58.736994) (xy 441.387417 -58.665742) (xy 441.439773 -58.599166)
			(xy 441.498221 -58.537868) (xy 441.562231 -58.482403) (xy 441.631223 -58.433274) (xy 441.704573 -58.390925)
			(xy 441.781616 -58.355741) (xy 441.861655 -58.328039) (xy 441.943964 -58.308071) (xy 442.027799 -58.296018)
			(xy 442.1124 -58.291988) (xy 442.197001 -58.296018) (xy 442.280836 -58.308071) (xy 442.363145 -58.328039)
			(xy 442.443184 -58.355741) (xy 442.520227 -58.390925) (xy 442.593577 -58.433274) (xy 442.662569 -58.482403)
			(xy 442.726579 -58.537868) (xy 442.785027 -58.599166) (xy 442.837383 -58.665742) (xy 442.883173 -58.736994)
			(xy 442.921984 -58.812275) (xy 442.953463 -58.890905) (xy 442.977324 -58.972172) (xy 442.993353 -59.055338)
			(xy 443.001404 -59.139652) (xy 443.001908 -59.182) (xy 443.001908 -59.182762) (xy 443.0015 -59.220982)
			(xy 442.994935 -59.297141) (xy 442.981851 -59.372453) (xy 442.962344 -59.446363) (xy 442.949838 -59.482482)
			(xy 442.947252 -59.490798) (xy 442.947252 -59.508202) (xy 442.949838 -59.516518) (xy 442.962358 -59.552732)
			(xy 442.98188 -59.626832) (xy 442.994965 -59.702336) (xy 443.001514 -59.778685) (xy 443.001908 -59.817)
			(xy 443.00154 -59.855316) (xy 442.995008 -59.93167) (xy 442.981923 -60.007177) (xy 442.962383 -60.081276)
			(xy 442.949838 -60.117482) (xy 442.947252 -60.125798) (xy 442.947252 -60.143202) (xy 442.949838 -60.151518)
			(xy 442.962358 -60.187732) (xy 442.98188 -60.261832) (xy 442.994965 -60.337336) (xy 443.001514 -60.413685)
			(xy 443.001908 -60.452) (xy 443.00154 -60.490316) (xy 442.995008 -60.56667) (xy 442.981923 -60.642177)
			(xy 442.962383 -60.716276) (xy 442.949838 -60.752482) (xy 442.947252 -60.760798) (xy 442.947252 -60.778202)
			(xy 442.949838 -60.786518) (xy 442.962329 -60.822641) (xy 442.981819 -60.896553) (xy 442.994903 -60.971864)
			(xy 443.001485 -61.048019) (xy 443.001908 -61.086238) (xy 443.001908 -61.087) (xy 444.016892 -61.087)
			(xy 444.016892 -61.086238) (xy 444.0173 -61.048018) (xy 444.023865 -60.971859) (xy 444.036949 -60.896547)
			(xy 444.056456 -60.822637) (xy 444.068962 -60.786518) (xy 444.071548 -60.778202) (xy 444.071548 -60.760798)
			(xy 444.068962 -60.752482) (xy 444.056442 -60.716268) (xy 444.03692 -60.642168) (xy 444.023835 -60.566664)
			(xy 444.017286 -60.490315) (xy 444.016892 -60.452) (xy 444.01726 -60.413684) (xy 444.023792 -60.33733)
			(xy 444.036877 -60.261823) (xy 444.056417 -60.187724) (xy 444.068962 -60.151518) (xy 444.071548 -60.143202)
			(xy 444.071548 -60.125798) (xy 444.068962 -60.117482) (xy 444.056442 -60.081268) (xy 444.03692 -60.007168)
			(xy 444.023835 -59.931664) (xy 444.017286 -59.855315) (xy 444.016892 -59.817) (xy 444.01726 -59.778684)
			(xy 444.023792 -59.70233) (xy 444.036877 -59.626823) (xy 444.056417 -59.552724) (xy 444.068962 -59.516518)
			(xy 444.071548 -59.508202) (xy 444.071548 -59.490798) (xy 444.068962 -59.482482) (xy 444.056471 -59.446359)
			(xy 444.036981 -59.372447) (xy 444.023897 -59.297136) (xy 444.017315 -59.220981) (xy 444.016892 -59.182762)
			(xy 444.016892 -59.182) (xy 444.017396 -59.139652) (xy 444.025447 -59.055338) (xy 444.041476 -58.972172)
			(xy 444.065337 -58.890905) (xy 444.096816 -58.812275) (xy 444.135627 -58.736994) (xy 444.181417 -58.665742)
			(xy 444.233773 -58.599166) (xy 444.292221 -58.537868) (xy 444.356231 -58.482403) (xy 444.425223 -58.433274)
			(xy 444.498573 -58.390925) (xy 444.575616 -58.355741) (xy 444.655655 -58.328039) (xy 444.737964 -58.308071)
			(xy 444.821799 -58.296018) (xy 444.9064 -58.291988) (xy 444.991001 -58.296018) (xy 445.074836 -58.308071)
			(xy 445.157145 -58.328039) (xy 445.237184 -58.355741) (xy 445.314227 -58.390925) (xy 445.387577 -58.433274)
			(xy 445.456569 -58.482403) (xy 445.520579 -58.537868) (xy 445.579027 -58.599166) (xy 445.631383 -58.665742)
			(xy 445.677173 -58.736994) (xy 445.715984 -58.812275) (xy 445.747463 -58.890905) (xy 445.771324 -58.972172)
			(xy 445.787353 -59.055338) (xy 445.795404 -59.139652) (xy 445.795908 -59.182) (xy 445.795908 -59.182762)
			(xy 445.7955 -59.220982) (xy 445.788935 -59.297141) (xy 445.775851 -59.372453) (xy 445.756344 -59.446363)
			(xy 445.743838 -59.482482) (xy 445.741252 -59.490798) (xy 445.741252 -59.508202) (xy 445.743838 -59.516518)
			(xy 445.756358 -59.552732) (xy 445.77588 -59.626832) (xy 445.788965 -59.702336) (xy 445.795514 -59.778685)
			(xy 445.795908 -59.817) (xy 445.79554 -59.855316) (xy 445.789008 -59.93167) (xy 445.775923 -60.007177)
			(xy 445.756383 -60.081276) (xy 445.743838 -60.117482) (xy 445.741252 -60.125798) (xy 445.741252 -60.143202)
			(xy 445.743838 -60.151518) (xy 445.756358 -60.187732) (xy 445.77588 -60.261832) (xy 445.788965 -60.337336)
			(xy 445.795514 -60.413685) (xy 445.795908 -60.452) (xy 445.79554 -60.490316) (xy 445.789008 -60.56667)
			(xy 445.775923 -60.642177) (xy 445.756383 -60.716276) (xy 445.743838 -60.752482) (xy 445.741252 -60.760798)
			(xy 445.741252 -60.778202) (xy 445.743838 -60.786518) (xy 445.756329 -60.822641) (xy 445.775819 -60.896553)
			(xy 445.788903 -60.971864) (xy 445.795485 -61.048019) (xy 445.795908 -61.086238) (xy 445.795908 -61.087)
			(xy 445.795404 -61.129348) (xy 445.787353 -61.213662) (xy 445.771324 -61.296828) (xy 445.747463 -61.378095)
			(xy 445.715984 -61.456725) (xy 445.677173 -61.532006) (xy 445.631383 -61.603258) (xy 445.579027 -61.669834)
			(xy 445.520579 -61.731132) (xy 445.456569 -61.786597) (xy 445.387577 -61.835726) (xy 445.314227 -61.878075)
			(xy 445.237184 -61.913259) (xy 445.157145 -61.940961) (xy 445.074836 -61.960929) (xy 444.991001 -61.972982)
			(xy 444.9064 -61.977013) (xy 444.821799 -61.972982) (xy 444.737964 -61.960929) (xy 444.655655 -61.940961)
			(xy 444.575616 -61.913259) (xy 444.498573 -61.878075) (xy 444.425223 -61.835726) (xy 444.356231 -61.786597)
			(xy 444.292221 -61.731132) (xy 444.233773 -61.669834) (xy 444.181417 -61.603258) (xy 444.135627 -61.532006)
			(xy 444.096816 -61.456725) (xy 444.065337 -61.378095) (xy 444.041476 -61.296828) (xy 444.025447 -61.213662)
			(xy 444.017396 -61.129348) (xy 444.016892 -61.087) (xy 443.001908 -61.087) (xy 443.001404 -61.129348)
			(xy 442.993353 -61.213662) (xy 442.977324 -61.296828) (xy 442.953463 -61.378095) (xy 442.921984 -61.456725)
			(xy 442.883173 -61.532006) (xy 442.837383 -61.603258) (xy 442.785027 -61.669834) (xy 442.726579 -61.731132)
			(xy 442.662569 -61.786597) (xy 442.593577 -61.835726) (xy 442.520227 -61.878075) (xy 442.443184 -61.913259)
			(xy 442.363145 -61.940961) (xy 442.280836 -61.960929) (xy 442.197001 -61.972982) (xy 442.1124 -61.977013)
			(xy 442.027799 -61.972982) (xy 441.943964 -61.960929) (xy 441.861655 -61.940961) (xy 441.781616 -61.913259)
			(xy 441.704573 -61.878075) (xy 441.631223 -61.835726) (xy 441.562231 -61.786597) (xy 441.498221 -61.731132)
			(xy 441.439773 -61.669834) (xy 441.387417 -61.603258) (xy 441.341627 -61.532006) (xy 441.302816 -61.456725)
			(xy 441.271337 -61.378095) (xy 441.247476 -61.296828) (xy 441.231447 -61.213662) (xy 441.223396 -61.129348)
			(xy 441.222892 -61.087) (xy 430.678328 -61.087) (xy 430.643838 -61.270398) (xy 430.596432 -61.479374)
			(xy 430.541292 -61.686444) (xy 430.478493 -61.891321) (xy 430.408122 -62.093722) (xy 430.330276 -62.293368)
			(xy 430.245063 -62.489982) (xy 430.152601 -62.683293) (xy 430.053018 -62.873033) (xy 429.94645 -63.058941)
			(xy 429.833046 -63.240759) (xy 429.712963 -63.418237) (xy 429.586365 -63.591128) (xy 429.453429 -63.759194)
			(xy 429.314337 -63.922203) (xy 429.169282 -64.079929) (xy 429.018465 -64.232154) (xy 428.862094 -64.378669)
			(xy 428.700385 -64.519269) (xy 428.533562 -64.653762) (xy 428.361855 -64.781961) (xy 428.185501 -64.903689)
			(xy 428.004745 -65.018778) (xy 427.819836 -65.127069) (xy 427.631029 -65.228412) (xy 427.438586 -65.322666)
			(xy 427.242772 -65.409703) (xy 427.043859 -65.489401) (xy 426.924911 -65.532) (xy 441.222892 -65.532)
			(xy 441.222892 -65.531238) (xy 441.2233 -65.493018) (xy 441.229865 -65.416859) (xy 441.242949 -65.341547)
			(xy 441.262456 -65.267637) (xy 441.274962 -65.231518) (xy 441.277548 -65.223202) (xy 441.277548 -65.205798)
			(xy 441.274962 -65.197482) (xy 441.262442 -65.161268) (xy 441.24292 -65.087168) (xy 441.229835 -65.011664)
			(xy 441.223286 -64.935315) (xy 441.222892 -64.897) (xy 441.22326 -64.858684) (xy 441.229792 -64.78233)
			(xy 441.242877 -64.706823) (xy 441.262417 -64.632724) (xy 441.274962 -64.596518) (xy 441.277548 -64.588202)
			(xy 441.277548 -64.570798) (xy 441.274962 -64.562482) (xy 441.262442 -64.526268) (xy 441.24292 -64.452168)
			(xy 441.229835 -64.376664) (xy 441.223286 -64.300315) (xy 441.222892 -64.262) (xy 441.22326 -64.223684)
			(xy 441.229792 -64.14733) (xy 441.242877 -64.071823) (xy 441.262417 -63.997724) (xy 441.274962 -63.961518)
			(xy 441.277548 -63.953202) (xy 441.277548 -63.935798) (xy 441.274962 -63.927482) (xy 441.262442 -63.891268)
			(xy 441.24292 -63.817168) (xy 441.229835 -63.741664) (xy 441.223286 -63.665315) (xy 441.222892 -63.627)
			(xy 441.22326 -63.588684) (xy 441.229792 -63.51233) (xy 441.242877 -63.436823) (xy 441.262417 -63.362724)
			(xy 441.274962 -63.326518) (xy 441.277548 -63.318202) (xy 441.277548 -63.300798) (xy 441.274962 -63.292482)
			(xy 441.262471 -63.256359) (xy 441.242981 -63.182447) (xy 441.229897 -63.107136) (xy 441.223315 -63.030981)
			(xy 441.222892 -62.992762) (xy 441.222892 -62.992) (xy 441.223396 -62.949652) (xy 441.231447 -62.865338)
			(xy 441.247476 -62.782172) (xy 441.271337 -62.700905) (xy 441.302816 -62.622275) (xy 441.341627 -62.546994)
			(xy 441.387417 -62.475742) (xy 441.439773 -62.409166) (xy 441.498221 -62.347868) (xy 441.562231 -62.292403)
			(xy 441.631223 -62.243274) (xy 441.704573 -62.200925) (xy 441.781616 -62.165741) (xy 441.861655 -62.138039)
			(xy 441.943964 -62.118071) (xy 442.027799 -62.106018) (xy 442.1124 -62.101988) (xy 442.197001 -62.106018)
			(xy 442.280836 -62.118071) (xy 442.363145 -62.138039) (xy 442.443184 -62.165741) (xy 442.520227 -62.200925)
			(xy 442.593577 -62.243274) (xy 442.662569 -62.292403) (xy 442.726579 -62.347868) (xy 442.785027 -62.409166)
			(xy 442.837383 -62.475742) (xy 442.883173 -62.546994) (xy 442.921984 -62.622275) (xy 442.953463 -62.700905)
			(xy 442.977324 -62.782172) (xy 442.993353 -62.865338) (xy 443.001404 -62.949652) (xy 443.001908 -62.992)
			(xy 443.001908 -62.992762) (xy 443.0015 -63.030982) (xy 442.994935 -63.107141) (xy 442.981851 -63.182453)
			(xy 442.962344 -63.256363) (xy 442.949838 -63.292482) (xy 442.947252 -63.300798) (xy 442.947252 -63.318202)
			(xy 442.949838 -63.326518) (xy 442.962358 -63.362732) (xy 442.98188 -63.436832) (xy 442.994965 -63.512336)
			(xy 443.001514 -63.588685) (xy 443.001908 -63.627) (xy 443.00154 -63.665316) (xy 442.995008 -63.74167)
			(xy 442.981923 -63.817177) (xy 442.962383 -63.891276) (xy 442.949838 -63.927482) (xy 442.947252 -63.935798)
			(xy 442.947252 -63.953202) (xy 442.949838 -63.961518) (xy 442.962358 -63.997732) (xy 442.98188 -64.071832)
			(xy 442.994965 -64.147336) (xy 443.001514 -64.223685) (xy 443.001908 -64.262) (xy 443.00154 -64.300316)
			(xy 442.995008 -64.37667) (xy 442.981923 -64.452177) (xy 442.962383 -64.526276) (xy 442.949838 -64.562482)
			(xy 442.947252 -64.570798) (xy 442.947252 -64.588202) (xy 442.949838 -64.596518) (xy 442.962358 -64.632732)
			(xy 442.98188 -64.706832) (xy 442.994965 -64.782336) (xy 443.001514 -64.858685) (xy 443.001908 -64.897)
			(xy 443.00154 -64.935316) (xy 442.995008 -65.01167) (xy 442.981923 -65.087177) (xy 442.962383 -65.161276)
			(xy 442.949838 -65.197482) (xy 442.947252 -65.205798) (xy 442.947252 -65.223202) (xy 442.949838 -65.231518)
			(xy 442.962329 -65.267641) (xy 442.981819 -65.341553) (xy 442.994903 -65.416864) (xy 443.001485 -65.493019)
			(xy 443.001908 -65.531238) (xy 443.001908 -65.532) (xy 444.016892 -65.532) (xy 444.016892 -65.531238)
			(xy 444.0173 -65.493018) (xy 444.023865 -65.416859) (xy 444.036949 -65.341547) (xy 444.056456 -65.267637)
			(xy 444.068962 -65.231518) (xy 444.071548 -65.223202) (xy 444.071548 -65.205798) (xy 444.068962 -65.197482)
			(xy 444.056442 -65.161268) (xy 444.03692 -65.087168) (xy 444.023835 -65.011664) (xy 444.017286 -64.935315)
			(xy 444.016892 -64.897) (xy 444.01726 -64.858684) (xy 444.023792 -64.78233) (xy 444.036877 -64.706823)
			(xy 444.056417 -64.632724) (xy 444.068962 -64.596518) (xy 444.071548 -64.588202) (xy 444.071548 -64.570798)
			(xy 444.068962 -64.562482) (xy 444.056442 -64.526268) (xy 444.03692 -64.452168) (xy 444.023835 -64.376664)
			(xy 444.017286 -64.300315) (xy 444.016892 -64.262) (xy 444.01726 -64.223684) (xy 444.023792 -64.14733)
			(xy 444.036877 -64.071823) (xy 444.056417 -63.997724) (xy 444.068962 -63.961518) (xy 444.071548 -63.953202)
			(xy 444.071548 -63.935798) (xy 444.068962 -63.927482) (xy 444.056442 -63.891268) (xy 444.03692 -63.817168)
			(xy 444.023835 -63.741664) (xy 444.017286 -63.665315) (xy 444.016892 -63.627) (xy 444.01726 -63.588684)
			(xy 444.023792 -63.51233) (xy 444.036877 -63.436823) (xy 444.056417 -63.362724) (xy 444.068962 -63.326518)
			(xy 444.071548 -63.318202) (xy 444.071548 -63.300798) (xy 444.068962 -63.292482) (xy 444.056471 -63.256359)
			(xy 444.036981 -63.182447) (xy 444.023897 -63.107136) (xy 444.017315 -63.030981) (xy 444.016892 -62.992762)
			(xy 444.016892 -62.992) (xy 444.017396 -62.949652) (xy 444.025447 -62.865338) (xy 444.041476 -62.782172)
			(xy 444.065337 -62.700905) (xy 444.096816 -62.622275) (xy 444.135627 -62.546994) (xy 444.181417 -62.475742)
			(xy 444.233773 -62.409166) (xy 444.292221 -62.347868) (xy 444.356231 -62.292403) (xy 444.425223 -62.243274)
			(xy 444.498573 -62.200925) (xy 444.575616 -62.165741) (xy 444.655655 -62.138039) (xy 444.737964 -62.118071)
			(xy 444.821799 -62.106018) (xy 444.9064 -62.101988) (xy 444.991001 -62.106018) (xy 445.074836 -62.118071)
			(xy 445.157145 -62.138039) (xy 445.237184 -62.165741) (xy 445.314227 -62.200925) (xy 445.387577 -62.243274)
			(xy 445.456569 -62.292403) (xy 445.520579 -62.347868) (xy 445.579027 -62.409166) (xy 445.631383 -62.475742)
			(xy 445.677173 -62.546994) (xy 445.715984 -62.622275) (xy 445.747463 -62.700905) (xy 445.771324 -62.782172)
			(xy 445.787353 -62.865338) (xy 445.795404 -62.949652) (xy 445.795908 -62.992) (xy 445.795908 -62.992762)
			(xy 445.7955 -63.030982) (xy 445.788935 -63.107141) (xy 445.775851 -63.182453) (xy 445.756344 -63.256363)
			(xy 445.743838 -63.292482) (xy 445.741252 -63.300798) (xy 445.741252 -63.318202) (xy 445.743838 -63.326518)
			(xy 445.756358 -63.362732) (xy 445.77588 -63.436832) (xy 445.788965 -63.512336) (xy 445.794465 -63.576454)
			(xy 447.78422 -63.576454) (xy 447.78422 -63.575946) (xy 447.784843 -63.529615) (xy 447.794509 -63.437457)
			(xy 447.813699 -63.346803) (xy 447.842207 -63.258634) (xy 447.86042 -63.216028) (xy 447.864251 -63.206094)
			(xy 447.864234 -63.184823) (xy 447.86042 -63.17488) (xy 447.842217 -63.132269) (xy 447.813694 -63.044105)
			(xy 447.794496 -62.953452) (xy 447.784831 -62.861294) (xy 447.78422 -62.814962) (xy 447.78422 -62.814454)
			(xy 447.78468 -62.7727) (xy 447.792516 -62.689559) (xy 447.808106 -62.607519) (xy 447.831313 -62.527299)
			(xy 447.861931 -62.449606) (xy 447.899693 -62.375123) (xy 447.944266 -62.304504) (xy 447.969386 -62.271148)
			(xy 447.975731 -62.262005) (xy 447.980648 -62.240328) (xy 447.975925 -62.218609) (xy 447.96964 -62.209426)
			(xy 447.944951 -62.176255) (xy 447.90117 -62.106099) (xy 447.86409 -62.032182) (xy 447.834031 -61.955142)
			(xy 447.811252 -61.875645) (xy 447.79595 -61.794377) (xy 447.788256 -61.71204) (xy 447.787776 -61.670692)
			(xy 447.7884 -61.62429) (xy 447.798091 -61.531992) (xy 447.817345 -61.441207) (xy 447.845954 -61.352922)
			(xy 447.86423 -61.310266) (xy 447.868044 -61.300326) (xy 447.868041 -61.27906) (xy 447.86423 -61.269118)
			(xy 447.845965 -61.226458) (xy 447.817373 -61.13817) (xy 447.798116 -61.047387) (xy 447.788405 -60.955093)
			(xy 447.787776 -60.908692) (xy 447.78828 -60.866331) (xy 447.796333 -60.781994) (xy 447.812367 -60.698804)
			(xy 447.836235 -60.617514) (xy 447.867723 -60.538862) (xy 447.906545 -60.463559) (xy 447.952348 -60.392287)
			(xy 448.004719 -60.325691) (xy 448.063184 -60.264376) (xy 448.127212 -60.208895) (xy 448.196224 -60.159752)
			(xy 448.269594 -60.117392) (xy 448.346659 -60.082197) (xy 448.426721 -60.054488) (xy 448.509054 -60.034514)
			(xy 448.592913 -60.022457) (xy 448.677538 -60.018426) (xy 448.762163 -60.022457) (xy 448.846022 -60.034514)
			(xy 448.928355 -60.054488) (xy 449.008417 -60.082197) (xy 449.085482 -60.117392) (xy 449.158852 -60.159752)
			(xy 449.227864 -60.208895) (xy 449.291892 -60.264376) (xy 449.350357 -60.325691) (xy 449.402728 -60.392287)
			(xy 449.448531 -60.463559) (xy 449.487353 -60.538862) (xy 449.518841 -60.617514) (xy 449.542709 -60.698804)
			(xy 449.558743 -60.781994) (xy 449.566796 -60.866331) (xy 449.5673 -60.908692) (xy 449.566672 -60.955094)
			(xy 449.556983 -61.047391) (xy 449.53773 -61.138177) (xy 449.509122 -61.226462) (xy 449.490846 -61.269118)
			(xy 449.487043 -61.279061) (xy 449.48704 -61.300324) (xy 449.490846 -61.310266) (xy 449.509104 -61.352928)
			(xy 449.537699 -61.441216) (xy 449.556957 -61.531998) (xy 449.566671 -61.624291) (xy 449.5673 -61.670692)
			(xy 449.566799 -61.712452) (xy 449.558944 -61.795603) (xy 449.543329 -61.877651) (xy 449.520092 -61.957875)
			(xy 449.489438 -62.035567) (xy 449.451637 -62.110044) (xy 449.407022 -62.180651) (xy 449.38188 -62.213998)
			(xy 449.375496 -62.223118) (xy 449.370596 -62.244808) (xy 449.375334 -62.266535) (xy 449.381626 -62.27572)
			(xy 449.406266 -62.308918) (xy 449.449995 -62.379087) (xy 449.48703 -62.453009) (xy 449.517051 -62.530046)
			(xy 449.539799 -62.609535) (xy 449.55508 -62.690791) (xy 449.562759 -62.773114) (xy 449.563236 -62.814454)
			(xy 449.562635 -62.860849) (xy 449.552995 -62.953137) (xy 449.533804 -63.043921) (xy 449.505271 -63.132215)
			(xy 449.487036 -63.17488) (xy 449.483256 -63.18483) (xy 449.483239 -63.206087) (xy 449.487036 -63.216028)
			(xy 449.505245 -63.258636) (xy 449.533765 -63.346802) (xy 449.552962 -63.437456) (xy 449.562626 -63.529614)
			(xy 449.563236 -63.575946) (xy 449.563236 -63.576454) (xy 449.563067 -63.590678) (xy 450.07022 -63.590678)
			(xy 450.07022 -63.59017) (xy 450.070816 -63.543838) (xy 450.08049 -63.45168) (xy 450.099688 -63.361025)
			(xy 450.128203 -63.272857) (xy 450.14642 -63.230252) (xy 450.150237 -63.220313) (xy 450.150229 -63.199047)
			(xy 450.14642 -63.189104) (xy 450.12817 -63.146444) (xy 450.099627 -63.058151) (xy 450.080435 -62.967365)
			(xy 450.070804 -62.875074) (xy 450.07022 -62.828678) (xy 450.07071 -62.786326) (xy 450.078732 -62.702002)
			(xy 450.09474 -62.618824) (xy 450.118588 -62.537546) (xy 450.15006 -62.458905) (xy 450.18887 -62.383615)
			(xy 450.234667 -62.312359) (xy 450.260466 -62.278768) (xy 450.266974 -62.269555) (xy 450.271965 -62.24758)
			(xy 450.267127 -62.225571) (xy 450.26072 -62.216284) (xy 450.23535 -62.182857) (xy 450.190358 -62.112014)
			(xy 450.152236 -62.037249) (xy 450.121324 -61.959226) (xy 450.097897 -61.878639) (xy 450.082163 -61.796204)
			(xy 450.074261 -61.712654) (xy 450.073776 -61.670692) (xy 450.0744 -61.62429) (xy 450.084091 -61.531992)
			(xy 450.103345 -61.441207) (xy 450.131954 -61.352922) (xy 450.15023 -61.310266) (xy 450.154044 -61.300326)
			(xy 450.154041 -61.27906) (xy 450.15023 -61.269118) (xy 450.131965 -61.226458) (xy 450.103373 -61.13817)
			(xy 450.084116 -61.047387) (xy 450.074405 -60.955093) (xy 450.073776 -60.908692) (xy 450.07428 -60.866331)
			(xy 450.082333 -60.781994) (xy 450.098367 -60.698804) (xy 450.122235 -60.617514) (xy 450.153723 -60.538862)
			(xy 450.192545 -60.463559) (xy 450.238348 -60.392287) (xy 450.290719 -60.325691) (xy 450.349184 -60.264376)
			(xy 450.413212 -60.208895) (xy 450.482224 -60.159752) (xy 450.555594 -60.117392) (xy 450.632659 -60.082197)
			(xy 450.712721 -60.054488) (xy 450.795054 -60.034514) (xy 450.878913 -60.022457) (xy 450.963538 -60.018426)
			(xy 451.048163 -60.022457) (xy 451.132022 -60.034514) (xy 451.214355 -60.054488) (xy 451.294417 -60.082197)
			(xy 451.371482 -60.117392) (xy 451.444852 -60.159752) (xy 451.513864 -60.208895) (xy 451.577892 -60.264376)
			(xy 451.636357 -60.325691) (xy 451.688728 -60.392287) (xy 451.734531 -60.463559) (xy 451.773353 -60.538862)
			(xy 451.804841 -60.617514) (xy 451.828709 -60.698804) (xy 451.844743 -60.781994) (xy 451.852796 -60.866331)
			(xy 451.8533 -60.908692) (xy 451.852672 -60.955094) (xy 451.842983 -61.047391) (xy 451.82373 -61.138177)
			(xy 451.795122 -61.226462) (xy 451.776846 -61.269118) (xy 451.773043 -61.279061) (xy 451.77304 -61.300324)
			(xy 451.776846 -61.310266) (xy 451.795104 -61.352928) (xy 451.823699 -61.441216) (xy 451.842957 -61.531998)
			(xy 451.852671 -61.624291) (xy 451.8533 -61.670692) (xy 451.85276 -61.713048) (xy 451.844682 -61.797373)
			(xy 451.828627 -61.880549) (xy 451.80474 -61.961823) (xy 451.773237 -62.040459) (xy 451.734404 -62.115746)
			(xy 451.688592 -62.187001) (xy 451.6628 -62.220602) (xy 451.656312 -62.22983) (xy 451.651306 -62.251796)
			(xy 451.656139 -62.273802) (xy 451.662546 -62.283086) (xy 451.687884 -62.316528) (xy 451.73283 -62.387384)
			(xy 451.770908 -62.462155) (xy 451.801781 -62.540178) (xy 451.825174 -62.62076) (xy 451.84088 -62.703186)
			(xy 451.84876 -62.786724) (xy 451.849236 -62.828678) (xy 451.848643 -62.875073) (xy 451.839001 -62.967361)
			(xy 451.819807 -63.058145) (xy 451.791272 -63.146439) (xy 451.773036 -63.189104) (xy 451.769242 -63.19905)
			(xy 451.769234 -63.22031) (xy 451.773036 -63.230252) (xy 451.791253 -63.272857) (xy 451.819771 -63.361024)
			(xy 451.838965 -63.451679) (xy 451.848627 -63.543838) (xy 451.849236 -63.59017) (xy 451.849236 -63.590678)
			(xy 452.22922 -63.590678) (xy 452.229828 -63.544283) (xy 452.239465 -63.451995) (xy 452.258654 -63.361212)
			(xy 452.287185 -63.272917) (xy 452.30542 -63.230252) (xy 452.309237 -63.220313) (xy 452.309229 -63.199047)
			(xy 452.30542 -63.189104) (xy 452.28717 -63.146444) (xy 452.258627 -63.058151) (xy 452.239435 -62.967365)
			(xy 452.229804 -62.875074) (xy 452.22922 -62.828678) (xy 452.22971 -62.786326) (xy 452.237732 -62.702002)
			(xy 452.25374 -62.618824) (xy 452.277588 -62.537546) (xy 452.30906 -62.458905) (xy 452.34787 -62.383615)
			(xy 452.393667 -62.312359) (xy 452.419466 -62.278768) (xy 452.425974 -62.269555) (xy 452.430965 -62.24758)
			(xy 452.426127 -62.225571) (xy 452.41972 -62.216284) (xy 452.39435 -62.182857) (xy 452.349358 -62.112014)
			(xy 452.311236 -62.037249) (xy 452.280324 -61.959226) (xy 452.256897 -61.878639) (xy 452.241163 -61.796204)
			(xy 452.233261 -61.712654) (xy 452.232776 -61.670692) (xy 452.2334 -61.62429) (xy 452.243091 -61.531992)
			(xy 452.262345 -61.441207) (xy 452.290954 -61.352922) (xy 452.30923 -61.310266) (xy 452.313044 -61.300326)
			(xy 452.313041 -61.27906) (xy 452.30923 -61.269118) (xy 452.290965 -61.226458) (xy 452.262373 -61.13817)
			(xy 452.243116 -61.047387) (xy 452.233405 -60.955093) (xy 452.232776 -60.908692) (xy 452.23328 -60.866331)
			(xy 452.241333 -60.781994) (xy 452.257367 -60.698804) (xy 452.281235 -60.617514) (xy 452.312723 -60.538862)
			(xy 452.351545 -60.463559) (xy 452.397348 -60.392287) (xy 452.449719 -60.325691) (xy 452.508184 -60.264376)
			(xy 452.572212 -60.208895) (xy 452.641224 -60.159752) (xy 452.714594 -60.117392) (xy 452.791659 -60.082197)
			(xy 452.871721 -60.054488) (xy 452.954054 -60.034514) (xy 453.037913 -60.022457) (xy 453.122538 -60.018426)
			(xy 453.207163 -60.022457) (xy 453.291022 -60.034514) (xy 453.373355 -60.054488) (xy 453.453417 -60.082197)
			(xy 453.530482 -60.117392) (xy 453.603852 -60.159752) (xy 453.672864 -60.208895) (xy 453.736892 -60.264376)
			(xy 453.795357 -60.325691) (xy 453.847728 -60.392287) (xy 453.893531 -60.463559) (xy 453.932353 -60.538862)
			(xy 453.963841 -60.617514) (xy 453.987709 -60.698804) (xy 454.003743 -60.781994) (xy 454.011796 -60.866331)
			(xy 454.0123 -60.908692) (xy 454.010776 -60.958222) (xy 454.010695 -60.967088) (xy 454.015852 -60.98404)
			(xy 454.02645 -60.998239) (xy 454.033636 -61.003434) (xy 454.118726 -61.059314) (xy 454.145396 -61.060838)
			(xy 454.157842 -61.054488) (xy 454.195079 -61.036277) (xy 454.272274 -61.006058) (xy 454.351944 -60.983149)
			(xy 454.4334 -60.967749) (xy 454.515935 -60.959992) (xy 454.557384 -60.959492) (xy 454.5584 -60.959492)
			(xy 454.599502 -60.959967) (xy 454.681357 -60.967552) (xy 454.762162 -60.982657) (xy 454.841229 -61.005153)
			(xy 454.917883 -61.034849) (xy 454.99147 -61.071491) (xy 455.061362 -61.114766) (xy 455.126963 -61.164306)
			(xy 455.187713 -61.219687) (xy 455.243094 -61.280437) (xy 455.292634 -61.346038) (xy 455.335909 -61.41593)
			(xy 455.372551 -61.489517) (xy 455.402247 -61.566171) (xy 455.424743 -61.645238) (xy 455.439848 -61.726043)
			(xy 455.447433 -61.807898) (xy 455.447908 -61.849) (xy 455.447908 -61.849508) (xy 455.447389 -61.893272)
			(xy 455.438814 -61.980378) (xy 455.421718 -62.066219) (xy 455.396267 -62.149965) (xy 455.362707 -62.230803)
			(xy 455.342498 -62.269624) (xy 455.337171 -62.280977) (xy 455.337171 -62.306023) (xy 455.342498 -62.317376)
			(xy 455.362692 -62.356204) (xy 455.396232 -62.437047) (xy 455.421677 -62.520792) (xy 455.438782 -62.606629)
			(xy 455.447381 -62.69373) (xy 455.447908 -62.737492) (xy 455.447908 -62.738) (xy 455.447433 -62.779102)
			(xy 455.439848 -62.860957) (xy 455.424743 -62.941762) (xy 455.402247 -63.020829) (xy 455.372551 -63.097483)
			(xy 455.335909 -63.17107) (xy 455.292634 -63.240962) (xy 455.243094 -63.306563) (xy 455.187713 -63.367313)
			(xy 455.126963 -63.422694) (xy 455.061362 -63.472234) (xy 454.99147 -63.515509) (xy 454.917883 -63.552151)
			(xy 454.841229 -63.581847) (xy 454.762162 -63.604343) (xy 454.681357 -63.619448) (xy 454.599502 -63.627033)
			(xy 454.5584 -63.627508) (xy 454.557638 -63.627508) (xy 454.515903 -63.627003) (xy 454.432803 -63.619162)
			(xy 454.350805 -63.603562) (xy 454.27063 -63.580343) (xy 454.192986 -63.549708) (xy 454.155556 -63.531242)
			(xy 454.143872 -63.525146) (xy 454.117964 -63.526162) (xy 454.021444 -63.583058) (xy 454.008236 -63.60541)
			(xy 454.007982 -63.618618) (xy 454.006156 -63.661393) (xy 453.995269 -63.746321) (xy 453.976273 -63.82981)
			(xy 453.949343 -63.911087) (xy 453.914728 -63.989401) (xy 453.87275 -64.064028) (xy 453.823796 -64.134275)
			(xy 453.768319 -64.199495) (xy 453.706833 -64.259083) (xy 453.639906 -64.312488) (xy 453.568158 -64.359215)
			(xy 453.492253 -64.398833) (xy 453.412892 -64.430975) (xy 453.33081 -64.455344) (xy 453.246767 -64.471714)
			(xy 453.161539 -64.479933) (xy 453.118728 -64.48044) (xy 453.077619 -64.479921) (xy 452.995751 -64.472336)
			(xy 452.914932 -64.457228) (xy 452.835853 -64.434727) (xy 452.759188 -64.405023) (xy 452.685591 -64.368372)
			(xy 452.61569 -64.325084) (xy 452.550082 -64.275531) (xy 452.489328 -64.220135) (xy 452.433945 -64.159368)
			(xy 452.384406 -64.09375) (xy 452.341134 -64.02384) (xy 452.304498 -63.950235) (xy 452.274812 -63.873563)
			(xy 452.252327 -63.794479) (xy 452.237237 -63.713657) (xy 452.22967 -63.631787) (xy 452.22922 -63.590678)
			(xy 451.849236 -63.590678) (xy 451.848732 -63.633026) (xy 451.840681 -63.71734) (xy 451.824652 -63.800506)
			(xy 451.800791 -63.881773) (xy 451.769312 -63.960403) (xy 451.730501 -64.035684) (xy 451.684711 -64.106936)
			(xy 451.632355 -64.173512) (xy 451.573907 -64.23481) (xy 451.509897 -64.290275) (xy 451.440905 -64.339404)
			(xy 451.367555 -64.381753) (xy 451.290512 -64.416937) (xy 451.210473 -64.444639) (xy 451.128164 -64.464607)
			(xy 451.044329 -64.47666) (xy 450.959728 -64.480691) (xy 450.875127 -64.47666) (xy 450.791292 -64.464607)
			(xy 450.708983 -64.444639) (xy 450.628944 -64.416937) (xy 450.551901 -64.381753) (xy 450.478551 -64.339404)
			(xy 450.409559 -64.290275) (xy 450.345549 -64.23481) (xy 450.287101 -64.173512) (xy 450.234745 -64.106936)
			(xy 450.188955 -64.035684) (xy 450.150144 -63.960403) (xy 450.118665 -63.881773) (xy 450.094804 -63.800506)
			(xy 450.078775 -63.71734) (xy 450.070724 -63.633026) (xy 450.07022 -63.590678) (xy 449.563067 -63.590678)
			(xy 449.562732 -63.618802) (xy 449.554681 -63.703116) (xy 449.538652 -63.786282) (xy 449.514791 -63.867549)
			(xy 449.483312 -63.946179) (xy 449.444501 -64.02146) (xy 449.398711 -64.092712) (xy 449.346355 -64.159288)
			(xy 449.287907 -64.220586) (xy 449.223897 -64.276051) (xy 449.154905 -64.32518) (xy 449.081555 -64.367529)
			(xy 449.004512 -64.402713) (xy 448.924473 -64.430415) (xy 448.842164 -64.450383) (xy 448.758329 -64.462436)
			(xy 448.673728 -64.466467) (xy 448.589127 -64.462436) (xy 448.505292 -64.450383) (xy 448.422983 -64.430415)
			(xy 448.342944 -64.402713) (xy 448.265901 -64.367529) (xy 448.192551 -64.32518) (xy 448.123559 -64.276051)
			(xy 448.059549 -64.220586) (xy 448.001101 -64.159288) (xy 447.948745 -64.092712) (xy 447.902955 -64.02146)
			(xy 447.864144 -63.946179) (xy 447.832665 -63.867549) (xy 447.808804 -63.786282) (xy 447.792775 -63.703116)
			(xy 447.784724 -63.618802) (xy 447.78422 -63.576454) (xy 445.794465 -63.576454) (xy 445.795514 -63.588685)
			(xy 445.795908 -63.627) (xy 445.79554 -63.665316) (xy 445.789008 -63.74167) (xy 445.775923 -63.817177)
			(xy 445.756383 -63.891276) (xy 445.743838 -63.927482) (xy 445.741252 -63.935798) (xy 445.741252 -63.953202)
			(xy 445.743838 -63.961518) (xy 445.756358 -63.997732) (xy 445.77588 -64.071832) (xy 445.788965 -64.147336)
			(xy 445.795514 -64.223685) (xy 445.795908 -64.262) (xy 445.79554 -64.300316) (xy 445.789008 -64.37667)
			(xy 445.775923 -64.452177) (xy 445.756383 -64.526276) (xy 445.743838 -64.562482) (xy 445.741252 -64.570798)
			(xy 445.741252 -64.588202) (xy 445.743838 -64.596518) (xy 445.756358 -64.632732) (xy 445.77588 -64.706832)
			(xy 445.788965 -64.782336) (xy 445.795514 -64.858685) (xy 445.795908 -64.897) (xy 445.79554 -64.935316)
			(xy 445.789008 -65.01167) (xy 445.775923 -65.087177) (xy 445.756383 -65.161276) (xy 445.743838 -65.197482)
			(xy 445.741252 -65.205798) (xy 445.741252 -65.223202) (xy 445.743838 -65.231518) (xy 445.756329 -65.267641)
			(xy 445.775819 -65.341553) (xy 445.788903 -65.416864) (xy 445.795485 -65.493019) (xy 445.795908 -65.531238)
			(xy 445.795908 -65.532) (xy 445.795404 -65.574348) (xy 445.787353 -65.658662) (xy 445.771324 -65.741828)
			(xy 445.747463 -65.823095) (xy 445.715984 -65.901725) (xy 445.677173 -65.977006) (xy 445.631383 -66.048258)
			(xy 445.579027 -66.114834) (xy 445.520579 -66.176132) (xy 445.456569 -66.231597) (xy 445.387577 -66.280726)
			(xy 445.314227 -66.323075) (xy 445.237184 -66.358259) (xy 445.157145 -66.385961) (xy 445.074836 -66.405929)
			(xy 444.991001 -66.417982) (xy 444.9064 -66.422013) (xy 444.821799 -66.417982) (xy 444.737964 -66.405929)
			(xy 444.655655 -66.385961) (xy 444.575616 -66.358259) (xy 444.498573 -66.323075) (xy 444.425223 -66.280726)
			(xy 444.356231 -66.231597) (xy 444.292221 -66.176132) (xy 444.233773 -66.114834) (xy 444.181417 -66.048258)
			(xy 444.135627 -65.977006) (xy 444.096816 -65.901725) (xy 444.065337 -65.823095) (xy 444.041476 -65.741828)
			(xy 444.025447 -65.658662) (xy 444.017396 -65.574348) (xy 444.016892 -65.532) (xy 443.001908 -65.532)
			(xy 443.001404 -65.574348) (xy 442.993353 -65.658662) (xy 442.977324 -65.741828) (xy 442.953463 -65.823095)
			(xy 442.921984 -65.901725) (xy 442.883173 -65.977006) (xy 442.837383 -66.048258) (xy 442.785027 -66.114834)
			(xy 442.726579 -66.176132) (xy 442.662569 -66.231597) (xy 442.593577 -66.280726) (xy 442.520227 -66.323075)
			(xy 442.443184 -66.358259) (xy 442.363145 -66.385961) (xy 442.280836 -66.405929) (xy 442.197001 -66.417982)
			(xy 442.1124 -66.422013) (xy 442.027799 -66.417982) (xy 441.943964 -66.405929) (xy 441.861655 -66.385961)
			(xy 441.781616 -66.358259) (xy 441.704573 -66.323075) (xy 441.631223 -66.280726) (xy 441.562231 -66.231597)
			(xy 441.498221 -66.176132) (xy 441.439773 -66.114834) (xy 441.387417 -66.048258) (xy 441.341627 -65.977006)
			(xy 441.302816 -65.901725) (xy 441.271337 -65.823095) (xy 441.247476 -65.741828) (xy 441.231447 -65.658662)
			(xy 441.223396 -65.574348) (xy 441.222892 -65.532) (xy 426.924911 -65.532) (xy 426.84212 -65.56165)
			(xy 426.637836 -65.626351) (xy 426.431288 -65.683414) (xy 426.222761 -65.732759) (xy 426.012545 -65.77432)
			(xy 425.800928 -65.808039) (xy 425.588205 -65.833868) (xy 425.374669 -65.851772) (xy 425.160615 -65.861727)
			(xy 424.946338 -65.863719) (xy 424.732136 -65.857745) (xy 424.518304 -65.843813) (xy 424.305137 -65.821942)
			(xy 424.092931 -65.792163) (xy 423.881978 -65.754517) (xy 423.67257 -65.709056) (xy 423.464997 -65.655842)
			(xy 423.259545 -65.59495) (xy 423.056499 -65.526463) (xy 422.856138 -65.450476) (xy 422.65874 -65.367095)
			(xy 422.464578 -65.276433) (xy 422.273921 -65.178618) (xy 422.08703 -65.073783) (xy 421.904166 -64.962074)
			(xy 421.72558 -64.843645) (xy 421.55152 -64.71866) (xy 421.382225 -64.587291) (xy 421.217931 -64.449721)
			(xy 421.058863 -64.306138) (xy 420.905243 -64.156743) (xy 420.757281 -64.00174) (xy 420.615184 -63.841345)
			(xy 420.479146 -63.675779) (xy 420.349357 -63.505271) (xy 420.225995 -63.330056) (xy 420.109231 -63.150377)
			(xy 419.999226 -62.966483) (xy 419.896133 -62.778626) (xy 419.800093 -62.587067) (xy 419.711241 -62.392071)
			(xy 419.629697 -62.193907) (xy 419.555576 -61.992849) (xy 419.48898 -61.789174) (xy 419.43 -61.583165)
			(xy 419.378718 -61.375107) (xy 419.335205 -61.165285) (xy 419.299521 -60.953992) (xy 419.271716 -60.741518)
			(xy 419.251827 -60.528157) (xy 419.239883 -60.314205) (xy 419.2359 -60.099956) (xy 402.6154 -60.099956)
			(xy 402.6154 -73.809606) (xy 402.615858 -73.819484) (xy 402.623298 -73.837786) (xy 402.629878 -73.845166)
			(xy 402.630132 -73.84542) (xy 405.858726 -77.074014) (xy 405.859234 -77.074522) (xy 405.866613 -77.081111)
			(xy 405.884912 -77.088573) (xy 405.894794 -77.089)
		)
		(stroke
			(width 0)
			(type solid)
		)
		(fill yes)
		(layer "In5.Cu")
		(net "P52V_FAN")
	)
	(gr_arc
		(start 4.99999 0)
		(mid 1.464463 -1.464463)
		(end 0 -4.99999)
		(stroke
			(width 2.032)
			(type default)
		)
		(layer "In5.Cu")
	)
	(gr_line
		(start 4.99999 0)
		(end 434.999892 0)
		(stroke
			(width 2.032)
			(type default)
		)
		(layer "In5.Cu")
	)
	(gr_line
		(start 21.70557 -158.315406)
		(end 23.212552 -156.808424)
		(stroke
			(width 1.016)
			(type default)
		)
		(layer "In5.Cu")
	)
	(gr_line
		(start 23.212552 -158.299912)
		(end 23.212552 -44.961048)
		(stroke
			(width 1.016)
			(type default)
		)
		(layer "In5.Cu")
	)
	(gr_line
		(start 23.212552 -156.808424)
		(end 24.736552 -158.332424)
		(stroke
			(width 1.016)
			(type default)
		)
		(layer "In5.Cu")
	)
	(gr_line
		(start 23.212552 -44.961048)
		(end 34.6456 -33.528)
		(stroke
			(width 1.016)
			(type default)
		)
		(layer "In5.Cu")
	)
	(gr_line
		(start 25.999948 -158.299912)
		(end 4.99999 -158.299912)
		(stroke
			(width 2.032)
			(type default)
		)
		(layer "In5.Cu")
	)
	(gr_line
		(start 30.999938 -166.649908)
		(end 30.999938 -163.299902)
		(stroke
			(width 2.032)
			(type default)
		)
		(layer "In5.Cu")
	)
	(gr_arc
		(start 30.999938 -166.649908)
		(mid 32.4644 -170.185437)
		(end 35.999928 -171.649898)
		(stroke
			(width 2.032)
			(type default)
		)
		(layer "In5.Cu")
	)
	(gr_arc
		(start 30.999938 -163.299902)
		(mid 29.535475 -159.764375)
		(end 25.999948 -158.299912)
		(stroke
			(width 2.032)
			(type default)
		)
		(layer "In5.Cu")
	)
	(gr_circle
		(center 34.1884 -38.1)
		(end 35.0774 -38.1)
		(stroke
			(width 0.2)
			(type default)
		)
		(fill no)
		(layer "In5.Cu")
	)
	(gr_line
		(start 34.6456 -33.528)
		(end 73.5076 -33.528)
		(stroke
			(width 1.016)
			(type default)
		)
		(layer "In5.Cu")
	)
	(gr_circle
		(center 39.625016 -168.82999)
		(end 40.83812 -168.82999)
		(stroke
			(width 0.2)
			(type default)
		)
		(fill no)
		(layer "In5.Cu")
	)
	(gr_circle
		(center 39.625016 -166.829994)
		(end 40.83812 -166.829994)
		(stroke
			(width 0.2)
			(type default)
		)
		(fill no)
		(layer "In5.Cu")
	)
	(gr_circle
		(center 39.625016 -164.829998)
		(end 40.83812 -164.829998)
		(stroke
			(width 0.2)
			(type default)
		)
		(fill no)
		(layer "In5.Cu")
	)
	(gr_circle
		(center 39.625016 -162.830002)
		(end 40.83812 -162.830002)
		(stroke
			(width 0.2)
			(type default)
		)
		(fill no)
		(layer "In5.Cu")
	)
	(gr_circle
		(center 39.625016 -160.830006)
		(end 40.83812 -160.830006)
		(stroke
			(width 0.2)
			(type default)
		)
		(fill no)
		(layer "In5.Cu")
	)
	(gr_circle
		(center 39.625016 -158.83001)
		(end 40.83812 -158.83001)
		(stroke
			(width 0.2)
			(type default)
		)
		(fill no)
		(layer "In5.Cu")
	)
	(gr_circle
		(center 39.625016 -156.830014)
		(end 40.83812 -156.830014)
		(stroke
			(width 0.2)
			(type default)
		)
		(fill no)
		(layer "In5.Cu")
	)
	(gr_circle
		(center 39.625016 -154.830018)
		(end 40.83812 -154.830018)
		(stroke
			(width 0.2)
			(type default)
		)
		(fill no)
		(layer "In5.Cu")
	)
	(gr_circle
		(center 39.625016 -152.830022)
		(end 40.83812 -152.830022)
		(stroke
			(width 0.2)
			(type default)
		)
		(fill no)
		(layer "In5.Cu")
	)
	(gr_circle
		(center 40.609012 -167.845994)
		(end 41.822116 -167.845994)
		(stroke
			(width 0.2)
			(type default)
		)
		(fill no)
		(layer "In5.Cu")
	)
	(gr_circle
		(center 40.609012 -165.845998)
		(end 41.822116 -165.845998)
		(stroke
			(width 0.2)
			(type default)
		)
		(fill no)
		(layer "In5.Cu")
	)
	(gr_circle
		(center 40.609012 -163.846002)
		(end 41.822116 -163.846002)
		(stroke
			(width 0.2)
			(type default)
		)
		(fill no)
		(layer "In5.Cu")
	)
	(gr_circle
		(center 40.609012 -161.846006)
		(end 41.822116 -161.846006)
		(stroke
			(width 0.2)
			(type default)
		)
		(fill no)
		(layer "In5.Cu")
	)
	(gr_circle
		(center 40.609012 -159.84601)
		(end 41.822116 -159.84601)
		(stroke
			(width 0.2)
			(type default)
		)
		(fill no)
		(layer "In5.Cu")
	)
	(gr_circle
		(center 40.609012 -157.846014)
		(end 41.822116 -157.846014)
		(stroke
			(width 0.2)
			(type default)
		)
		(fill no)
		(layer "In5.Cu")
	)
	(gr_circle
		(center 40.609012 -155.846018)
		(end 41.822116 -155.846018)
		(stroke
			(width 0.2)
			(type default)
		)
		(fill no)
		(layer "In5.Cu")
	)
	(gr_circle
		(center 40.609012 -153.846022)
		(end 41.822116 -153.846022)
		(stroke
			(width 0.2)
			(type default)
		)
		(fill no)
		(layer "In5.Cu")
	)
	(gr_circle
		(center 41.625012 -168.82999)
		(end 42.838116 -168.82999)
		(stroke
			(width 0.2)
			(type default)
		)
		(fill no)
		(layer "In5.Cu")
	)
	(gr_circle
		(center 41.625012 -166.829994)
		(end 42.838116 -166.829994)
		(stroke
			(width 0.2)
			(type default)
		)
		(fill no)
		(layer "In5.Cu")
	)
	(gr_circle
		(center 41.625012 -164.829998)
		(end 42.838116 -164.829998)
		(stroke
			(width 0.2)
			(type default)
		)
		(fill no)
		(layer "In5.Cu")
	)
	(gr_circle
		(center 41.625012 -162.830002)
		(end 42.838116 -162.830002)
		(stroke
			(width 0.2)
			(type default)
		)
		(fill no)
		(layer "In5.Cu")
	)
	(gr_circle
		(center 41.625012 -160.830006)
		(end 42.838116 -160.830006)
		(stroke
			(width 0.2)
			(type default)
		)
		(fill no)
		(layer "In5.Cu")
	)
	(gr_circle
		(center 41.625012 -158.83001)
		(end 42.838116 -158.83001)
		(stroke
			(width 0.2)
			(type default)
		)
		(fill no)
		(layer "In5.Cu")
	)
	(gr_circle
		(center 41.625012 -156.830014)
		(end 42.838116 -156.830014)
		(stroke
			(width 0.2)
			(type default)
		)
		(fill no)
		(layer "In5.Cu")
	)
	(gr_circle
		(center 41.625012 -154.830018)
		(end 42.838116 -154.830018)
		(stroke
			(width 0.2)
			(type default)
		)
		(fill no)
		(layer "In5.Cu")
	)
	(gr_circle
		(center 41.625012 -152.830022)
		(end 42.838116 -152.830022)
		(stroke
			(width 0.2)
			(type default)
		)
		(fill no)
		(layer "In5.Cu")
	)
	(gr_circle
		(center 42.36339 -132.199888)
		(end 43.88739 -132.199888)
		(stroke
			(width 0.2)
			(type default)
		)
		(fill no)
		(layer "In5.Cu")
	)
	(gr_circle
		(center 42.36339 -111.879888)
		(end 43.88739 -111.879888)
		(stroke
			(width 0.2)
			(type default)
		)
		(fill no)
		(layer "In5.Cu")
	)
	(gr_circle
		(center 42.36339 -91.559888)
		(end 43.88739 -91.559888)
		(stroke
			(width 0.2)
			(type default)
		)
		(fill no)
		(layer "In5.Cu")
	)
	(gr_circle
		(center 42.36339 -71.239888)
		(end 43.88739 -71.239888)
		(stroke
			(width 0.2)
			(type default)
		)
		(fill no)
		(layer "In5.Cu")
	)
	(gr_circle
		(center 42.36339 -50.919888)
		(end 43.88739 -50.919888)
		(stroke
			(width 0.2)
			(type default)
		)
		(fill no)
		(layer "In5.Cu")
	)
	(gr_circle
		(center 48.800004 -168.82999)
		(end 50.013108 -168.82999)
		(stroke
			(width 0.2)
			(type default)
		)
		(fill no)
		(layer "In5.Cu")
	)
	(gr_circle
		(center 48.800004 -166.829994)
		(end 50.013108 -166.829994)
		(stroke
			(width 0.2)
			(type default)
		)
		(fill no)
		(layer "In5.Cu")
	)
	(gr_circle
		(center 48.800004 -164.829998)
		(end 50.013108 -164.829998)
		(stroke
			(width 0.2)
			(type default)
		)
		(fill no)
		(layer "In5.Cu")
	)
	(gr_circle
		(center 49.816004 -168.099994)
		(end 51.029108 -168.099994)
		(stroke
			(width 0.2)
			(type default)
		)
		(fill no)
		(layer "In5.Cu")
	)
	(gr_circle
		(center 49.816004 -166.099998)
		(end 51.029108 -166.099998)
		(stroke
			(width 0.2)
			(type default)
		)
		(fill no)
		(layer "In5.Cu")
	)
	(gr_circle
		(center 50.8 -168.82999)
		(end 52.013104 -168.82999)
		(stroke
			(width 0.2)
			(type default)
		)
		(fill no)
		(layer "In5.Cu")
	)
	(gr_circle
		(center 50.8 -166.829994)
		(end 52.013104 -166.829994)
		(stroke
			(width 0.2)
			(type default)
		)
		(fill no)
		(layer "In5.Cu")
	)
	(gr_circle
		(center 50.8 -164.829998)
		(end 52.013104 -164.829998)
		(stroke
			(width 0.2)
			(type default)
		)
		(fill no)
		(layer "In5.Cu")
	)
	(gr_circle
		(center 54.799992 -168.82999)
		(end 56.013096 -168.82999)
		(stroke
			(width 0.2)
			(type default)
		)
		(fill no)
		(layer "In5.Cu")
	)
	(gr_circle
		(center 54.799992 -166.829994)
		(end 56.013096 -166.829994)
		(stroke
			(width 0.2)
			(type default)
		)
		(fill no)
		(layer "In5.Cu")
	)
	(gr_circle
		(center 54.799992 -164.829998)
		(end 56.013096 -164.829998)
		(stroke
			(width 0.2)
			(type default)
		)
		(fill no)
		(layer "In5.Cu")
	)
	(gr_circle
		(center 55.658004 -167.718994)
		(end 56.871108 -167.718994)
		(stroke
			(width 0.2)
			(type default)
		)
		(fill no)
		(layer "In5.Cu")
	)
	(gr_circle
		(center 55.658004 -165.718998)
		(end 56.871108 -165.718998)
		(stroke
			(width 0.2)
			(type default)
		)
		(fill no)
		(layer "In5.Cu")
	)
	(gr_circle
		(center 56.799988 -168.82999)
		(end 58.013092 -168.82999)
		(stroke
			(width 0.2)
			(type default)
		)
		(fill no)
		(layer "In5.Cu")
	)
	(gr_circle
		(center 56.799988 -166.829994)
		(end 58.013092 -166.829994)
		(stroke
			(width 0.2)
			(type default)
		)
		(fill no)
		(layer "In5.Cu")
	)
	(gr_circle
		(center 56.799988 -164.829998)
		(end 58.013092 -164.829998)
		(stroke
			(width 0.2)
			(type default)
		)
		(fill no)
		(layer "In5.Cu")
	)
	(gr_line
		(start 57.893204 -33.528)
		(end 58.562494 -32.85871)
		(stroke
			(width 1.016)
			(type default)
		)
		(layer "In5.Cu")
	)
	(gr_line
		(start 58.562494 -32.85871)
		(end 58.562494 -0.292862)
		(stroke
			(width 1.524)
			(type default)
		)
		(layer "In5.Cu")
	)
	(gr_line
		(start 58.562494 -32.85871)
		(end 59.231784 -33.528)
		(stroke
			(width 1.016)
			(type default)
		)
		(layer "In5.Cu")
	)
	(gr_line
		(start 58.562494 -1.78435)
		(end 57.038494 -0.26035)
		(stroke
			(width 1.016)
			(type default)
		)
		(layer "In5.Cu")
	)
	(gr_line
		(start 60.069476 -0.277368)
		(end 58.562494 -1.78435)
		(stroke
			(width 1.016)
			(type default)
		)
		(layer "In5.Cu")
	)
	(gr_circle
		(center 61.92139 -132.199888)
		(end 63.44539 -132.199888)
		(stroke
			(width 0.2)
			(type default)
		)
		(fill no)
		(layer "In5.Cu")
	)
	(gr_circle
		(center 61.92139 -111.879888)
		(end 63.44539 -111.879888)
		(stroke
			(width 0.2)
			(type default)
		)
		(fill no)
		(layer "In5.Cu")
	)
	(gr_circle
		(center 61.92139 -91.559888)
		(end 63.44539 -91.559888)
		(stroke
			(width 0.2)
			(type default)
		)
		(fill no)
		(layer "In5.Cu")
	)
	(gr_circle
		(center 61.92139 -71.239888)
		(end 63.44539 -71.239888)
		(stroke
			(width 0.2)
			(type default)
		)
		(fill no)
		(layer "In5.Cu")
	)
	(gr_circle
		(center 61.92139 -50.919888)
		(end 63.44539 -50.919888)
		(stroke
			(width 0.2)
			(type default)
		)
		(fill no)
		(layer "In5.Cu")
	)
	(gr_circle
		(center 63.000128 -168.82999)
		(end 64.213232 -168.82999)
		(stroke
			(width 0.2)
			(type default)
		)
		(fill no)
		(layer "In5.Cu")
	)
	(gr_circle
		(center 63.000128 -166.829994)
		(end 64.213232 -166.829994)
		(stroke
			(width 0.2)
			(type default)
		)
		(fill no)
		(layer "In5.Cu")
	)
	(gr_circle
		(center 63.000128 -164.829998)
		(end 64.213232 -164.829998)
		(stroke
			(width 0.2)
			(type default)
		)
		(fill no)
		(layer "In5.Cu")
	)
	(gr_circle
		(center 63.719964 -5.290058)
		(end 64.933068 -5.290058)
		(stroke
			(width 0.2)
			(type default)
		)
		(fill no)
		(layer "In5.Cu")
	)
	(gr_circle
		(center 63.913004 -168.099994)
		(end 65.126108 -168.099994)
		(stroke
			(width 0.2)
			(type default)
		)
		(fill no)
		(layer "In5.Cu")
	)
	(gr_circle
		(center 63.913004 -166.099998)
		(end 65.126108 -166.099998)
		(stroke
			(width 0.2)
			(type default)
		)
		(fill no)
		(layer "In5.Cu")
	)
	(gr_circle
		(center 65.000124 -168.82999)
		(end 66.213228 -168.82999)
		(stroke
			(width 0.2)
			(type default)
		)
		(fill no)
		(layer "In5.Cu")
	)
	(gr_circle
		(center 65.000124 -166.829994)
		(end 66.213228 -166.829994)
		(stroke
			(width 0.2)
			(type default)
		)
		(fill no)
		(layer "In5.Cu")
	)
	(gr_circle
		(center 65.000124 -164.829998)
		(end 66.213228 -164.829998)
		(stroke
			(width 0.2)
			(type default)
		)
		(fill no)
		(layer "In5.Cu")
	)
	(gr_circle
		(center 66.259964 -5.290058)
		(end 67.473068 -5.290058)
		(stroke
			(width 0.2)
			(type default)
		)
		(fill no)
		(layer "In5.Cu")
	)
	(gr_circle
		(center 69.000116 -168.82999)
		(end 70.21322 -168.82999)
		(stroke
			(width 0.2)
			(type default)
		)
		(fill no)
		(layer "In5.Cu")
	)
	(gr_circle
		(center 69.000116 -166.829994)
		(end 70.21322 -166.829994)
		(stroke
			(width 0.2)
			(type default)
		)
		(fill no)
		(layer "In5.Cu")
	)
	(gr_circle
		(center 69.000116 -164.829998)
		(end 70.21322 -164.829998)
		(stroke
			(width 0.2)
			(type default)
		)
		(fill no)
		(layer "In5.Cu")
	)
	(gr_circle
		(center 69.760084 -4.575048)
		(end 70.973188 -4.575048)
		(stroke
			(width 0.2)
			(type default)
		)
		(fill no)
		(layer "In5.Cu")
	)
	(gr_circle
		(center 69.760084 -2.035048)
		(end 70.973188 -2.035048)
		(stroke
			(width 0.2)
			(type default)
		)
		(fill no)
		(layer "In5.Cu")
	)
	(gr_circle
		(center 69.882004 -167.972994)
		(end 71.095108 -167.972994)
		(stroke
			(width 0.2)
			(type default)
		)
		(fill no)
		(layer "In5.Cu")
	)
	(gr_circle
		(center 69.882004 -165.972998)
		(end 71.095108 -165.972998)
		(stroke
			(width 0.2)
			(type default)
		)
		(fill no)
		(layer "In5.Cu")
	)
	(gr_circle
		(center 71.000112 -168.82999)
		(end 72.213216 -168.82999)
		(stroke
			(width 0.2)
			(type default)
		)
		(fill no)
		(layer "In5.Cu")
	)
	(gr_circle
		(center 71.000112 -166.829994)
		(end 72.213216 -166.829994)
		(stroke
			(width 0.2)
			(type default)
		)
		(fill no)
		(layer "In5.Cu")
	)
	(gr_circle
		(center 71.000112 -164.829998)
		(end 72.213216 -164.829998)
		(stroke
			(width 0.2)
			(type default)
		)
		(fill no)
		(layer "In5.Cu")
	)
	(gr_circle
		(center 71.030084 -5.845048)
		(end 72.243188 -5.845048)
		(stroke
			(width 0.2)
			(type default)
		)
		(fill no)
		(layer "In5.Cu")
	)
	(gr_circle
		(center 71.030084 -4.448048)
		(end 72.243188 -4.448048)
		(stroke
			(width 0.2)
			(type default)
		)
		(fill no)
		(layer "In5.Cu")
	)
	(gr_circle
		(center 71.030084 -3.305048)
		(end 72.243188 -3.305048)
		(stroke
			(width 0.2)
			(type default)
		)
		(fill no)
		(layer "In5.Cu")
	)
	(gr_circle
		(center 71.030084 -1.527048)
		(end 72.243188 -1.527048)
		(stroke
			(width 0.2)
			(type default)
		)
		(fill no)
		(layer "In5.Cu")
	)
	(gr_circle
		(center 72.300084 -4.575048)
		(end 73.513188 -4.575048)
		(stroke
			(width 0.2)
			(type default)
		)
		(fill no)
		(layer "In5.Cu")
	)
	(gr_circle
		(center 72.300084 -3.432048)
		(end 73.513188 -3.432048)
		(stroke
			(width 0.2)
			(type default)
		)
		(fill no)
		(layer "In5.Cu")
	)
	(gr_circle
		(center 72.300084 -2.035048)
		(end 73.513188 -2.035048)
		(stroke
			(width 0.2)
			(type default)
		)
		(fill no)
		(layer "In5.Cu")
	)
	(gr_circle
		(center 73.062084 -1.781048)
		(end 74.275188 -1.781048)
		(stroke
			(width 0.2)
			(type default)
		)
		(fill no)
		(layer "In5.Cu")
	)
	(gr_line
		(start 73.5076 -33.528)
		(end 98.289618 -8.745982)
		(stroke
			(width 1.016)
			(type default)
		)
		(layer "In5.Cu")
	)
	(gr_circle
		(center 73.570084 -5.845048)
		(end 74.783188 -5.845048)
		(stroke
			(width 0.2)
			(type default)
		)
		(fill no)
		(layer "In5.Cu")
	)
	(gr_circle
		(center 73.570084 -3.305048)
		(end 74.783188 -3.305048)
		(stroke
			(width 0.2)
			(type default)
		)
		(fill no)
		(layer "In5.Cu")
	)
	(gr_circle
		(center 74.332084 -1.654048)
		(end 75.545188 -1.654048)
		(stroke
			(width 0.2)
			(type default)
		)
		(fill no)
		(layer "In5.Cu")
	)
	(gr_line
		(start 75.000104 -171.649898)
		(end 35.999928 -171.649898)
		(stroke
			(width 2.032)
			(type default)
		)
		(layer "In5.Cu")
	)
	(gr_arc
		(start 75.000104 -171.649898)
		(mid 78.535631 -170.185434)
		(end 80.000094 -166.649908)
		(stroke
			(width 2.032)
			(type default)
		)
		(layer "In5.Cu")
	)
	(gr_circle
		(center 75.000104 -168.82999)
		(end 76.213208 -168.82999)
		(stroke
			(width 0.2)
			(type default)
		)
		(fill no)
		(layer "In5.Cu")
	)
	(gr_circle
		(center 75.000104 -166.829994)
		(end 76.213208 -166.829994)
		(stroke
			(width 0.2)
			(type default)
		)
		(fill no)
		(layer "In5.Cu")
	)
	(gr_circle
		(center 75.000104 -164.829998)
		(end 76.213208 -164.829998)
		(stroke
			(width 0.2)
			(type default)
		)
		(fill no)
		(layer "In5.Cu")
	)
	(gr_circle
		(center 75.851004 -167.718994)
		(end 77.064108 -167.718994)
		(stroke
			(width 0.2)
			(type default)
		)
		(fill no)
		(layer "In5.Cu")
	)
	(gr_circle
		(center 75.851004 -165.718998)
		(end 77.064108 -165.718998)
		(stroke
			(width 0.2)
			(type default)
		)
		(fill no)
		(layer "In5.Cu")
	)
	(gr_circle
		(center 77.0001 -168.82999)
		(end 78.213204 -168.82999)
		(stroke
			(width 0.2)
			(type default)
		)
		(fill no)
		(layer "In5.Cu")
	)
	(gr_circle
		(center 77.0001 -166.829994)
		(end 78.213204 -166.829994)
		(stroke
			(width 0.2)
			(type default)
		)
		(fill no)
		(layer "In5.Cu")
	)
	(gr_circle
		(center 77.0001 -164.829998)
		(end 78.213204 -164.829998)
		(stroke
			(width 0.2)
			(type default)
		)
		(fill no)
		(layer "In5.Cu")
	)
	(gr_circle
		(center 79.950564 -9.959594)
		(end 80.839564 -9.959594)
		(stroke
			(width 0.2)
			(type default)
		)
		(fill no)
		(layer "In5.Cu")
	)
	(gr_line
		(start 80.000094 -161.299906)
		(end 80.000094 -166.649908)
		(stroke
			(width 2.032)
			(type default)
		)
		(layer "In5.Cu")
	)
	(gr_circle
		(center 80.518 -18.91665)
		(end 81.407 -18.91665)
		(stroke
			(width 0.2)
			(type default)
		)
		(fill no)
		(layer "In5.Cu")
	)
	(gr_circle
		(center 80.518 -16.383)
		(end 81.407 -16.383)
		(stroke
			(width 0.2)
			(type default)
		)
		(fill no)
		(layer "In5.Cu")
	)
	(gr_circle
		(center 80.518 -14.732)
		(end 81.407 -14.732)
		(stroke
			(width 0.2)
			(type default)
		)
		(fill no)
		(layer "In5.Cu")
	)
	(gr_circle
		(center 80.712564 -9.959594)
		(end 81.601564 -9.959594)
		(stroke
			(width 0.2)
			(type default)
		)
		(fill no)
		(layer "In5.Cu")
	)
	(gr_circle
		(center 81.474564 -9.959594)
		(end 82.363564 -9.959594)
		(stroke
			(width 0.2)
			(type default)
		)
		(fill no)
		(layer "In5.Cu")
	)
	(gr_circle
		(center 81.534 -16.002)
		(end 82.423 -16.002)
		(stroke
			(width 0.2)
			(type default)
		)
		(fill no)
		(layer "In5.Cu")
	)
	(gr_circle
		(center 81.661 -18.91665)
		(end 82.55 -18.91665)
		(stroke
			(width 0.2)
			(type default)
		)
		(fill no)
		(layer "In5.Cu")
	)
	(gr_circle
		(center 81.661 -16.891)
		(end 82.55 -16.891)
		(stroke
			(width 0.2)
			(type default)
		)
		(fill no)
		(layer "In5.Cu")
	)
	(gr_circle
		(center 82.236564 -9.959594)
		(end 83.125564 -9.959594)
		(stroke
			(width 0.2)
			(type default)
		)
		(fill no)
		(layer "In5.Cu")
	)
	(gr_circle
		(center 82.296 -19.558)
		(end 83.185 -19.558)
		(stroke
			(width 0.2)
			(type default)
		)
		(fill no)
		(layer "In5.Cu")
	)
	(gr_circle
		(center 82.5754 -16.256)
		(end 83.4644 -16.256)
		(stroke
			(width 0.2)
			(type default)
		)
		(fill no)
		(layer "In5.Cu")
	)
	(gr_circle
		(center 82.804 -18.916904)
		(end 83.693 -18.916904)
		(stroke
			(width 0.2)
			(type default)
		)
		(fill no)
		(layer "In5.Cu")
	)
	(gr_arc
		(start 83.000088 -158.299912)
		(mid 80.878772 -159.17859)
		(end 80.000094 -161.299906)
		(stroke
			(width 2.032)
			(type default)
		)
		(layer "In5.Cu")
	)
	(gr_line
		(start 83.49996 -158.299912)
		(end 83.000088 -158.299912)
		(stroke
			(width 2.032)
			(type default)
		)
		(layer "In5.Cu")
	)
	(gr_arc
		(start 83.49996 -158.299912)
		(mid 87.035488 -156.835449)
		(end 88.49995 -153.299922)
		(stroke
			(width 2.032)
			(type default)
		)
		(layer "In5.Cu")
	)
	(gr_circle
		(center 83.947 -18.916904)
		(end 84.836 -18.916904)
		(stroke
			(width 0.2)
			(type default)
		)
		(fill no)
		(layer "In5.Cu")
	)
	(gr_circle
		(center 84.455 -16.0782)
		(end 85.344 -16.0782)
		(stroke
			(width 0.2)
			(type default)
		)
		(fill no)
		(layer "In5.Cu")
	)
	(gr_line
		(start 88.49995 -110.499906)
		(end 88.49995 -153.299922)
		(stroke
			(width 2.032)
			(type default)
		)
		(layer "In5.Cu")
	)
	(gr_circle
		(center 93.774768 -9.757918)
		(end 94.663768 -9.757918)
		(stroke
			(width 0.2)
			(type default)
		)
		(fill no)
		(layer "In5.Cu")
	)
	(gr_circle
		(center 94.536768 -9.757918)
		(end 95.425768 -9.757918)
		(stroke
			(width 0.2)
			(type default)
		)
		(fill no)
		(layer "In5.Cu")
	)
	(gr_circle
		(center 95.298768 -9.757918)
		(end 96.187768 -9.757918)
		(stroke
			(width 0.2)
			(type default)
		)
		(fill no)
		(layer "In5.Cu")
	)
	(gr_arc
		(start 96.000062 -103.000048)
		(mid 90.696772 -105.19669)
		(end 88.49995 -110.499906)
		(stroke
			(width 2.032)
			(type default)
		)
		(layer "In5.Cu")
	)
	(gr_line
		(start 96.000062 -103.000048)
		(end 114.705384 -103.000048)
		(stroke
			(width 2.032)
			(type default)
		)
		(layer "In5.Cu")
	)
	(gr_circle
		(center 96.060768 -9.757918)
		(end 96.949768 -9.757918)
		(stroke
			(width 0.2)
			(type default)
		)
		(fill no)
		(layer "In5.Cu")
	)
	(gr_line
		(start 98.289618 -8.745982)
		(end 122.8344 -8.745982)
		(stroke
			(width 1.016)
			(type default)
		)
		(layer "In5.Cu")
	)
	(gr_line
		(start 111.168434 -79.861918)
		(end 113.856516 -82.55)
		(stroke
			(width 1.016)
			(type default)
		)
		(layer "In5.Cu")
	)
	(gr_line
		(start 111.168434 -75.179174)
		(end 111.168434 -79.861918)
		(stroke
			(width 1.016)
			(type default)
		)
		(layer "In5.Cu")
	)
	(gr_circle
		(center 111.2774 -54.483)
		(end 112.1664 -54.483)
		(stroke
			(width 0.2)
			(type default)
		)
		(fill no)
		(layer "In5.Cu")
	)
	(gr_circle
		(center 111.2774 -43.18)
		(end 112.1664 -43.18)
		(stroke
			(width 0.2)
			(type default)
		)
		(fill no)
		(layer "In5.Cu")
	)
	(gr_line
		(start 111.408972 -67.38874)
		(end 112.208818 -68.188586)
		(stroke
			(width 1.016)
			(type default)
		)
		(layer "In5.Cu")
	)
	(gr_line
		(start 111.408972 -64.34963)
		(end 111.408972 -67.38874)
		(stroke
			(width 1.016)
			(type default)
		)
		(layer "In5.Cu")
	)
	(gr_line
		(start 111.409226 -56.57596)
		(end 111.985044 -57.151778)
		(stroke
			(width 1.016)
			(type default)
		)
		(layer "In5.Cu")
	)
	(gr_line
		(start 111.409226 -55.736744)
		(end 111.409226 -56.57596)
		(stroke
			(width 1.016)
			(type default)
		)
		(layer "In5.Cu")
	)
	(gr_line
		(start 111.46028 -34.594038)
		(end 111.46028 -30.659324)
		(stroke
			(width 1.016)
			(type default)
		)
		(layer "In5.Cu")
	)
	(gr_line
		(start 111.46028 -30.659324)
		(end 112.132364 -29.98724)
		(stroke
			(width 1.016)
			(type default)
		)
		(layer "In5.Cu")
	)
	(gr_line
		(start 111.492284 -45.310806)
		(end 111.492284 -44.15917)
		(stroke
			(width 1.016)
			(type default)
		)
		(layer "In5.Cu")
	)
	(gr_line
		(start 111.492284 -44.15917)
		(end 112.164114 -43.48734)
		(stroke
			(width 1.016)
			(type default)
		)
		(layer "In5.Cu")
	)
	(gr_line
		(start 111.524542 -23.460964)
		(end 111.524542 -19.302476)
		(stroke
			(width 1.016)
			(type default)
		)
		(layer "In5.Cu")
	)
	(gr_line
		(start 111.524542 -19.302476)
		(end 112.100614 -18.726404)
		(stroke
			(width 1.016)
			(type default)
		)
		(layer "In5.Cu")
	)
	(gr_line
		(start 111.697008 -74.6506)
		(end 111.168434 -75.179174)
		(stroke
			(width 1.016)
			(type default)
		)
		(layer "In5.Cu")
	)
	(gr_line
		(start 111.985044 -57.151778)
		(end 118.15953 -57.151778)
		(stroke
			(width 1.016)
			(type default)
		)
		(layer "In5.Cu")
	)
	(gr_line
		(start 112.028478 -45.847)
		(end 111.492284 -45.310806)
		(stroke
			(width 1.016)
			(type default)
		)
		(layer "In5.Cu")
	)
	(gr_line
		(start 112.036606 -23.973028)
		(end 111.524542 -23.460964)
		(stroke
			(width 1.016)
			(type default)
		)
		(layer "In5.Cu")
	)
	(gr_line
		(start 112.048798 -63.709804)
		(end 111.408972 -64.34963)
		(stroke
			(width 1.016)
			(type default)
		)
		(layer "In5.Cu")
	)
	(gr_line
		(start 112.097566 -55.048404)
		(end 111.409226 -55.736744)
		(stroke
			(width 1.016)
			(type default)
		)
		(layer "In5.Cu")
	)
	(gr_line
		(start 112.100614 -18.726404)
		(end 122.8344 -18.726404)
		(stroke
			(width 1.016)
			(type default)
		)
		(layer "In5.Cu")
	)
	(gr_line
		(start 112.131856 -35.265614)
		(end 111.46028 -34.594038)
		(stroke
			(width 1.016)
			(type default)
		)
		(layer "In5.Cu")
	)
	(gr_line
		(start 112.132364 -29.98724)
		(end 118.914672 -29.98724)
		(stroke
			(width 1.016)
			(type default)
		)
		(layer "In5.Cu")
	)
	(gr_line
		(start 112.164114 -43.48734)
		(end 118.146322 -43.48734)
		(stroke
			(width 1.016)
			(type default)
		)
		(layer "In5.Cu")
	)
	(gr_line
		(start 112.208818 -68.188586)
		(end 117.966998 -68.188586)
		(stroke
			(width 1.016)
			(type default)
		)
		(layer "In5.Cu")
	)
	(gr_line
		(start 113.856516 -82.55)
		(end 122.8344 -82.55)
		(stroke
			(width 1.016)
			(type default)
		)
		(layer "In5.Cu")
	)
	(gr_line
		(start 114.705384 -103.000048)
		(end 114.832384 -103.000048)
		(stroke
			(width 2.032)
			(type default)
		)
		(layer "In5.Cu")
	)
	(gr_line
		(start 114.705384 -103.000048)
		(end 179.735226 -103.000048)
		(stroke
			(width 2.032)
			(type default)
		)
		(layer "In5.Cu")
	)
	(gr_line
		(start 114.705384 -99.314)
		(end 114.705384 -103.000048)
		(stroke
			(width 1.016)
			(type default)
		)
		(layer "In5.Cu")
	)
	(gr_line
		(start 114.705384 -90.531442)
		(end 114.705384 -99.314)
		(stroke
			(width 1.016)
			(type default)
		)
		(layer "In5.Cu")
	)
	(gr_line
		(start 114.705384 -90.531442)
		(end 114.705384 -83.398868)
		(stroke
			(width 1.016)
			(type default)
		)
		(layer "In5.Cu")
	)
	(gr_line
		(start 114.705384 -83.398868)
		(end 113.856516 -82.55)
		(stroke
			(width 1.016)
			(type default)
		)
		(layer "In5.Cu")
	)
	(gr_line
		(start 117.966998 -68.188586)
		(end 119.2149 -69.436488)
		(stroke
			(width 1.016)
			(type default)
		)
		(layer "In5.Cu")
	)
	(gr_line
		(start 118.031514 -63.709804)
		(end 112.048798 -63.709804)
		(stroke
			(width 1.016)
			(type default)
		)
		(layer "In5.Cu")
	)
	(gr_line
		(start 118.146322 -43.48734)
		(end 119.521986 -42.111676)
		(stroke
			(width 1.016)
			(type default)
		)
		(layer "In5.Cu")
	)
	(gr_line
		(start 118.15953 -57.151778)
		(end 119.119142 -58.11139)
		(stroke
			(width 1.016)
			(type default)
		)
		(layer "In5.Cu")
	)
	(gr_line
		(start 118.22303 -74.6506)
		(end 111.697008 -74.6506)
		(stroke
			(width 1.016)
			(type default)
		)
		(layer "In5.Cu")
	)
	(gr_line
		(start 118.786656 -23.973028)
		(end 112.036606 -23.973028)
		(stroke
			(width 1.016)
			(type default)
		)
		(layer "In5.Cu")
	)
	(gr_line
		(start 118.818152 -35.265614)
		(end 112.131856 -35.265614)
		(stroke
			(width 1.016)
			(type default)
		)
		(layer "In5.Cu")
	)
	(gr_line
		(start 118.914672 -29.98724)
		(end 119.394478 -29.507434)
		(stroke
			(width 1.016)
			(type default)
		)
		(layer "In5.Cu")
	)
	(gr_line
		(start 119.119142 -62.622176)
		(end 118.031514 -63.709804)
		(stroke
			(width 1.016)
			(type default)
		)
		(layer "In5.Cu")
	)
	(gr_line
		(start 119.119142 -58.11139)
		(end 119.119142 -62.622176)
		(stroke
			(width 1.016)
			(type default)
		)
		(layer "In5.Cu")
	)
	(gr_line
		(start 119.2149 -73.65873)
		(end 118.22303 -74.6506)
		(stroke
			(width 1.016)
			(type default)
		)
		(layer "In5.Cu")
	)
	(gr_line
		(start 119.2149 -69.436488)
		(end 119.2149 -73.65873)
		(stroke
			(width 1.016)
			(type default)
		)
		(layer "In5.Cu")
	)
	(gr_line
		(start 119.394478 -29.507434)
		(end 119.394478 -24.58085)
		(stroke
			(width 1.016)
			(type default)
		)
		(layer "In5.Cu")
	)
	(gr_line
		(start 119.394478 -24.58085)
		(end 118.786656 -23.973028)
		(stroke
			(width 1.016)
			(type default)
		)
		(layer "In5.Cu")
	)
	(gr_line
		(start 119.521986 -42.111676)
		(end 119.521986 -35.969448)
		(stroke
			(width 1.016)
			(type default)
		)
		(layer "In5.Cu")
	)
	(gr_line
		(start 119.521986 -35.969448)
		(end 118.818152 -35.265614)
		(stroke
			(width 1.016)
			(type default)
		)
		(layer "In5.Cu")
	)
	(gr_line
		(start 122.8344 -82.55)
		(end 122.8344 -55.048404)
		(stroke
			(width 1.016)
			(type default)
		)
		(layer "In5.Cu")
	)
	(gr_line
		(start 122.8344 -79.883)
		(end 123.4694 -80.518)
		(stroke
			(width 1.016)
			(type default)
		)
		(layer "In5.Cu")
	)
	(gr_line
		(start 122.8344 -55.048404)
		(end 112.097566 -55.048404)
		(stroke
			(width 1.016)
			(type default)
		)
		(layer "In5.Cu")
	)
	(gr_line
		(start 122.8344 -52.345082)
		(end 122.8344 -55.048404)
		(stroke
			(width 1.016)
			(type default)
		)
		(layer "In5.Cu")
	)
	(gr_line
		(start 122.8344 -46.863)
		(end 122.8344 -52.345082)
		(stroke
			(width 1.016)
			(type default)
		)
		(layer "In5.Cu")
	)
	(gr_line
		(start 122.8344 -45.847)
		(end 112.028478 -45.847)
		(stroke
			(width 1.016)
			(type default)
		)
		(layer "In5.Cu")
	)
	(gr_line
		(start 122.8344 -18.726404)
		(end 122.8344 -46.863)
		(stroke
			(width 1.016)
			(type default)
		)
		(layer "In5.Cu")
	)
	(gr_line
		(start 122.8344 -13.081)
		(end 122.8344 -18.726404)
		(stroke
			(width 1.016)
			(type default)
		)
		(layer "In5.Cu")
	)
	(gr_line
		(start 122.8344 -13.081)
		(end 123.4694 -12.446)
		(stroke
			(width 1.016)
			(type default)
		)
		(layer "In5.Cu")
	)
	(gr_line
		(start 122.8344 -8.745982)
		(end 122.8344 -13.081)
		(stroke
			(width 1.016)
			(type default)
		)
		(layer "In5.Cu")
	)
	(gr_line
		(start 122.8344 -8.745982)
		(end 182.918862 -8.745982)
		(stroke
			(width 1.016)
			(type default)
		)
		(layer "In5.Cu")
	)
	(gr_line
		(start 123.3424 -46.355)
		(end 122.8344 -46.863)
		(stroke
			(width 1.016)
			(type default)
		)
		(layer "In5.Cu")
	)
	(gr_line
		(start 123.3424 -46.355)
		(end 122.8344 -45.847)
		(stroke
			(width 1.016)
			(type default)
		)
		(layer "In5.Cu")
	)
	(gr_line
		(start 123.4694 -80.518)
		(end 136.23925 -80.518)
		(stroke
			(width 1.016)
			(type default)
		)
		(layer "In5.Cu")
	)
	(gr_line
		(start 136.23925 -80.518)
		(end 136.86663 -79.89062)
		(stroke
			(width 1.016)
			(type default)
		)
		(layer "In5.Cu")
	)
	(gr_line
		(start 136.86663 -68.303902)
		(end 136.86663 -79.89062)
		(stroke
			(width 1.016)
			(type default)
		)
		(layer "In5.Cu")
	)
	(gr_line
		(start 136.86663 -68.303902)
		(end 137.855706 -67.314826)
		(stroke
			(width 1.016)
			(type default)
		)
		(layer "In5.Cu")
	)
	(gr_line
		(start 137.855706 -67.314826)
		(end 149.521926 -67.314826)
		(stroke
			(width 1.016)
			(type default)
		)
		(layer "In5.Cu")
	)
	(gr_line
		(start 138.049 -38.862)
		(end 139.1666 -39.9796)
		(stroke
			(width 1.016)
			(type default)
		)
		(layer "In5.Cu")
	)
	(gr_line
		(start 138.049 -33.8328)
		(end 138.049 -38.862)
		(stroke
			(width 1.016)
			(type default)
		)
		(layer "In5.Cu")
	)
	(gr_line
		(start 138.2268 -38.2524)
		(end 147.066 -38.2524)
		(stroke
			(width 1.016)
			(type default)
		)
		(layer "In5.Cu")
	)
	(gr_line
		(start 138.2268 -37.6682)
		(end 147.066 -37.6682)
		(stroke
			(width 1.016)
			(type default)
		)
		(layer "In5.Cu")
	)
	(gr_line
		(start 138.2522 -37.0586)
		(end 147.0914 -37.0586)
		(stroke
			(width 1.016)
			(type default)
		)
		(layer "In5.Cu")
	)
	(gr_line
		(start 138.2522 -34.8742)
		(end 147.0914 -34.8742)
		(stroke
			(width 1.016)
			(type default)
		)
		(layer "In5.Cu")
	)
	(gr_line
		(start 138.2776 -36.3474)
		(end 147.1168 -36.3474)
		(stroke
			(width 1.016)
			(type default)
		)
		(layer "In5.Cu")
	)
	(gr_line
		(start 138.303 -35.6616)
		(end 147.1422 -35.6616)
		(stroke
			(width 1.016)
			(type default)
		)
		(layer "In5.Cu")
	)
	(gr_line
		(start 138.34872 -33.53308)
		(end 138.049 -33.8328)
		(stroke
			(width 1.016)
			(type default)
		)
		(layer "In5.Cu")
	)
	(gr_line
		(start 138.3538 -34.2392)
		(end 147.193 -34.2392)
		(stroke
			(width 1.016)
			(type default)
		)
		(layer "In5.Cu")
	)
	(gr_line
		(start 138.3792 -38.7604)
		(end 147.2184 -38.7604)
		(stroke
			(width 1.016)
			(type default)
		)
		(layer "In5.Cu")
	)
	(gr_line
		(start 138.6078 -34.2646)
		(end 138.6078 -39.2938)
		(stroke
			(width 1.016)
			(type default)
		)
		(layer "In5.Cu")
	)
	(gr_line
		(start 139.0904 -34.5694)
		(end 139.0904 -39.5986)
		(stroke
			(width 1.016)
			(type default)
		)
		(layer "In5.Cu")
	)
	(gr_line
		(start 139.1666 -39.9796)
		(end 141.7066 -39.9796)
		(stroke
			(width 1.016)
			(type default)
		)
		(layer "In5.Cu")
	)
	(gr_line
		(start 141.7066 -39.9796)
		(end 142.6464 -40.9194)
		(stroke
			(width 1.016)
			(type default)
		)
		(layer "In5.Cu")
	)
	(gr_line
		(start 141.8844 -12.446)
		(end 142.6464 -13.208)
		(stroke
			(width 1.016)
			(type default)
		)
		(layer "In5.Cu")
	)
	(gr_line
		(start 142.3924 -46.355)
		(end 123.3424 -46.355)
		(stroke
			(width 1.016)
			(type default)
		)
		(layer "In5.Cu")
	)
	(gr_line
		(start 142.3924 -46.355)
		(end 142.6464 -46.609)
		(stroke
			(width 1.016)
			(type default)
		)
		(layer "In5.Cu")
	)
	(gr_line
		(start 142.621 -32.6644)
		(end 141.5034 -33.782)
		(stroke
			(width 1.016)
			(type default)
		)
		(layer "In5.Cu")
	)
	(gr_line
		(start 142.621 -32.6644)
		(end 143.7386 -33.782)
		(stroke
			(width 1.016)
			(type default)
		)
		(layer "In5.Cu")
	)
	(gr_line
		(start 142.6464 -47.498)
		(end 141.5288 -46.3804)
		(stroke
			(width 1.016)
			(type default)
		)
		(layer "In5.Cu")
	)
	(gr_line
		(start 142.6464 -45.1612)
		(end 141.5288 -46.2788)
		(stroke
			(width 1.016)
			(type default)
		)
		(layer "In5.Cu")
	)
	(gr_line
		(start 142.6464 -33.909)
		(end 142.6464 -67.437)
		(stroke
			(width 1.016)
			(type default)
		)
		(layer "In5.Cu")
	)
	(gr_line
		(start 142.6464 -33.53308)
		(end 138.34872 -33.53308)
		(stroke
			(width 1.016)
			(type default)
		)
		(layer "In5.Cu")
	)
	(gr_line
		(start 142.6464 -33.53308)
		(end 147.35048 -33.53308)
		(stroke
			(width 1.016)
			(type default)
		)
		(layer "In5.Cu")
	)
	(gr_line
		(start 142.6464 -13.208)
		(end 142.6464 -33.53308)
		(stroke
			(width 1.016)
			(type default)
		)
		(layer "In5.Cu")
	)
	(gr_line
		(start 143.4084 -12.446)
		(end 142.6464 -13.208)
		(stroke
			(width 1.016)
			(type default)
		)
		(layer "In5.Cu")
	)
	(gr_circle
		(center 143.533114 -76.858368)
		(end 144.422114 -76.858368)
		(stroke
			(width 0.2)
			(type default)
		)
		(fill no)
		(layer "In5.Cu")
	)
	(gr_line
		(start 143.5862 -39.9796)
		(end 142.6464 -40.9194)
		(stroke
			(width 1.016)
			(type default)
		)
		(layer "In5.Cu")
	)
	(gr_line
		(start 144.4244 -39.3192)
		(end 139.3952 -39.3192)
		(stroke
			(width 1.016)
			(type default)
		)
		(layer "In5.Cu")
	)
	(gr_circle
		(center 144.892522 -76.886308)
		(end 145.781522 -76.886308)
		(stroke
			(width 0.2)
			(type default)
		)
		(fill no)
		(layer "In5.Cu")
	)
	(gr_circle
		(center 145.11655 -74.360278)
		(end 146.00555 -74.360278)
		(stroke
			(width 0.2)
			(type default)
		)
		(fill no)
		(layer "In5.Cu")
	)
	(gr_circle
		(center 145.171668 -73.42251)
		(end 146.060668 -73.42251)
		(stroke
			(width 0.2)
			(type default)
		)
		(fill no)
		(layer "In5.Cu")
	)
	(gr_line
		(start 145.5928 -39.8272)
		(end 140.5636 -39.8272)
		(stroke
			(width 1.016)
			(type default)
		)
		(layer "In5.Cu")
	)
	(gr_line
		(start 146.05 -34.544)
		(end 146.05 -39.5732)
		(stroke
			(width 1.016)
			(type default)
		)
		(layer "In5.Cu")
	)
	(gr_line
		(start 146.2024 -39.4208)
		(end 141.1732 -39.4208)
		(stroke
			(width 1.016)
			(type default)
		)
		(layer "In5.Cu")
	)
	(gr_line
		(start 146.2532 -39.9796)
		(end 143.5862 -39.9796)
		(stroke
			(width 1.016)
			(type default)
		)
		(layer "In5.Cu")
	)
	(gr_line
		(start 146.6596 -34.1884)
		(end 146.6596 -39.2176)
		(stroke
			(width 1.016)
			(type default)
		)
		(layer "In5.Cu")
	)
	(gr_line
		(start 147.2692 -33.8582)
		(end 147.2692 -38.8874)
		(stroke
			(width 1.016)
			(type default)
		)
		(layer "In5.Cu")
	)
	(gr_line
		(start 147.35048 -33.53308)
		(end 147.8534 -34.036)
		(stroke
			(width 1.016)
			(type default)
		)
		(layer "In5.Cu")
	)
	(gr_line
		(start 147.8534 -38.3794)
		(end 146.2532 -39.9796)
		(stroke
			(width 1.016)
			(type default)
		)
		(layer "In5.Cu")
	)
	(gr_line
		(start 147.8534 -34.036)
		(end 147.8534 -38.3794)
		(stroke
			(width 1.016)
			(type default)
		)
		(layer "In5.Cu")
	)
	(gr_line
		(start 149.123908 -80.209136)
		(end 149.65172 -80.736948)
		(stroke
			(width 1.016)
			(type default)
		)
		(layer "In5.Cu")
	)
	(gr_line
		(start 149.123908 -75.67549)
		(end 149.123908 -80.209136)
		(stroke
			(width 1.016)
			(type default)
		)
		(layer "In5.Cu")
	)
	(gr_line
		(start 149.521926 -67.314826)
		(end 150.718012 -68.510912)
		(stroke
			(width 1.016)
			(type default)
		)
		(layer "In5.Cu")
	)
	(gr_line
		(start 149.65172 -80.736948)
		(end 151.50719 -80.736948)
		(stroke
			(width 1.016)
			(type default)
		)
		(layer "In5.Cu")
	)
	(gr_circle
		(center 149.935692 -71.85406)
		(end 150.824692 -71.85406)
		(stroke
			(width 0.2)
			(type default)
		)
		(fill no)
		(layer "In5.Cu")
	)
	(gr_circle
		(center 149.935692 -70.353936)
		(end 150.824692 -70.353936)
		(stroke
			(width 0.2)
			(type default)
		)
		(fill no)
		(layer "In5.Cu")
	)
	(gr_line
		(start 150.718012 -74.081386)
		(end 149.123908 -75.67549)
		(stroke
			(width 1.016)
			(type default)
		)
		(layer "In5.Cu")
	)
	(gr_line
		(start 150.718012 -68.510912)
		(end 150.718012 -74.081386)
		(stroke
			(width 1.016)
			(type default)
		)
		(layer "In5.Cu")
	)
	(gr_circle
		(center 150.801832 -60.917582)
		(end 151.690832 -60.917582)
		(stroke
			(width 0.2)
			(type default)
		)
		(fill no)
		(layer "In5.Cu")
	)
	(gr_line
		(start 151.50719 -80.736948)
		(end 152.588722 -79.655416)
		(stroke
			(width 1.016)
			(type default)
		)
		(layer "In5.Cu")
	)
	(gr_circle
		(center 151.563832 -60.917582)
		(end 152.452832 -60.917582)
		(stroke
			(width 0.2)
			(type default)
		)
		(fill no)
		(layer "In5.Cu")
	)
	(gr_line
		(start 152.588722 -79.655416)
		(end 152.588722 -63.40221)
		(stroke
			(width 1.016)
			(type default)
		)
		(layer "In5.Cu")
	)
	(gr_line
		(start 152.588722 -63.40221)
		(end 160.620964 -55.369968)
		(stroke
			(width 1.016)
			(type default)
		)
		(layer "In5.Cu")
	)
	(gr_line
		(start 156.980382 -12.446)
		(end 123.4694 -12.446)
		(stroke
			(width 1.016)
			(type default)
		)
		(layer "In5.Cu")
	)
	(gr_circle
		(center 158.369 -96.266)
		(end 159.258 -96.266)
		(stroke
			(width 0.2)
			(type default)
		)
		(fill no)
		(layer "In5.Cu")
	)
	(gr_circle
		(center 160.575244 -86.084918)
		(end 161.464244 -86.084918)
		(stroke
			(width 0.2)
			(type default)
		)
		(fill no)
		(layer "In5.Cu")
	)
	(gr_line
		(start 160.620964 -55.369968)
		(end 175.611282 -55.369968)
		(stroke
			(width 1.016)
			(type default)
		)
		(layer "In5.Cu")
	)
	(gr_line
		(start 160.6804 -27.182318)
		(end 161.946082 -28.448)
		(stroke
			(width 1.016)
			(type default)
		)
		(layer "In5.Cu")
	)
	(gr_line
		(start 160.6804 -16.146018)
		(end 156.980382 -12.446)
		(stroke
			(width 1.016)
			(type default)
		)
		(layer "In5.Cu")
	)
	(gr_line
		(start 160.6804 -16.146018)
		(end 160.6804 -27.182318)
		(stroke
			(width 1.016)
			(type default)
		)
		(layer "In5.Cu")
	)
	(gr_line
		(start 161.946082 -28.448)
		(end 209.1944 -28.448)
		(stroke
			(width 1.016)
			(type default)
		)
		(layer "In5.Cu")
	)
	(gr_circle
		(center 166.5224 -60.3758)
		(end 167.4114 -60.3758)
		(stroke
			(width 0.2)
			(type default)
		)
		(fill no)
		(layer "In5.Cu")
	)
	(gr_circle
		(center 167.2844 -60.3758)
		(end 168.1734 -60.3758)
		(stroke
			(width 0.2)
			(type default)
		)
		(fill no)
		(layer "In5.Cu")
	)
	(gr_line
		(start 172.174662 -50.696622)
		(end 172.174662 -43.570398)
		(stroke
			(width 1.016)
			(type default)
		)
		(layer "In5.Cu")
	)
	(gr_line
		(start 172.174662 -43.570398)
		(end 173.915832 -41.829228)
		(stroke
			(width 1.016)
			(type default)
		)
		(layer "In5.Cu")
	)
	(gr_line
		(start 172.583348 -51.105308)
		(end 172.174662 -50.696622)
		(stroke
			(width 1.016)
			(type default)
		)
		(layer "In5.Cu")
	)
	(gr_line
		(start 173.915832 -41.829228)
		(end 191.747394 -41.829228)
		(stroke
			(width 1.016)
			(type default)
		)
		(layer "In5.Cu")
	)
	(gr_line
		(start 173.980348 -51.105308)
		(end 172.583348 -51.105308)
		(stroke
			(width 1.016)
			(type default)
		)
		(layer "In5.Cu")
	)
	(gr_line
		(start 175.611282 -55.369968)
		(end 176.302162 -54.679088)
		(stroke
			(width 1.016)
			(type default)
		)
		(layer "In5.Cu")
	)
	(gr_circle
		(center 176.251616 -82.304128)
		(end 177.140616 -82.304128)
		(stroke
			(width 0.2)
			(type default)
		)
		(fill no)
		(layer "In5.Cu")
	)
	(gr_line
		(start 176.302162 -54.679088)
		(end 176.302162 -53.427122)
		(stroke
			(width 1.016)
			(type default)
		)
		(layer "In5.Cu")
	)
	(gr_line
		(start 176.302162 -53.427122)
		(end 173.980348 -51.105308)
		(stroke
			(width 1.016)
			(type default)
		)
		(layer "In5.Cu")
	)
	(gr_circle
		(center 176.939702 -82.304128)
		(end 177.828702 -82.304128)
		(stroke
			(width 0.2)
			(type default)
		)
		(fill no)
		(layer "In5.Cu")
	)
	(gr_circle
		(center 178.87696 -46.99)
		(end 179.76596 -46.99)
		(stroke
			(width 0.2)
			(type default)
		)
		(fill no)
		(layer "In5.Cu")
	)
	(gr_line
		(start 179.735226 -103.000048)
		(end 264.668 -103.000048)
		(stroke
			(width 2.032)
			(type default)
		)
		(layer "In5.Cu")
	)
	(gr_line
		(start 182.1434 -50.894996)
		(end 182.1434 -50.419)
		(stroke
			(width 1.016)
			(type default)
		)
		(layer "In5.Cu")
	)
	(gr_line
		(start 182.1434 -50.419)
		(end 182.1434 -47.879)
		(stroke
			(width 1.016)
			(type default)
		)
		(layer "In5.Cu")
	)
	(gr_line
		(start 182.1434 -47.879)
		(end 182.1434 -46.609)
		(stroke
			(width 1.016)
			(type default)
		)
		(layer "In5.Cu")
	)
	(gr_line
		(start 182.1434 -46.609)
		(end 185.8264 -42.926)
		(stroke
			(width 1.016)
			(type default)
		)
		(layer "In5.Cu")
	)
	(gr_circle
		(center 182.215536 -69.4436)
		(end 183.104536 -69.4436)
		(stroke
			(width 0.2)
			(type default)
		)
		(fill no)
		(layer "In5.Cu")
	)
	(gr_line
		(start 182.815484 -51.56708)
		(end 182.1434 -50.894996)
		(stroke
			(width 1.016)
			(type default)
		)
		(layer "In5.Cu")
	)
	(gr_line
		(start 182.918862 -8.745982)
		(end 255.633982 -8.745982)
		(stroke
			(width 1.016)
			(type default)
		)
		(layer "In5.Cu")
	)
	(gr_circle
		(center 184.8104 -68.58)
		(end 185.6994 -68.58)
		(stroke
			(width 0.2)
			(type default)
		)
		(fill no)
		(layer "In5.Cu")
	)
	(gr_circle
		(center 185.5724 -68.58)
		(end 186.4614 -68.58)
		(stroke
			(width 0.2)
			(type default)
		)
		(fill no)
		(layer "In5.Cu")
	)
	(gr_line
		(start 185.8264 -42.926)
		(end 189.847982 -42.926)
		(stroke
			(width 1.016)
			(type default)
		)
		(layer "In5.Cu")
	)
	(gr_line
		(start 189.847982 -42.926)
		(end 193.576448 -46.654466)
		(stroke
			(width 1.016)
			(type default)
		)
		(layer "In5.Cu")
	)
	(gr_line
		(start 191.747394 -41.829228)
		(end 197.797166 -47.879)
		(stroke
			(width 1.016)
			(type default)
		)
		(layer "In5.Cu")
	)
	(gr_line
		(start 193.031618 -51.56708)
		(end 182.815484 -51.56708)
		(stroke
			(width 1.016)
			(type default)
		)
		(layer "In5.Cu")
	)
	(gr_line
		(start 193.576448 -51.02225)
		(end 193.031618 -51.56708)
		(stroke
			(width 1.016)
			(type default)
		)
		(layer "In5.Cu")
	)
	(gr_line
		(start 193.576448 -47.879)
		(end 193.576448 -51.02225)
		(stroke
			(width 1.016)
			(type default)
		)
		(layer "In5.Cu")
	)
	(gr_line
		(start 193.576448 -46.654466)
		(end 193.576448 -47.879)
		(stroke
			(width 1.016)
			(type default)
		)
		(layer "In5.Cu")
	)
	(gr_line
		(start 197.797166 -47.879)
		(end 210.0834 -47.879)
		(stroke
			(width 1.016)
			(type default)
		)
		(layer "In5.Cu")
	)
	(gr_circle
		(center 208.810098 -51.049936)
		(end 210.20913 -51.049936)
		(stroke
			(width 0.2)
			(type default)
		)
		(fill no)
		(layer "In5.Cu")
	)
	(gr_line
		(start 209.1944 -28.448)
		(end 210.9724 -30.226)
		(stroke
			(width 1.016)
			(type default)
		)
		(layer "In5.Cu")
	)
	(gr_line
		(start 210.9724 -46.99)
		(end 210.0834 -47.879)
		(stroke
			(width 1.016)
			(type default)
		)
		(layer "In5.Cu")
	)
	(gr_line
		(start 210.9724 -30.226)
		(end 210.9724 -46.99)
		(stroke
			(width 1.016)
			(type default)
		)
		(layer "In5.Cu")
	)
	(gr_circle
		(center 219.1004 -7.493)
		(end 219.9894 -7.493)
		(stroke
			(width 0.2)
			(type default)
		)
		(fill no)
		(layer "In5.Cu")
	)
	(gr_circle
		(center 220.2434 -8.001)
		(end 221.1324 -8.001)
		(stroke
			(width 0.2)
			(type default)
		)
		(fill no)
		(layer "In5.Cu")
	)
	(gr_circle
		(center 220.2434 -7.112)
		(end 221.1324 -7.112)
		(stroke
			(width 0.2)
			(type default)
		)
		(fill no)
		(layer "In5.Cu")
	)
	(gr_circle
		(center 220.734382 -7.983728)
		(end 221.623382 -7.983728)
		(stroke
			(width 0.2)
			(type default)
		)
		(fill no)
		(layer "In5.Cu")
	)
	(gr_circle
		(center 221.623382 -7.475728)
		(end 222.512382 -7.475728)
		(stroke
			(width 0.2)
			(type default)
		)
		(fill no)
		(layer "In5.Cu")
	)
	(gr_line
		(start 229.362 -46.99)
		(end 230.251 -47.879)
		(stroke
			(width 1.016)
			(type default)
		)
		(layer "In5.Cu")
	)
	(gr_line
		(start 229.362 -30.226)
		(end 229.362 -46.99)
		(stroke
			(width 1.016)
			(type default)
		)
		(layer "In5.Cu")
	)
	(gr_line
		(start 230.251 -47.879)
		(end 242.963954 -47.879)
		(stroke
			(width 1.016)
			(type default)
		)
		(layer "In5.Cu")
	)
	(gr_line
		(start 231.14 -28.448)
		(end 229.362 -30.226)
		(stroke
			(width 1.016)
			(type default)
		)
		(layer "In5.Cu")
	)
	(gr_circle
		(center 238.810038 -51.049936)
		(end 240.20907 -51.049936)
		(stroke
			(width 0.2)
			(type default)
		)
		(fill no)
		(layer "In5.Cu")
	)
	(gr_line
		(start 242.963954 -47.879)
		(end 247.916954 -42.926)
		(stroke
			(width 1.016)
			(type default)
		)
		(layer "In5.Cu")
	)
	(gr_line
		(start 246.757952 -51.02225)
		(end 247.302782 -51.56708)
		(stroke
			(width 1.016)
			(type default)
		)
		(layer "In5.Cu")
	)
	(gr_line
		(start 246.757952 -47.879)
		(end 246.757952 -51.02225)
		(stroke
			(width 1.016)
			(type default)
		)
		(layer "In5.Cu")
	)
	(gr_line
		(start 246.757952 -46.654466)
		(end 246.757952 -47.879)
		(stroke
			(width 1.016)
			(type default)
		)
		(layer "In5.Cu")
	)
	(gr_line
		(start 247.302782 -51.56708)
		(end 257.518916 -51.56708)
		(stroke
			(width 1.016)
			(type default)
		)
		(layer "In5.Cu")
	)
	(gr_line
		(start 247.916954 -42.926)
		(end 248.718832 -42.124122)
		(stroke
			(width 1.016)
			(type default)
		)
		(layer "In5.Cu")
	)
	(gr_line
		(start 248.718832 -42.124122)
		(end 254.682244 -42.124122)
		(stroke
			(width 1.016)
			(type default)
		)
		(layer "In5.Cu")
	)
	(gr_line
		(start 250.486418 -42.926)
		(end 246.757952 -46.654466)
		(stroke
			(width 1.016)
			(type default)
		)
		(layer "In5.Cu")
	)
	(gr_line
		(start 254.508 -42.926)
		(end 247.916954 -42.926)
		(stroke
			(width 1.016)
			(type default)
		)
		(layer "In5.Cu")
	)
	(gr_line
		(start 254.682244 -42.124122)
		(end 258.191 -45.632878)
		(stroke
			(width 1.016)
			(type default)
		)
		(layer "In5.Cu")
	)
	(gr_line
		(start 255.524 -8.636)
		(end 255.633982 -8.745982)
		(stroke
			(width 1.016)
			(type default)
		)
		(layer "In5.Cu")
	)
	(gr_line
		(start 255.633982 -8.745982)
		(end 258.462018 -8.745982)
		(stroke
			(width 1.016)
			(type default)
		)
		(layer "In5.Cu")
	)
	(gr_line
		(start 255.690116 -42.124122)
		(end 254.682244 -42.124122)
		(stroke
			(width 1.016)
			(type default)
		)
		(layer "In5.Cu")
	)
	(gr_line
		(start 257.048 -8.636)
		(end 279.654 -8.636)
		(stroke
			(width 1.016)
			(type default)
		)
		(layer "In5.Cu")
	)
	(gr_line
		(start 257.518916 -51.56708)
		(end 258.191 -50.894996)
		(stroke
			(width 1.016)
			(type default)
		)
		(layer "In5.Cu")
	)
	(gr_line
		(start 258.191 -50.894996)
		(end 258.191 -50.419)
		(stroke
			(width 1.016)
			(type default)
		)
		(layer "In5.Cu")
	)
	(gr_line
		(start 258.191 -50.419)
		(end 258.191 -47.879)
		(stroke
			(width 1.016)
			(type default)
		)
		(layer "In5.Cu")
	)
	(gr_line
		(start 258.191 -46.609)
		(end 254.508 -42.926)
		(stroke
			(width 1.016)
			(type default)
		)
		(layer "In5.Cu")
	)
	(gr_line
		(start 258.191 -46.609)
		(end 258.191 -47.879)
		(stroke
			(width 1.016)
			(type default)
		)
		(layer "In5.Cu")
	)
	(gr_line
		(start 258.191 -45.632878)
		(end 258.191 -46.609)
		(stroke
			(width 1.016)
			(type default)
		)
		(layer "In5.Cu")
	)
	(gr_line
		(start 258.191 -45.632878)
		(end 258.191 -44.625006)
		(stroke
			(width 1.016)
			(type default)
		)
		(layer "In5.Cu")
	)
	(gr_line
		(start 258.191 -44.625006)
		(end 255.690116 -42.124122)
		(stroke
			(width 1.016)
			(type default)
		)
		(layer "In5.Cu")
	)
	(gr_line
		(start 258.462018 -8.745982)
		(end 258.572 -8.636)
		(stroke
			(width 1.016)
			(type default)
		)
		(layer "In5.Cu")
	)
	(gr_circle
		(center 260.2484 -46.99)
		(end 261.1374 -46.99)
		(stroke
			(width 0.2)
			(type default)
		)
		(fill no)
		(layer "In5.Cu")
	)
	(gr_line
		(start 260.51383 -85.493606)
		(end 260.51383 -48.93183)
		(stroke
			(width 1.016)
			(type default)
		)
		(layer "In5.Cu")
	)
	(gr_line
		(start 260.51383 -48.93183)
		(end 258.191 -46.609)
		(stroke
			(width 1.016)
			(type default)
		)
		(layer "In5.Cu")
	)
	(gr_circle
		(center 261.02945 -54.61)
		(end 261.91845 -54.61)
		(stroke
			(width 0.2)
			(type default)
		)
		(fill no)
		(layer "In5.Cu")
	)
	(gr_circle
		(center 261.493 -71.5772)
		(end 262.382 -71.5772)
		(stroke
			(width 0.2)
			(type default)
		)
		(fill no)
		(layer "In5.Cu")
	)
	(gr_circle
		(center 261.6454 -52.705)
		(end 262.5344 -52.705)
		(stroke
			(width 0.2)
			(type default)
		)
		(fill no)
		(layer "In5.Cu")
	)
	(gr_circle
		(center 262.255 -71.5772)
		(end 263.144 -71.5772)
		(stroke
			(width 0.2)
			(type default)
		)
		(fill no)
		(layer "In5.Cu")
	)
	(gr_circle
		(center 262.72744 -64.516)
		(end 263.61644 -64.516)
		(stroke
			(width 0.2)
			(type default)
		)
		(fill no)
		(layer "In5.Cu")
	)
	(gr_circle
		(center 262.772398 -51.164998)
		(end 263.661398 -51.164998)
		(stroke
			(width 0.2)
			(type default)
		)
		(fill no)
		(layer "In5.Cu")
	)
	(gr_line
		(start 263.66343 -88.643206)
		(end 260.51383 -85.493606)
		(stroke
			(width 1.016)
			(type default)
		)
		(layer "In5.Cu")
	)
	(gr_line
		(start 264.696702 -82.761074)
		(end 265.824716 -83.889088)
		(stroke
			(width 1.016)
			(type default)
		)
		(layer "In5.Cu")
	)
	(gr_line
		(start 264.696702 -52.959)
		(end 264.696702 -82.761074)
		(stroke
			(width 1.016)
			(type default)
		)
		(layer "In5.Cu")
	)
	(gr_circle
		(center 265.4046 -70.7644)
		(end 266.2936 -70.7644)
		(stroke
			(width 0.2)
			(type default)
		)
		(fill no)
		(layer "In5.Cu")
	)
	(gr_line
		(start 265.824716 -83.889088)
		(end 279.229566 -83.889088)
		(stroke
			(width 1.016)
			(type default)
		)
		(layer "In5.Cu")
	)
	(gr_circle
		(center 265.979402 -50.148998)
		(end 266.868402 -50.148998)
		(stroke
			(width 0.2)
			(type default)
		)
		(fill no)
		(layer "In5.Cu")
	)
	(gr_line
		(start 266.41679 -51.238912)
		(end 264.696702 -52.959)
		(stroke
			(width 1.016)
			(type default)
		)
		(layer "In5.Cu")
	)
	(gr_circle
		(center 269.6464 -57.912)
		(end 270.5354 -57.912)
		(stroke
			(width 0.2)
			(type default)
		)
		(fill no)
		(layer "In5.Cu")
	)
	(gr_circle
		(center 270.4084 -57.912)
		(end 271.2974 -57.912)
		(stroke
			(width 0.2)
			(type default)
		)
		(fill no)
		(layer "In5.Cu")
	)
	(gr_circle
		(center 271.9324 -57.912)
		(end 272.8214 -57.912)
		(stroke
			(width 0.2)
			(type default)
		)
		(fill no)
		(layer "In5.Cu")
	)
	(gr_circle
		(center 272.6944 -57.912)
		(end 273.5834 -57.912)
		(stroke
			(width 0.2)
			(type default)
		)
		(fill no)
		(layer "In5.Cu")
	)
	(gr_line
		(start 274.733512 -51.238912)
		(end 266.41679 -51.238912)
		(stroke
			(width 1.016)
			(type default)
		)
		(layer "In5.Cu")
	)
	(gr_line
		(start 278.388318 -28.448)
		(end 231.14 -28.448)
		(stroke
			(width 1.016)
			(type default)
		)
		(layer "In5.Cu")
	)
	(gr_line
		(start 278.853392 -88.643206)
		(end 263.66343 -88.643206)
		(stroke
			(width 1.016)
			(type default)
		)
		(layer "In5.Cu")
	)
	(gr_line
		(start 279.229566 -83.889088)
		(end 279.653238 -84.31276)
		(stroke
			(width 1.016)
			(type default)
		)
		(layer "In5.Cu")
	)
	(gr_line
		(start 279.653238 -87.84336)
		(end 278.853392 -88.643206)
		(stroke
			(width 1.016)
			(type default)
		)
		(layer "In5.Cu")
	)
	(gr_line
		(start 279.653238 -84.31276)
		(end 279.653238 -87.84336)
		(stroke
			(width 1.016)
			(type default)
		)
		(layer "In5.Cu")
	)
	(gr_line
		(start 279.654 -27.182318)
		(end 278.388318 -28.448)
		(stroke
			(width 1.016)
			(type default)
		)
		(layer "In5.Cu")
	)
	(gr_line
		(start 279.654 -16.146018)
		(end 279.654 -27.182318)
		(stroke
			(width 1.016)
			(type default)
		)
		(layer "In5.Cu")
	)
	(gr_line
		(start 279.764998 -84.201)
		(end 279.653238 -84.31276)
		(stroke
			(width 0.508)
			(type default)
		)
		(layer "In5.Cu")
	)
	(gr_circle
		(center 280.329894 -78.1558)
		(end 281.218894 -78.1558)
		(stroke
			(width 0.2)
			(type default)
		)
		(fill no)
		(layer "In5.Cu")
	)
	(gr_line
		(start 280.416 -8.636)
		(end 279.654 -8.636)
		(stroke
			(width 1.016)
			(type default)
		)
		(layer "In5.Cu")
	)
	(gr_line
		(start 280.416 -8.636)
		(end 281.051 -8.636)
		(stroke
			(width 1.016)
			(type default)
		)
		(layer "In5.Cu")
	)
	(gr_line
		(start 281.051 -8.636)
		(end 323.142356 -8.636)
		(stroke
			(width 1.016)
			(type default)
		)
		(layer "In5.Cu")
	)
	(gr_circle
		(center 281.091894 -78.1558)
		(end 281.980894 -78.1558)
		(stroke
			(width 0.2)
			(type default)
		)
		(fill no)
		(layer "In5.Cu")
	)
	(gr_line
		(start 282.2956 -58.801)
		(end 274.733512 -51.238912)
		(stroke
			(width 1.016)
			(type default)
		)
		(layer "In5.Cu")
	)
	(gr_line
		(start 283.354018 -12.446)
		(end 279.654 -16.146018)
		(stroke
			(width 1.016)
			(type default)
		)
		(layer "In5.Cu")
	)
	(gr_line
		(start 291.667438 -58.801)
		(end 282.2956 -58.801)
		(stroke
			(width 1.016)
			(type default)
		)
		(layer "In5.Cu")
	)
	(gr_line
		(start 291.667438 -58.801)
		(end 293.3954 -58.801)
		(stroke
			(width 1.016)
			(type default)
		)
		(layer "In5.Cu")
	)
	(gr_line
		(start 293.3954 -58.801)
		(end 296.545 -61.9506)
		(stroke
			(width 1.016)
			(type default)
		)
		(layer "In5.Cu")
	)
	(gr_line
		(start 296.545 -65.532)
		(end 296.545 -63.678562)
		(stroke
			(width 1.016)
			(type default)
		)
		(layer "In5.Cu")
	)
	(gr_line
		(start 296.545 -61.9506)
		(end 296.545 -63.678562)
		(stroke
			(width 1.016)
			(type default)
		)
		(layer "In5.Cu")
	)
	(gr_circle
		(center 297.9928 -80.391)
		(end 298.8818 -80.391)
		(stroke
			(width 0.2)
			(type default)
		)
		(fill no)
		(layer "In5.Cu")
	)
	(gr_circle
		(center 298.069 -75.819)
		(end 298.958 -75.819)
		(stroke
			(width 0.2)
			(type default)
		)
		(fill no)
		(layer "In5.Cu")
	)
	(gr_line
		(start 298.35729 -67.34429)
		(end 296.545 -65.532)
		(stroke
			(width 1.016)
			(type default)
		)
		(layer "In5.Cu")
	)
	(gr_line
		(start 298.35729 -67.34429)
		(end 309.808372 -67.34429)
		(stroke
			(width 1.016)
			(type default)
		)
		(layer "In5.Cu")
	)
	(gr_circle
		(center 298.7548 -80.391)
		(end 299.6438 -80.391)
		(stroke
			(width 0.2)
			(type default)
		)
		(fill no)
		(layer "In5.Cu")
	)
	(gr_line
		(start 299.168312 -38.996112)
		(end 300.6852 -40.513)
		(stroke
			(width 1.016)
			(type default)
		)
		(layer "In5.Cu")
	)
	(gr_line
		(start 299.168312 -33.576768)
		(end 299.168312 -38.996112)
		(stroke
			(width 1.016)
			(type default)
		)
		(layer "In5.Cu")
	)
	(gr_line
		(start 299.265086 -33.479994)
		(end 299.168312 -33.576768)
		(stroke
			(width 1.016)
			(type default)
		)
		(layer "In5.Cu")
	)
	(gr_line
		(start 300.446694 -34.461958)
		(end 300.126654 -34.781998)
		(stroke
			(width 2.54)
			(type default)
		)
		(layer "In5.Cu")
	)
	(gr_line
		(start 300.6852 -40.513)
		(end 303.4792 -40.513)
		(stroke
			(width 1.016)
			(type default)
		)
		(layer "In5.Cu")
	)
	(gr_line
		(start 302.078136 -36.06165)
		(end 301.822104 -36.317682)
		(stroke
			(width 2.54)
			(type default)
		)
		(layer "In5.Cu")
	)
	(gr_line
		(start 303.101756 -37.821108)
		(end 303.069752 -37.853112)
		(stroke
			(width 2.54)
			(type default)
		)
		(layer "In5.Cu")
	)
	(gr_line
		(start 303.391316 -40.2844)
		(end 305.5366 -40.2844)
		(stroke
			(width 1.016)
			(type default)
		)
		(layer "In5.Cu")
	)
	(gr_line
		(start 303.4792 -40.513)
		(end 304.8 -41.8338)
		(stroke
			(width 1.016)
			(type default)
		)
		(layer "In5.Cu")
	)
	(gr_line
		(start 304.038 -12.446)
		(end 304.8 -13.208)
		(stroke
			(width 1.016)
			(type default)
		)
		(layer "In5.Cu")
	)
	(gr_line
		(start 304.546 -39.053516)
		(end 304.546 -41.1988)
		(stroke
			(width 1.016)
			(type default)
		)
		(layer "In5.Cu")
	)
	(gr_line
		(start 304.779934 -32.938466)
		(end 303.7586 -33.9598)
		(stroke
			(width 1.016)
			(type default)
		)
		(layer "In5.Cu")
	)
	(gr_line
		(start 304.794666 -32.938466)
		(end 305.816 -33.9598)
		(stroke
			(width 1.016)
			(type default)
		)
		(layer "In5.Cu")
	)
	(gr_line
		(start 304.8 -67.065144)
		(end 305.079146 -67.34429)
		(stroke
			(width 1.016)
			(type default)
		)
		(layer "In5.Cu")
	)
	(gr_line
		(start 304.8 -33.909)
		(end 304.8 -67.065144)
		(stroke
			(width 1.016)
			(type default)
		)
		(layer "In5.Cu")
	)
	(gr_line
		(start 304.8 -33.479994)
		(end 299.265086 -33.479994)
		(stroke
			(width 1.016)
			(type default)
		)
		(layer "In5.Cu")
	)
	(gr_line
		(start 304.8 -33.479994)
		(end 309.723028 -33.479994)
		(stroke
			(width 1.016)
			(type default)
		)
		(layer "In5.Cu")
	)
	(gr_line
		(start 304.8 -13.208)
		(end 304.8 -33.479994)
		(stroke
			(width 1.016)
			(type default)
		)
		(layer "In5.Cu")
	)
	(gr_line
		(start 305.562 -12.446)
		(end 304.8 -13.208)
		(stroke
			(width 1.016)
			(type default)
		)
		(layer "In5.Cu")
	)
	(gr_line
		(start 305.6128 -40.513)
		(end 304.8 -41.3258)
		(stroke
			(width 1.016)
			(type default)
		)
		(layer "In5.Cu")
	)
	(gr_line
		(start 305.6636 -46.2534)
		(end 304.8508 -45.4406)
		(stroke
			(width 1.016)
			(type default)
		)
		(layer "In5.Cu")
	)
	(gr_line
		(start 306.076858 -37.821108)
		(end 303.101756 -37.821108)
		(stroke
			(width 2.54)
			(type default)
		)
		(layer "In5.Cu")
	)
	(gr_line
		(start 306.17287 -37.91712)
		(end 306.076858 -37.821108)
		(stroke
			(width 2.54)
			(type default)
		)
		(layer "In5.Cu")
	)
	(gr_line
		(start 307.388514 -36.06165)
		(end 302.078136 -36.06165)
		(stroke
			(width 2.54)
			(type default)
		)
		(layer "In5.Cu")
	)
	(gr_line
		(start 307.836316 -36.509452)
		(end 307.388514 -36.06165)
		(stroke
			(width 2.54)
			(type default)
		)
		(layer "In5.Cu")
	)
	(gr_line
		(start 308.3052 -37.5412)
		(end 300.083728 -37.5412)
		(stroke
			(width 2.54)
			(type default)
		)
		(layer "In5.Cu")
	)
	(gr_line
		(start 308.3306 -36.068)
		(end 300.109128 -36.068)
		(stroke
			(width 2.54)
			(type default)
		)
		(layer "In5.Cu")
	)
	(gr_line
		(start 308.5592 -38.7858)
		(end 300.337728 -38.7858)
		(stroke
			(width 2.54)
			(type default)
		)
		(layer "In5.Cu")
	)
	(gr_line
		(start 308.668166 -34.461958)
		(end 300.446694 -34.461958)
		(stroke
			(width 2.54)
			(type default)
		)
		(layer "In5.Cu")
	)
	(gr_line
		(start 309.1688 -39.2938)
		(end 300.947328 -39.2938)
		(stroke
			(width 2.54)
			(type default)
		)
		(layer "In5.Cu")
	)
	(gr_line
		(start 309.2704 -40.513)
		(end 305.6128 -40.513)
		(stroke
			(width 1.016)
			(type default)
		)
		(layer "In5.Cu")
	)
	(gr_line
		(start 309.448962 -34.323528)
		(end 309.448962 -38.861238)
		(stroke
			(width 1.016)
			(type default)
		)
		(layer "In5.Cu")
	)
	(gr_line
		(start 309.627778 -35.42157)
		(end 308.668166 -34.461958)
		(stroke
			(width 2.54)
			(type default)
		)
		(layer "In5.Cu")
	)
	(gr_line
		(start 309.723028 -33.479994)
		(end 310.744362 -34.501328)
		(stroke
			(width 1.016)
			(type default)
		)
		(layer "In5.Cu")
	)
	(gr_line
		(start 309.804562 -34.425128)
		(end 309.804562 -38.962838)
		(stroke
			(width 1.016)
			(type default)
		)
		(layer "In5.Cu")
	)
	(gr_line
		(start 309.808372 -67.34429)
		(end 310.72201 -68.257928)
		(stroke
			(width 1.016)
			(type default)
		)
		(layer "In5.Cu")
	)
	(gr_line
		(start 310.236362 -34.501328)
		(end 310.236362 -39.039038)
		(stroke
			(width 1.016)
			(type default)
		)
		(layer "In5.Cu")
	)
	(gr_line
		(start 310.72201 -79.844646)
		(end 311.395364 -80.518)
		(stroke
			(width 1.016)
			(type default)
		)
		(layer "In5.Cu")
	)
	(gr_line
		(start 310.72201 -68.257928)
		(end 310.72201 -79.844646)
		(stroke
			(width 1.016)
			(type default)
		)
		(layer "In5.Cu")
	)
	(gr_line
		(start 310.744362 -39.039038)
		(end 309.2704 -40.513)
		(stroke
			(width 1.016)
			(type default)
		)
		(layer "In5.Cu")
	)
	(gr_line
		(start 310.744362 -34.501328)
		(end 310.744362 -39.039038)
		(stroke
			(width 1.016)
			(type default)
		)
		(layer "In5.Cu")
	)
	(gr_line
		(start 311.395364 -80.518)
		(end 323.977 -80.518)
		(stroke
			(width 1.016)
			(type default)
		)
		(layer "In5.Cu")
	)
	(gr_line
		(start 323.142356 -8.636)
		(end 324.612 -10.105644)
		(stroke
			(width 1.016)
			(type default)
		)
		(layer "In5.Cu")
	)
	(gr_line
		(start 323.977 -80.518)
		(end 324.612 -79.883)
		(stroke
			(width 1.016)
			(type default)
		)
		(layer "In5.Cu")
	)
	(gr_line
		(start 323.977 -12.446)
		(end 283.354018 -12.446)
		(stroke
			(width 1.016)
			(type default)
		)
		(layer "In5.Cu")
	)
	(gr_line
		(start 324.104 -46.355)
		(end 305.010058 -46.355)
		(stroke
			(width 1.016)
			(type default)
		)
		(layer "In5.Cu")
	)
	(gr_line
		(start 324.612 -49.227232)
		(end 324.612 -79.883)
		(stroke
			(width 1.016)
			(type default)
		)
		(layer "In5.Cu")
	)
	(gr_line
		(start 324.612 -49.227232)
		(end 335.25587 -49.227232)
		(stroke
			(width 1.016)
			(type default)
		)
		(layer "In5.Cu")
	)
	(gr_line
		(start 324.612 -46.863)
		(end 324.104 -46.355)
		(stroke
			(width 1.016)
			(type default)
		)
		(layer "In5.Cu")
	)
	(gr_line
		(start 324.612 -46.863)
		(end 324.612 -49.227232)
		(stroke
			(width 1.016)
			(type default)
		)
		(layer "In5.Cu")
	)
	(gr_line
		(start 324.612 -40.428672)
		(end 335.658968 -40.428672)
		(stroke
			(width 1.016)
			(type default)
		)
		(layer "In5.Cu")
	)
	(gr_line
		(start 324.612 -15.5956)
		(end 324.612 -46.986952)
		(stroke
			(width 1.016)
			(type default)
		)
		(layer "In5.Cu")
	)
	(gr_line
		(start 324.612 -13.081)
		(end 323.977 -12.446)
		(stroke
			(width 1.016)
			(type default)
		)
		(layer "In5.Cu")
	)
	(gr_line
		(start 324.612 -10.105644)
		(end 324.612 -15.5956)
		(stroke
			(width 1.016)
			(type default)
		)
		(layer "In5.Cu")
	)
	(gr_line
		(start 328.739246 -80.518)
		(end 323.977 -80.518)
		(stroke
			(width 1.016)
			(type default)
		)
		(layer "In5.Cu")
	)
	(gr_line
		(start 328.9808 -102.99827)
		(end 328.9808 -84.582)
		(stroke
			(width 1.016)
			(type default)
		)
		(layer "In5.Cu")
	)
	(gr_line
		(start 328.9808 -84.582)
		(end 328.9808 -80.276446)
		(stroke
			(width 1.016)
			(type default)
		)
		(layer "In5.Cu")
	)
	(gr_line
		(start 328.9808 -80.276446)
		(end 329.6031 -79.654146)
		(stroke
			(width 1.016)
			(type default)
		)
		(layer "In5.Cu")
	)
	(gr_line
		(start 328.982578 -103.000048)
		(end 328.9808 -102.99827)
		(stroke
			(width 1.016)
			(type default)
		)
		(layer "In5.Cu")
	)
	(gr_line
		(start 329.523344 -69.124322)
		(end 330.16317 -69.764148)
		(stroke
			(width 1.016)
			(type default)
		)
		(layer "In5.Cu")
	)
	(gr_line
		(start 329.523344 -64.29375)
		(end 329.523344 -69.124322)
		(stroke
			(width 1.016)
			(type default)
		)
		(layer "In5.Cu")
	)
	(gr_line
		(start 329.6031 -79.654146)
		(end 328.739246 -80.518)
		(stroke
			(width 1.016)
			(type default)
		)
		(layer "In5.Cu")
	)
	(gr_line
		(start 329.6031 -75.586336)
		(end 329.6031 -79.654146)
		(stroke
			(width 1.016)
			(type default)
		)
		(layer "In5.Cu")
	)
	(gr_line
		(start 329.61961 -36.040822)
		(end 329.61961 -30.31998)
		(stroke
			(width 1.016)
			(type default)
		)
		(layer "In5.Cu")
	)
	(gr_line
		(start 329.61961 -30.31998)
		(end 330.09967 -29.83992)
		(stroke
			(width 1.016)
			(type default)
		)
		(layer "In5.Cu")
	)
	(gr_line
		(start 329.620118 -23.60168)
		(end 329.620118 -19.02714)
		(stroke
			(width 1.016)
			(type default)
		)
		(layer "In5.Cu")
	)
	(gr_line
		(start 329.620118 -19.02714)
		(end 330.195936 -18.451322)
		(stroke
			(width 1.016)
			(type default)
		)
		(layer "In5.Cu")
	)
	(gr_line
		(start 329.747118 -58.247534)
		(end 330.226924 -58.72734)
		(stroke
			(width 1.016)
			(type default)
		)
		(layer "In5.Cu")
	)
	(gr_line
		(start 329.747118 -52.553108)
		(end 329.747118 -58.247534)
		(stroke
			(width 1.016)
			(type default)
		)
		(layer "In5.Cu")
	)
	(gr_line
		(start 329.987148 -75.202288)
		(end 329.6031 -75.586336)
		(stroke
			(width 1.016)
			(type default)
		)
		(layer "In5.Cu")
	)
	(gr_line
		(start 330.066904 -52.233322)
		(end 329.747118 -52.553108)
		(stroke
			(width 1.016)
			(type default)
		)
		(layer "In5.Cu")
	)
	(gr_line
		(start 330.09967 -29.83992)
		(end 336.178144 -29.83992)
		(stroke
			(width 1.016)
			(type default)
		)
		(layer "In5.Cu")
	)
	(gr_line
		(start 330.16317 -69.764148)
		(end 336.177382 -69.764148)
		(stroke
			(width 1.016)
			(type default)
		)
		(layer "In5.Cu")
	)
	(gr_line
		(start 330.195936 -18.451322)
		(end 336.210148 -18.451322)
		(stroke
			(width 1.016)
			(type default)
		)
		(layer "In5.Cu")
	)
	(gr_line
		(start 330.226924 -58.72734)
		(end 336.081116 -58.72734)
		(stroke
			(width 1.016)
			(type default)
		)
		(layer "In5.Cu")
	)
	(gr_line
		(start 330.355956 -24.337518)
		(end 329.620118 -23.60168)
		(stroke
			(width 1.016)
			(type default)
		)
		(layer "In5.Cu")
	)
	(gr_line
		(start 330.706984 -63.11011)
		(end 329.523344 -64.29375)
		(stroke
			(width 1.016)
			(type default)
		)
		(layer "In5.Cu")
	)
	(gr_circle
		(center 332.070964 -9.774428)
		(end 332.959964 -9.774428)
		(stroke
			(width 0.2)
			(type default)
		)
		(fill no)
		(layer "In5.Cu")
	)
	(gr_line
		(start 332.266036 -38.687248)
		(end 329.61961 -36.040822)
		(stroke
			(width 1.016)
			(type default)
		)
		(layer "In5.Cu")
	)
	(gr_circle
		(center 332.832964 -9.774428)
		(end 333.721964 -9.774428)
		(stroke
			(width 0.2)
			(type default)
		)
		(fill no)
		(layer "In5.Cu")
	)
	(gr_circle
		(center 333.594964 -9.774428)
		(end 334.483964 -9.774428)
		(stroke
			(width 0.2)
			(type default)
		)
		(fill no)
		(layer "In5.Cu")
	)
	(gr_circle
		(center 334.356964 -9.774428)
		(end 335.245964 -9.774428)
		(stroke
			(width 0.2)
			(type default)
		)
		(fill no)
		(layer "In5.Cu")
	)
	(gr_line
		(start 335.25587 -49.227232)
		(end 336.135472 -50.106834)
		(stroke
			(width 1.016)
			(type default)
		)
		(layer "In5.Cu")
	)
	(gr_line
		(start 335.32064 -52.233322)
		(end 330.066904 -52.233322)
		(stroke
			(width 1.016)
			(type default)
		)
		(layer "In5.Cu")
	)
	(gr_line
		(start 335.576926 -38.687248)
		(end 332.266036 -38.687248)
		(stroke
			(width 1.016)
			(type default)
		)
		(layer "In5.Cu")
	)
	(gr_line
		(start 335.658968 -40.428672)
		(end 336.056732 -40.030908)
		(stroke
			(width 1.016)
			(type default)
		)
		(layer "In5.Cu")
	)
	(gr_line
		(start 335.825592 -63.11011)
		(end 330.706984 -63.11011)
		(stroke
			(width 1.016)
			(type default)
		)
		(layer "In5.Cu")
	)
	(gr_line
		(start 336.050128 -24.337518)
		(end 330.355956 -24.337518)
		(stroke
			(width 1.016)
			(type default)
		)
		(layer "In5.Cu")
	)
	(gr_line
		(start 336.056732 -40.030908)
		(end 336.056732 -39.167054)
		(stroke
			(width 1.016)
			(type default)
		)
		(layer "In5.Cu")
	)
	(gr_line
		(start 336.056732 -39.167054)
		(end 335.576926 -38.687248)
		(stroke
			(width 1.016)
			(type default)
		)
		(layer "In5.Cu")
	)
	(gr_line
		(start 336.081116 -58.72734)
		(end 336.625184 -59.271408)
		(stroke
			(width 1.016)
			(type default)
		)
		(layer "In5.Cu")
	)
	(gr_line
		(start 336.135472 -51.41849)
		(end 335.32064 -52.233322)
		(stroke
			(width 1.016)
			(type default)
		)
		(layer "In5.Cu")
	)
	(gr_line
		(start 336.135472 -50.106834)
		(end 336.135472 -51.41849)
		(stroke
			(width 1.016)
			(type default)
		)
		(layer "In5.Cu")
	)
	(gr_line
		(start 336.177382 -69.764148)
		(end 336.785204 -70.37197)
		(stroke
			(width 1.016)
			(type default)
		)
		(layer "In5.Cu")
	)
	(gr_line
		(start 336.178144 -29.83992)
		(end 336.65795 -29.360114)
		(stroke
			(width 1.016)
			(type default)
		)
		(layer "In5.Cu")
	)
	(gr_line
		(start 336.210148 -18.451322)
		(end 336.721958 -17.939512)
		(stroke
			(width 1.016)
			(type default)
		)
		(layer "In5.Cu")
	)
	(gr_line
		(start 336.257392 -75.202288)
		(end 329.987148 -75.202288)
		(stroke
			(width 1.016)
			(type default)
		)
		(layer "In5.Cu")
	)
	(gr_circle
		(center 336.3214 -49.5046)
		(end 337.2104 -49.5046)
		(stroke
			(width 0.2)
			(type default)
		)
		(fill no)
		(layer "In5.Cu")
	)
	(gr_circle
		(center 336.3214 -38.227)
		(end 337.2104 -38.227)
		(stroke
			(width 0.2)
			(type default)
		)
		(fill no)
		(layer "In5.Cu")
	)
	(gr_line
		(start 336.625184 -62.310518)
		(end 335.825592 -63.11011)
		(stroke
			(width 1.016)
			(type default)
		)
		(layer "In5.Cu")
	)
	(gr_line
		(start 336.625184 -59.271408)
		(end 336.625184 -62.310518)
		(stroke
			(width 1.016)
			(type default)
		)
		(layer "In5.Cu")
	)
	(gr_line
		(start 336.65795 -29.360114)
		(end 336.65795 -24.94534)
		(stroke
			(width 1.016)
			(type default)
		)
		(layer "In5.Cu")
	)
	(gr_line
		(start 336.65795 -24.94534)
		(end 336.050128 -24.337518)
		(stroke
			(width 1.016)
			(type default)
		)
		(layer "In5.Cu")
	)
	(gr_line
		(start 336.721958 -17.939512)
		(end 336.721958 -15.5956)
		(stroke
			(width 1.016)
			(type default)
		)
		(layer "In5.Cu")
	)
	(gr_line
		(start 336.721958 -15.5956)
		(end 324.612 -15.5956)
		(stroke
			(width 1.016)
			(type default)
		)
		(layer "In5.Cu")
	)
	(gr_line
		(start 336.721958 -15.5956)
		(end 353.8982 -15.5956)
		(stroke
			(width 1.016)
			(type default)
		)
		(layer "In5.Cu")
	)
	(gr_line
		(start 336.785204 -74.674476)
		(end 336.257392 -75.202288)
		(stroke
			(width 1.016)
			(type default)
		)
		(layer "In5.Cu")
	)
	(gr_line
		(start 336.785204 -70.37197)
		(end 336.785204 -74.674476)
		(stroke
			(width 1.016)
			(type default)
		)
		(layer "In5.Cu")
	)
	(gr_circle
		(center 342.72474 -9.878822)
		(end 343.61374 -9.878822)
		(stroke
			(width 0.2)
			(type default)
		)
		(fill no)
		(layer "In5.Cu")
	)
	(gr_circle
		(center 343.48674 -9.878822)
		(end 344.37574 -9.878822)
		(stroke
			(width 0.2)
			(type default)
		)
		(fill no)
		(layer "In5.Cu")
	)
	(gr_line
		(start 344.000074 -103.000048)
		(end 264.668 -103.000048)
		(stroke
			(width 2.032)
			(type default)
		)
		(layer "In5.Cu")
	)
	(gr_circle
		(center 344.24874 -9.878822)
		(end 345.13774 -9.878822)
		(stroke
			(width 0.2)
			(type default)
		)
		(fill no)
		(layer "In5.Cu")
	)
	(gr_circle
		(center 345.01074 -9.878822)
		(end 345.89974 -9.878822)
		(stroke
			(width 0.2)
			(type default)
		)
		(fill no)
		(layer "In5.Cu")
	)
	(gr_line
		(start 351.499932 -153.299922)
		(end 351.499932 -110.499906)
		(stroke
			(width 2.032)
			(type default)
		)
		(layer "In5.Cu")
	)
	(gr_arc
		(start 351.499932 -153.299922)
		(mid 352.964404 -156.835427)
		(end 356.499922 -158.299912)
		(stroke
			(width 2.032)
			(type default)
		)
		(layer "In5.Cu")
	)
	(gr_arc
		(start 351.499932 -110.499906)
		(mid 349.303274 -105.196706)
		(end 344.000074 -103.000048)
		(stroke
			(width 2.032)
			(type default)
		)
		(layer "In5.Cu")
	)
	(gr_line
		(start 353.8982 -15.5956)
		(end 370.3066 -32.004)
		(stroke
			(width 1.016)
			(type default)
		)
		(layer "In5.Cu")
	)
	(gr_line
		(start 357.000048 -158.299912)
		(end 356.499922 -158.299912)
		(stroke
			(width 2.032)
			(type default)
		)
		(layer "In5.Cu")
	)
	(gr_circle
		(center 359.74274 -10.282174)
		(end 360.63174 -10.282174)
		(stroke
			(width 0.2)
			(type default)
		)
		(fill no)
		(layer "In5.Cu")
	)
	(gr_line
		(start 360.000042 -166.649908)
		(end 360.000042 -161.299906)
		(stroke
			(width 2.032)
			(type default)
		)
		(layer "In5.Cu")
	)
	(gr_arc
		(start 360.000042 -166.649908)
		(mid 361.46451 -170.185418)
		(end 365.000032 -171.649898)
		(stroke
			(width 2.032)
			(type default)
		)
		(layer "In5.Cu")
	)
	(gr_arc
		(start 360.000042 -161.299906)
		(mid 359.121364 -159.17859)
		(end 357.000048 -158.299912)
		(stroke
			(width 2.032)
			(type default)
		)
		(layer "In5.Cu")
	)
	(gr_circle
		(center 360.50474 -10.282174)
		(end 361.39374 -10.282174)
		(stroke
			(width 0.2)
			(type default)
		)
		(fill no)
		(layer "In5.Cu")
	)
	(gr_circle
		(center 361.26674 -10.282174)
		(end 362.15574 -10.282174)
		(stroke
			(width 0.2)
			(type default)
		)
		(fill no)
		(layer "In5.Cu")
	)
	(gr_circle
		(center 362.02874 -10.282174)
		(end 362.91774 -10.282174)
		(stroke
			(width 0.2)
			(type default)
		)
		(fill no)
		(layer "In5.Cu")
	)
	(gr_circle
		(center 363.000036 -168.82999)
		(end 364.21314 -168.82999)
		(stroke
			(width 0.2)
			(type default)
		)
		(fill no)
		(layer "In5.Cu")
	)
	(gr_circle
		(center 363.000036 -166.829994)
		(end 364.21314 -166.829994)
		(stroke
			(width 0.2)
			(type default)
		)
		(fill no)
		(layer "In5.Cu")
	)
	(gr_circle
		(center 363.000036 -164.829998)
		(end 364.21314 -164.829998)
		(stroke
			(width 0.2)
			(type default)
		)
		(fill no)
		(layer "In5.Cu")
	)
	(gr_circle
		(center 364.143036 -167.972994)
		(end 365.35614 -167.972994)
		(stroke
			(width 0.2)
			(type default)
		)
		(fill no)
		(layer "In5.Cu")
	)
	(gr_circle
		(center 364.143036 -165.972998)
		(end 365.35614 -165.972998)
		(stroke
			(width 0.2)
			(type default)
		)
		(fill no)
		(layer "In5.Cu")
	)
	(gr_circle
		(center 365.000032 -168.82999)
		(end 366.213136 -168.82999)
		(stroke
			(width 0.2)
			(type default)
		)
		(fill no)
		(layer "In5.Cu")
	)
	(gr_circle
		(center 365.000032 -166.829994)
		(end 366.213136 -166.829994)
		(stroke
			(width 0.2)
			(type default)
		)
		(fill no)
		(layer "In5.Cu")
	)
	(gr_circle
		(center 365.000032 -164.829998)
		(end 366.213136 -164.829998)
		(stroke
			(width 0.2)
			(type default)
		)
		(fill no)
		(layer "In5.Cu")
	)
	(gr_circle
		(center 366.119918 -5.290058)
		(end 367.333022 -5.290058)
		(stroke
			(width 0.2)
			(type default)
		)
		(fill no)
		(layer "In5.Cu")
	)
	(gr_circle
		(center 368.659918 -5.290058)
		(end 369.873022 -5.290058)
		(stroke
			(width 0.2)
			(type default)
		)
		(fill no)
		(layer "In5.Cu")
	)
	(gr_circle
		(center 369.000024 -168.82999)
		(end 370.213128 -168.82999)
		(stroke
			(width 0.2)
			(type default)
		)
		(fill no)
		(layer "In5.Cu")
	)
	(gr_circle
		(center 369.000024 -166.829994)
		(end 370.213128 -166.829994)
		(stroke
			(width 0.2)
			(type default)
		)
		(fill no)
		(layer "In5.Cu")
	)
	(gr_circle
		(center 369.000024 -164.829998)
		(end 370.213128 -164.829998)
		(stroke
			(width 0.2)
			(type default)
		)
		(fill no)
		(layer "In5.Cu")
	)
	(gr_circle
		(center 370.112036 -167.718994)
		(end 371.32514 -167.718994)
		(stroke
			(width 0.2)
			(type default)
		)
		(fill no)
		(layer "In5.Cu")
	)
	(gr_circle
		(center 370.112036 -165.718998)
		(end 371.32514 -165.718998)
		(stroke
			(width 0.2)
			(type default)
		)
		(fill no)
		(layer "In5.Cu")
	)
	(gr_line
		(start 370.3066 -32.004)
		(end 389.560308 -32.004)
		(stroke
			(width 1.016)
			(type default)
		)
		(layer "In5.Cu")
	)
	(gr_circle
		(center 371.00002 -168.82999)
		(end 372.213124 -168.82999)
		(stroke
			(width 0.2)
			(type default)
		)
		(fill no)
		(layer "In5.Cu")
	)
	(gr_circle
		(center 371.00002 -166.829994)
		(end 372.213124 -166.829994)
		(stroke
			(width 0.2)
			(type default)
		)
		(fill no)
		(layer "In5.Cu")
	)
	(gr_circle
		(center 371.00002 -164.829998)
		(end 372.213124 -164.829998)
		(stroke
			(width 0.2)
			(type default)
		)
		(fill no)
		(layer "In5.Cu")
	)
	(gr_circle
		(center 372.160038 -4.575048)
		(end 373.373142 -4.575048)
		(stroke
			(width 0.2)
			(type default)
		)
		(fill no)
		(layer "In5.Cu")
	)
	(gr_circle
		(center 372.160038 -2.035048)
		(end 373.373142 -2.035048)
		(stroke
			(width 0.2)
			(type default)
		)
		(fill no)
		(layer "In5.Cu")
	)
	(gr_circle
		(center 373.303038 -4.575048)
		(end 374.516142 -4.575048)
		(stroke
			(width 0.2)
			(type default)
		)
		(fill no)
		(layer "In5.Cu")
	)
	(gr_circle
		(center 373.430038 -5.845048)
		(end 374.643142 -5.845048)
		(stroke
			(width 0.2)
			(type default)
		)
		(fill no)
		(layer "In5.Cu")
	)
	(gr_circle
		(center 373.430038 -3.305048)
		(end 374.643142 -3.305048)
		(stroke
			(width 0.2)
			(type default)
		)
		(fill no)
		(layer "In5.Cu")
	)
	(gr_circle
		(center 373.430038 -1.527048)
		(end 374.643142 -1.527048)
		(stroke
			(width 0.2)
			(type default)
		)
		(fill no)
		(layer "In5.Cu")
	)
	(gr_circle
		(center 374.192038 -3.432048)
		(end 375.405142 -3.432048)
		(stroke
			(width 0.2)
			(type default)
		)
		(fill no)
		(layer "In5.Cu")
	)
	(gr_circle
		(center 374.700038 -4.575048)
		(end 375.913142 -4.575048)
		(stroke
			(width 0.2)
			(type default)
		)
		(fill no)
		(layer "In5.Cu")
	)
	(gr_circle
		(center 374.700038 -2.035048)
		(end 375.913142 -2.035048)
		(stroke
			(width 0.2)
			(type default)
		)
		(fill no)
		(layer "In5.Cu")
	)
	(gr_circle
		(center 375.000012 -168.82999)
		(end 376.213116 -168.82999)
		(stroke
			(width 0.2)
			(type default)
		)
		(fill no)
		(layer "In5.Cu")
	)
	(gr_circle
		(center 375.000012 -166.829994)
		(end 376.213116 -166.829994)
		(stroke
			(width 0.2)
			(type default)
		)
		(fill no)
		(layer "In5.Cu")
	)
	(gr_circle
		(center 375.000012 -164.829998)
		(end 376.213116 -164.829998)
		(stroke
			(width 0.2)
			(type default)
		)
		(fill no)
		(layer "In5.Cu")
	)
	(gr_circle
		(center 375.462038 -1.654048)
		(end 376.675142 -1.654048)
		(stroke
			(width 0.2)
			(type default)
		)
		(fill no)
		(layer "In5.Cu")
	)
	(gr_circle
		(center 375.954036 -167.591994)
		(end 377.16714 -167.591994)
		(stroke
			(width 0.2)
			(type default)
		)
		(fill no)
		(layer "In5.Cu")
	)
	(gr_circle
		(center 375.954036 -165.591998)
		(end 377.16714 -165.591998)
		(stroke
			(width 0.2)
			(type default)
		)
		(fill no)
		(layer "In5.Cu")
	)
	(gr_circle
		(center 375.970038 -5.845048)
		(end 377.183142 -5.845048)
		(stroke
			(width 0.2)
			(type default)
		)
		(fill no)
		(layer "In5.Cu")
	)
	(gr_circle
		(center 375.970038 -3.305048)
		(end 377.183142 -3.305048)
		(stroke
			(width 0.2)
			(type default)
		)
		(fill no)
		(layer "In5.Cu")
	)
	(gr_circle
		(center 376.605038 -1.527048)
		(end 377.818142 -1.527048)
		(stroke
			(width 0.2)
			(type default)
		)
		(fill no)
		(layer "In5.Cu")
	)
	(gr_circle
		(center 377.000008 -168.82999)
		(end 378.213112 -168.82999)
		(stroke
			(width 0.2)
			(type default)
		)
		(fill no)
		(layer "In5.Cu")
	)
	(gr_circle
		(center 377.000008 -166.829994)
		(end 378.213112 -166.829994)
		(stroke
			(width 0.2)
			(type default)
		)
		(fill no)
		(layer "In5.Cu")
	)
	(gr_circle
		(center 377.000008 -164.829998)
		(end 378.213112 -164.829998)
		(stroke
			(width 0.2)
			(type default)
		)
		(fill no)
		(layer "In5.Cu")
	)
	(gr_circle
		(center 378.079 -132.199888)
		(end 379.603 -132.199888)
		(stroke
			(width 0.2)
			(type default)
		)
		(fill no)
		(layer "In5.Cu")
	)
	(gr_circle
		(center 378.079 -111.879888)
		(end 379.603 -111.879888)
		(stroke
			(width 0.2)
			(type default)
		)
		(fill no)
		(layer "In5.Cu")
	)
	(gr_circle
		(center 378.079 -91.559888)
		(end 379.603 -91.559888)
		(stroke
			(width 0.2)
			(type default)
		)
		(fill no)
		(layer "In5.Cu")
	)
	(gr_circle
		(center 378.079 -71.239888)
		(end 379.603 -71.239888)
		(stroke
			(width 0.2)
			(type default)
		)
		(fill no)
		(layer "In5.Cu")
	)
	(gr_circle
		(center 378.079 -50.919888)
		(end 379.603 -50.919888)
		(stroke
			(width 0.2)
			(type default)
		)
		(fill no)
		(layer "In5.Cu")
	)
	(gr_circle
		(center 378.46 -21.336)
		(end 379.349 -21.336)
		(stroke
			(width 0.2)
			(type default)
		)
		(fill no)
		(layer "In5.Cu")
	)
	(gr_circle
		(center 378.46 -20.447)
		(end 379.349 -20.447)
		(stroke
			(width 0.2)
			(type default)
		)
		(fill no)
		(layer "In5.Cu")
	)
	(gr_circle
		(center 378.517912 -16.891)
		(end 379.406912 -16.891)
		(stroke
			(width 0.2)
			(type default)
		)
		(fill no)
		(layer "In5.Cu")
	)
	(gr_circle
		(center 379.660912 -21.209)
		(end 380.549912 -21.209)
		(stroke
			(width 0.2)
			(type default)
		)
		(fill no)
		(layer "In5.Cu")
	)
	(gr_circle
		(center 379.660912 -16.891)
		(end 380.549912 -16.891)
		(stroke
			(width 0.2)
			(type default)
		)
		(fill no)
		(layer "In5.Cu")
	)
	(gr_circle
		(center 380.53772 -16.129)
		(end 381.42672 -16.129)
		(stroke
			(width 0.2)
			(type default)
		)
		(fill no)
		(layer "In5.Cu")
	)
	(gr_circle
		(center 380.803912 -18.923)
		(end 381.692912 -18.923)
		(stroke
			(width 0.2)
			(type default)
		)
		(fill no)
		(layer "In5.Cu")
	)
	(gr_circle
		(center 381.946912 -18.917158)
		(end 382.835912 -18.917158)
		(stroke
			(width 0.2)
			(type default)
		)
		(fill no)
		(layer "In5.Cu")
	)
	(gr_circle
		(center 382.2954 -16.383)
		(end 383.1844 -16.383)
		(stroke
			(width 0.2)
			(type default)
		)
		(fill no)
		(layer "In5.Cu")
	)
	(gr_circle
		(center 383.199894 -168.82999)
		(end 384.412998 -168.82999)
		(stroke
			(width 0.2)
			(type default)
		)
		(fill no)
		(layer "In5.Cu")
	)
	(gr_circle
		(center 383.199894 -166.829994)
		(end 384.412998 -166.829994)
		(stroke
			(width 0.2)
			(type default)
		)
		(fill no)
		(layer "In5.Cu")
	)
	(gr_circle
		(center 383.199894 -164.829998)
		(end 384.412998 -164.829998)
		(stroke
			(width 0.2)
			(type default)
		)
		(fill no)
		(layer "In5.Cu")
	)
	(gr_circle
		(center 384.209036 -167.718994)
		(end 385.42214 -167.718994)
		(stroke
			(width 0.2)
			(type default)
		)
		(fill no)
		(layer "In5.Cu")
	)
	(gr_circle
		(center 384.209036 -165.718998)
		(end 385.42214 -165.718998)
		(stroke
			(width 0.2)
			(type default)
		)
		(fill no)
		(layer "In5.Cu")
	)
	(gr_circle
		(center 385.19989 -168.82999)
		(end 386.412994 -168.82999)
		(stroke
			(width 0.2)
			(type default)
		)
		(fill no)
		(layer "In5.Cu")
	)
	(gr_circle
		(center 385.19989 -166.829994)
		(end 386.412994 -166.829994)
		(stroke
			(width 0.2)
			(type default)
		)
		(fill no)
		(layer "In5.Cu")
	)
	(gr_circle
		(center 385.19989 -164.829998)
		(end 386.412994 -164.829998)
		(stroke
			(width 0.2)
			(type default)
		)
		(fill no)
		(layer "In5.Cu")
	)
	(gr_circle
		(center 387.2484 -28.321)
		(end 388.1374 -28.321)
		(stroke
			(width 0.2)
			(type default)
		)
		(fill no)
		(layer "In5.Cu")
	)
	(gr_circle
		(center 387.8834 -27.559)
		(end 388.7724 -27.559)
		(stroke
			(width 0.2)
			(type default)
		)
		(fill no)
		(layer "In5.Cu")
	)
	(gr_circle
		(center 387.8834 -25.12695)
		(end 388.7724 -25.12695)
		(stroke
			(width 0.2)
			(type default)
		)
		(fill no)
		(layer "In5.Cu")
	)
	(gr_circle
		(center 389.0264 -24.623014)
		(end 389.9154 -24.623014)
		(stroke
			(width 0.2)
			(type default)
		)
		(fill no)
		(layer "In5.Cu")
	)
	(gr_circle
		(center 389.199882 -168.82999)
		(end 390.412986 -168.82999)
		(stroke
			(width 0.2)
			(type default)
		)
		(fill no)
		(layer "In5.Cu")
	)
	(gr_circle
		(center 389.199882 -166.829994)
		(end 390.412986 -166.829994)
		(stroke
			(width 0.2)
			(type default)
		)
		(fill no)
		(layer "In5.Cu")
	)
	(gr_circle
		(center 389.199882 -164.829998)
		(end 390.412986 -164.829998)
		(stroke
			(width 0.2)
			(type default)
		)
		(fill no)
		(layer "In5.Cu")
	)
	(gr_line
		(start 389.560308 -32.004)
		(end 389.471154 -32.004)
		(stroke
			(width 1.016)
			(type default)
		)
		(layer "In5.Cu")
	)
	(gr_circle
		(center 390.305036 -167.845994)
		(end 391.51814 -167.845994)
		(stroke
			(width 0.2)
			(type default)
		)
		(fill no)
		(layer "In5.Cu")
	)
	(gr_circle
		(center 390.305036 -165.845998)
		(end 391.51814 -165.845998)
		(stroke
			(width 0.2)
			(type default)
		)
		(fill no)
		(layer "In5.Cu")
	)
	(gr_circle
		(center 391.199878 -168.82999)
		(end 392.412982 -168.82999)
		(stroke
			(width 0.2)
			(type default)
		)
		(fill no)
		(layer "In5.Cu")
	)
	(gr_circle
		(center 391.199878 -166.829994)
		(end 392.412982 -166.829994)
		(stroke
			(width 0.2)
			(type default)
		)
		(fill no)
		(layer "In5.Cu")
	)
	(gr_circle
		(center 391.199878 -164.829998)
		(end 392.412982 -164.829998)
		(stroke
			(width 0.2)
			(type default)
		)
		(fill no)
		(layer "In5.Cu")
	)
	(gr_circle
		(center 393.954 -24.511)
		(end 394.843 -24.511)
		(stroke
			(width 0.2)
			(type default)
		)
		(fill no)
		(layer "In5.Cu")
	)
	(gr_circle
		(center 397.637 -132.199888)
		(end 399.161 -132.199888)
		(stroke
			(width 0.2)
			(type default)
		)
		(fill no)
		(layer "In5.Cu")
	)
	(gr_circle
		(center 397.637 -111.879888)
		(end 399.161 -111.879888)
		(stroke
			(width 0.2)
			(type default)
		)
		(fill no)
		(layer "In5.Cu")
	)
	(gr_circle
		(center 397.637 -91.559888)
		(end 399.161 -91.559888)
		(stroke
			(width 0.2)
			(type default)
		)
		(fill no)
		(layer "In5.Cu")
	)
	(gr_circle
		(center 397.637 -71.239888)
		(end 399.161 -71.239888)
		(stroke
			(width 0.2)
			(type default)
		)
		(fill no)
		(layer "In5.Cu")
	)
	(gr_circle
		(center 397.637 -50.919888)
		(end 399.161 -50.919888)
		(stroke
			(width 0.2)
			(type default)
		)
		(fill no)
		(layer "In5.Cu")
	)
	(gr_circle
		(center 398.145 -17.018)
		(end 399.034 -17.018)
		(stroke
			(width 0.2)
			(type default)
		)
		(fill no)
		(layer "In5.Cu")
	)
	(gr_line
		(start 402.1074 -74.041)
		(end 402.1074 -44.551092)
		(stroke
			(width 1.016)
			(type default)
		)
		(layer "In5.Cu")
	)
	(gr_line
		(start 402.1074 -44.551092)
		(end 389.560308 -32.004)
		(stroke
			(width 1.016)
			(type default)
		)
		(layer "In5.Cu")
	)
	(gr_circle
		(center 403.125178 -168.82999)
		(end 404.338282 -168.82999)
		(stroke
			(width 0.2)
			(type default)
		)
		(fill no)
		(layer "In5.Cu")
	)
	(gr_circle
		(center 403.125178 -166.829994)
		(end 404.338282 -166.829994)
		(stroke
			(width 0.2)
			(type default)
		)
		(fill no)
		(layer "In5.Cu")
	)
	(gr_circle
		(center 403.125178 -164.829998)
		(end 404.338282 -164.829998)
		(stroke
			(width 0.2)
			(type default)
		)
		(fill no)
		(layer "In5.Cu")
	)
	(gr_circle
		(center 403.125178 -162.830002)
		(end 404.338282 -162.830002)
		(stroke
			(width 0.2)
			(type default)
		)
		(fill no)
		(layer "In5.Cu")
	)
	(gr_circle
		(center 403.125178 -160.830006)
		(end 404.338282 -160.830006)
		(stroke
			(width 0.2)
			(type default)
		)
		(fill no)
		(layer "In5.Cu")
	)
	(gr_circle
		(center 403.125178 -158.83001)
		(end 404.338282 -158.83001)
		(stroke
			(width 0.2)
			(type default)
		)
		(fill no)
		(layer "In5.Cu")
	)
	(gr_circle
		(center 403.125178 -156.830014)
		(end 404.338282 -156.830014)
		(stroke
			(width 0.2)
			(type default)
		)
		(fill no)
		(layer "In5.Cu")
	)
	(gr_circle
		(center 403.125178 -154.830018)
		(end 404.338282 -154.830018)
		(stroke
			(width 0.2)
			(type default)
		)
		(fill no)
		(layer "In5.Cu")
	)
	(gr_circle
		(center 403.125178 -152.830022)
		(end 404.338282 -152.830022)
		(stroke
			(width 0.2)
			(type default)
		)
		(fill no)
		(layer "In5.Cu")
	)
	(gr_line
		(start 403.999954 -171.649898)
		(end 365.000032 -171.649898)
		(stroke
			(width 2.032)
			(type default)
		)
		(layer "In5.Cu")
	)
	(gr_arc
		(start 403.999954 -171.649898)
		(mid 407.535513 -170.185452)
		(end 408.999944 -166.649908)
		(stroke
			(width 2.032)
			(type default)
		)
		(layer "In5.Cu")
	)
	(gr_circle
		(center 404.014178 -169.97299)
		(end 405.227282 -169.97299)
		(stroke
			(width 0.2)
			(type default)
		)
		(fill no)
		(layer "In5.Cu")
	)
	(gr_circle
		(center 404.141178 -167.845994)
		(end 405.354282 -167.845994)
		(stroke
			(width 0.2)
			(type default)
		)
		(fill no)
		(layer "In5.Cu")
	)
	(gr_circle
		(center 404.141178 -165.845998)
		(end 405.354282 -165.845998)
		(stroke
			(width 0.2)
			(type default)
		)
		(fill no)
		(layer "In5.Cu")
	)
	(gr_circle
		(center 404.141178 -163.846002)
		(end 405.354282 -163.846002)
		(stroke
			(width 0.2)
			(type default)
		)
		(fill no)
		(layer "In5.Cu")
	)
	(gr_circle
		(center 404.141178 -161.846006)
		(end 405.354282 -161.846006)
		(stroke
			(width 0.2)
			(type default)
		)
		(fill no)
		(layer "In5.Cu")
	)
	(gr_circle
		(center 404.141178 -159.84601)
		(end 405.354282 -159.84601)
		(stroke
			(width 0.2)
			(type default)
		)
		(fill no)
		(layer "In5.Cu")
	)
	(gr_circle
		(center 404.141178 -157.846014)
		(end 405.354282 -157.846014)
		(stroke
			(width 0.2)
			(type default)
		)
		(fill no)
		(layer "In5.Cu")
	)
	(gr_circle
		(center 404.141178 -155.846018)
		(end 405.354282 -155.846018)
		(stroke
			(width 0.2)
			(type default)
		)
		(fill no)
		(layer "In5.Cu")
	)
	(gr_circle
		(center 404.141178 -153.846022)
		(end 405.354282 -153.846022)
		(stroke
			(width 0.2)
			(type default)
		)
		(fill no)
		(layer "In5.Cu")
	)
	(gr_circle
		(center 405.11222 -29.21)
		(end 406.00122 -29.21)
		(stroke
			(width 0.2)
			(type default)
		)
		(fill no)
		(layer "In5.Cu")
	)
	(gr_circle
		(center 405.125174 -168.82999)
		(end 406.338278 -168.82999)
		(stroke
			(width 0.2)
			(type default)
		)
		(fill no)
		(layer "In5.Cu")
	)
	(gr_circle
		(center 405.125174 -166.829994)
		(end 406.338278 -166.829994)
		(stroke
			(width 0.2)
			(type default)
		)
		(fill no)
		(layer "In5.Cu")
	)
	(gr_circle
		(center 405.125174 -164.829998)
		(end 406.338278 -164.829998)
		(stroke
			(width 0.2)
			(type default)
		)
		(fill no)
		(layer "In5.Cu")
	)
	(gr_circle
		(center 405.125174 -162.830002)
		(end 406.338278 -162.830002)
		(stroke
			(width 0.2)
			(type default)
		)
		(fill no)
		(layer "In5.Cu")
	)
	(gr_circle
		(center 405.125174 -160.830006)
		(end 406.338278 -160.830006)
		(stroke
			(width 0.2)
			(type default)
		)
		(fill no)
		(layer "In5.Cu")
	)
	(gr_circle
		(center 405.125174 -158.83001)
		(end 406.338278 -158.83001)
		(stroke
			(width 0.2)
			(type default)
		)
		(fill no)
		(layer "In5.Cu")
	)
	(gr_circle
		(center 405.125174 -156.830014)
		(end 406.338278 -156.830014)
		(stroke
			(width 0.2)
			(type default)
		)
		(fill no)
		(layer "In5.Cu")
	)
	(gr_circle
		(center 405.125174 -154.830018)
		(end 406.338278 -154.830018)
		(stroke
			(width 0.2)
			(type default)
		)
		(fill no)
		(layer "In5.Cu")
	)
	(gr_circle
		(center 405.125174 -152.830022)
		(end 406.338278 -152.830022)
		(stroke
			(width 0.2)
			(type default)
		)
		(fill no)
		(layer "In5.Cu")
	)
	(gr_circle
		(center 405.538178 -169.97299)
		(end 406.751282 -169.97299)
		(stroke
			(width 0.2)
			(type default)
		)
		(fill no)
		(layer "In5.Cu")
	)
	(gr_line
		(start 405.6634 -77.597)
		(end 402.1074 -74.041)
		(stroke
			(width 1.016)
			(type default)
		)
		(layer "In5.Cu")
	)
	(gr_circle
		(center 405.6634 -36.83)
		(end 406.5524 -36.83)
		(stroke
			(width 0.2)
			(type default)
		)
		(fill no)
		(layer "In5.Cu")
	)
	(gr_circle
		(center 405.6634 -32.004)
		(end 406.5524 -32.004)
		(stroke
			(width 0.2)
			(type default)
		)
		(fill no)
		(layer "In5.Cu")
	)
	(gr_circle
		(center 406.9334 -22.606)
		(end 407.8224 -22.606)
		(stroke
			(width 0.2)
			(type default)
		)
		(fill no)
		(layer "In5.Cu")
	)
	(gr_circle
		(center 406.9334 -21.717)
		(end 407.8224 -21.717)
		(stroke
			(width 0.2)
			(type default)
		)
		(fill no)
		(layer "In5.Cu")
	)
	(gr_circle
		(center 406.9334 -20.828)
		(end 407.8224 -20.828)
		(stroke
			(width 0.2)
			(type default)
		)
		(fill no)
		(layer "In5.Cu")
	)
	(gr_circle
		(center 406.9334 -17.653)
		(end 407.8224 -17.653)
		(stroke
			(width 0.2)
			(type default)
		)
		(fill no)
		(layer "In5.Cu")
	)
	(gr_circle
		(center 406.9334 -16.764)
		(end 407.8224 -16.764)
		(stroke
			(width 0.2)
			(type default)
		)
		(fill no)
		(layer "In5.Cu")
	)
	(gr_circle
		(center 406.9334 -15.875)
		(end 407.8224 -15.875)
		(stroke
			(width 0.2)
			(type default)
		)
		(fill no)
		(layer "In5.Cu")
	)
	(gr_circle
		(center 407.9494 -22.606)
		(end 408.8384 -22.606)
		(stroke
			(width 0.2)
			(type default)
		)
		(fill no)
		(layer "In5.Cu")
	)
	(gr_circle
		(center 407.9494 -21.717)
		(end 408.8384 -21.717)
		(stroke
			(width 0.2)
			(type default)
		)
		(fill no)
		(layer "In5.Cu")
	)
	(gr_circle
		(center 407.9494 -20.828)
		(end 408.8384 -20.828)
		(stroke
			(width 0.2)
			(type default)
		)
		(fill no)
		(layer "In5.Cu")
	)
	(gr_circle
		(center 407.9494 -17.653)
		(end 408.8384 -17.653)
		(stroke
			(width 0.2)
			(type default)
		)
		(fill no)
		(layer "In5.Cu")
	)
	(gr_circle
		(center 407.9494 -16.764)
		(end 408.8384 -16.764)
		(stroke
			(width 0.2)
			(type default)
		)
		(fill no)
		(layer "In5.Cu")
	)
	(gr_circle
		(center 407.9494 -15.875)
		(end 408.8384 -15.875)
		(stroke
			(width 0.2)
			(type default)
		)
		(fill no)
		(layer "In5.Cu")
	)
	(gr_circle
		(center 408.7114 -22.606)
		(end 409.6004 -22.606)
		(stroke
			(width 0.2)
			(type default)
		)
		(fill no)
		(layer "In5.Cu")
	)
	(gr_circle
		(center 408.7114 -21.717)
		(end 409.6004 -21.717)
		(stroke
			(width 0.2)
			(type default)
		)
		(fill no)
		(layer "In5.Cu")
	)
	(gr_circle
		(center 408.7114 -20.828)
		(end 409.6004 -20.828)
		(stroke
			(width 0.2)
			(type default)
		)
		(fill no)
		(layer "In5.Cu")
	)
	(gr_circle
		(center 408.7114 -17.653)
		(end 409.6004 -17.653)
		(stroke
			(width 0.2)
			(type default)
		)
		(fill no)
		(layer "In5.Cu")
	)
	(gr_circle
		(center 408.7114 -16.764)
		(end 409.6004 -16.764)
		(stroke
			(width 0.2)
			(type default)
		)
		(fill no)
		(layer "In5.Cu")
	)
	(gr_circle
		(center 408.7114 -15.875)
		(end 409.6004 -15.875)
		(stroke
			(width 0.2)
			(type default)
		)
		(fill no)
		(layer "In5.Cu")
	)
	(gr_line
		(start 408.999944 -163.299902)
		(end 408.999944 -166.649908)
		(stroke
			(width 2.032)
			(type default)
		)
		(layer "In5.Cu")
	)
	(gr_circle
		(center 409.9814 -33.02)
		(end 410.8704 -33.02)
		(stroke
			(width 0.2)
			(type default)
		)
		(fill no)
		(layer "In5.Cu")
	)
	(gr_circle
		(center 409.9814 -31.75)
		(end 410.8704 -31.75)
		(stroke
			(width 0.2)
			(type default)
		)
		(fill no)
		(layer "In5.Cu")
	)
	(gr_circle
		(center 409.9814 -30.48)
		(end 410.8704 -30.48)
		(stroke
			(width 0.2)
			(type default)
		)
		(fill no)
		(layer "In5.Cu")
	)
	(gr_circle
		(center 409.9814 -29.21)
		(end 410.8704 -29.21)
		(stroke
			(width 0.2)
			(type default)
		)
		(fill no)
		(layer "In5.Cu")
	)
	(gr_circle
		(center 409.9814 -27.94)
		(end 410.8704 -27.94)
		(stroke
			(width 0.2)
			(type default)
		)
		(fill no)
		(layer "In5.Cu")
	)
	(gr_circle
		(center 410.4132 -21.0058)
		(end 411.3022 -21.0058)
		(stroke
			(width 0.2)
			(type default)
		)
		(fill no)
		(layer "In5.Cu")
	)
	(gr_circle
		(center 410.4132 -20.2438)
		(end 411.3022 -20.2438)
		(stroke
			(width 0.2)
			(type default)
		)
		(fill no)
		(layer "In5.Cu")
	)
	(gr_circle
		(center 410.4132 -19.4818)
		(end 411.3022 -19.4818)
		(stroke
			(width 0.2)
			(type default)
		)
		(fill no)
		(layer "In5.Cu")
	)
	(gr_circle
		(center 410.9974 -37.82695)
		(end 411.8864 -37.82695)
		(stroke
			(width 0.2)
			(type default)
		)
		(fill no)
		(layer "In5.Cu")
	)
	(gr_circle
		(center 411.1752 -21.0058)
		(end 412.0642 -21.0058)
		(stroke
			(width 0.2)
			(type default)
		)
		(fill no)
		(layer "In5.Cu")
	)
	(gr_circle
		(center 411.1752 -20.2438)
		(end 412.0642 -20.2438)
		(stroke
			(width 0.2)
			(type default)
		)
		(fill no)
		(layer "In5.Cu")
	)
	(gr_circle
		(center 411.1752 -19.4818)
		(end 412.0642 -19.4818)
		(stroke
			(width 0.2)
			(type default)
		)
		(fill no)
		(layer "In5.Cu")
	)
	(gr_circle
		(center 412.0134 -39.606474)
		(end 412.9024 -39.606474)
		(stroke
			(width 0.2)
			(type default)
		)
		(fill no)
		(layer "In5.Cu")
	)
	(gr_circle
		(center 412.06293 -30.21076)
		(end 412.95193 -30.21076)
		(stroke
			(width 0.2)
			(type default)
		)
		(fill no)
		(layer "In5.Cu")
	)
	(gr_circle
		(center 412.06293 -29.19476)
		(end 412.95193 -29.19476)
		(stroke
			(width 0.2)
			(type default)
		)
		(fill no)
		(layer "In5.Cu")
	)
	(gr_circle
		(center 412.2674 -45.212)
		(end 413.1564 -45.212)
		(stroke
			(width 0.2)
			(type default)
		)
		(fill no)
		(layer "In5.Cu")
	)
	(gr_circle
		(center 412.2674 -43.815)
		(end 413.1564 -43.815)
		(stroke
			(width 0.2)
			(type default)
		)
		(fill no)
		(layer "In5.Cu")
	)
	(gr_circle
		(center 412.496 -48.006)
		(end 413.385 -48.006)
		(stroke
			(width 0.2)
			(type default)
		)
		(fill no)
		(layer "In5.Cu")
	)
	(gr_circle
		(center 412.623 -44.45)
		(end 413.512 -44.45)
		(stroke
			(width 0.2)
			(type default)
		)
		(fill no)
		(layer "In5.Cu")
	)
	(gr_circle
		(center 412.623 -37.084)
		(end 413.512 -37.084)
		(stroke
			(width 0.2)
			(type default)
		)
		(fill no)
		(layer "In5.Cu")
	)
	(gr_circle
		(center 412.623 -36.195)
		(end 413.512 -36.195)
		(stroke
			(width 0.2)
			(type default)
		)
		(fill no)
		(layer "In5.Cu")
	)
	(gr_circle
		(center 412.84398 -26.40076)
		(end 413.73298 -26.40076)
		(stroke
			(width 0.2)
			(type default)
		)
		(fill no)
		(layer "In5.Cu")
	)
	(gr_circle
		(center 413.004 -42.545)
		(end 413.893 -42.545)
		(stroke
			(width 0.2)
			(type default)
		)
		(fill no)
		(layer "In5.Cu")
	)
	(gr_circle
		(center 413.004 -41.529)
		(end 413.893 -41.529)
		(stroke
			(width 0.2)
			(type default)
		)
		(fill no)
		(layer "In5.Cu")
	)
	(gr_circle
		(center 413.23895 -39.624)
		(end 414.12795 -39.624)
		(stroke
			(width 0.2)
			(type default)
		)
		(fill no)
		(layer "In5.Cu")
	)
	(gr_circle
		(center 413.766 -44.45)
		(end 414.655 -44.45)
		(stroke
			(width 0.2)
			(type default)
		)
		(fill no)
		(layer "In5.Cu")
	)
	(gr_circle
		(center 413.83458 -26.47696)
		(end 414.72358 -26.47696)
		(stroke
			(width 0.2)
			(type default)
		)
		(fill no)
		(layer "In5.Cu")
	)
	(gr_arc
		(start 413.999934 -158.299912)
		(mid 410.464407 -159.764375)
		(end 408.999944 -163.299902)
		(stroke
			(width 2.032)
			(type default)
		)
		(layer "In5.Cu")
	)
	(gr_circle
		(center 414.356042 -29.24556)
		(end 415.245042 -29.24556)
		(stroke
			(width 0.2)
			(type default)
		)
		(fill no)
		(layer "In5.Cu")
	)
	(gr_circle
		(center 414.42259 -47.949358)
		(end 415.31159 -47.949358)
		(stroke
			(width 0.2)
			(type default)
		)
		(fill no)
		(layer "In5.Cu")
	)
	(gr_circle
		(center 414.613344 -27.715718)
		(end 415.502344 -27.715718)
		(stroke
			(width 0.2)
			(type default)
		)
		(fill no)
		(layer "In5.Cu")
	)
	(gr_circle
		(center 415.29 -38.84295)
		(end 416.179 -38.84295)
		(stroke
			(width 0.2)
			(type default)
		)
		(fill no)
		(layer "In5.Cu")
	)
	(gr_circle
		(center 415.6964 -44.069)
		(end 416.5854 -44.069)
		(stroke
			(width 0.2)
			(type default)
		)
		(fill no)
		(layer "In5.Cu")
	)
	(gr_circle
		(center 416.188398 -26.450036)
		(end 417.077398 -26.450036)
		(stroke
			(width 0.2)
			(type default)
		)
		(fill no)
		(layer "In5.Cu")
	)
	(gr_circle
		(center 416.231578 -33.770316)
		(end 417.120578 -33.770316)
		(stroke
			(width 0.2)
			(type default)
		)
		(fill no)
		(layer "In5.Cu")
	)
	(gr_circle
		(center 416.400488 -29.0703)
		(end 417.264088 -29.0703)
		(stroke
			(width 0.2)
			(type default)
		)
		(fill no)
		(layer "In5.Cu")
	)
	(gr_circle
		(center 416.400488 -28.4353)
		(end 417.264088 -28.4353)
		(stroke
			(width 0.2)
			(type default)
		)
		(fill no)
		(layer "In5.Cu")
	)
	(gr_circle
		(center 416.569398 -25.764236)
		(end 417.458398 -25.764236)
		(stroke
			(width 0.2)
			(type default)
		)
		(fill no)
		(layer "In5.Cu")
	)
	(gr_circle
		(center 417.050728 -31.234126)
		(end 417.939728 -31.234126)
		(stroke
			(width 0.2)
			(type default)
		)
		(fill no)
		(layer "In5.Cu")
	)
	(gr_circle
		(center 417.068 -46.863)
		(end 417.957 -46.863)
		(stroke
			(width 0.2)
			(type default)
		)
		(fill no)
		(layer "In5.Cu")
	)
	(gr_circle
		(center 417.077398 -26.450036)
		(end 417.966398 -26.450036)
		(stroke
			(width 0.2)
			(type default)
		)
		(fill no)
		(layer "In5.Cu")
	)
	(gr_line
		(start 417.086034 -158.284164)
		(end 418.593016 -156.777182)
		(stroke
			(width 1.016)
			(type default)
		)
		(layer "In5.Cu")
	)
	(gr_circle
		(center 417.30041 -29.0703)
		(end 418.16401 -29.0703)
		(stroke
			(width 0.2)
			(type default)
		)
		(fill no)
		(layer "In5.Cu")
	)
	(gr_circle
		(center 417.30041 -28.4353)
		(end 418.16401 -28.4353)
		(stroke
			(width 0.2)
			(type default)
		)
		(fill no)
		(layer "In5.Cu")
	)
	(gr_circle
		(center 417.458398 -25.764236)
		(end 418.347398 -25.764236)
		(stroke
			(width 0.2)
			(type default)
		)
		(fill no)
		(layer "In5.Cu")
	)
	(gr_circle
		(center 417.808918 -31.643574)
		(end 418.697918 -31.643574)
		(stroke
			(width 0.2)
			(type default)
		)
		(fill no)
		(layer "In5.Cu")
	)
	(gr_circle
		(center 417.83 -46.863)
		(end 418.719 -46.863)
		(stroke
			(width 0.2)
			(type default)
		)
		(fill no)
		(layer "In5.Cu")
	)
	(gr_circle
		(center 417.966398 -26.450036)
		(end 418.855398 -26.450036)
		(stroke
			(width 0.2)
			(type default)
		)
		(fill no)
		(layer "In5.Cu")
	)
	(gr_circle
		(center 418.200332 -29.0703)
		(end 419.063932 -29.0703)
		(stroke
			(width 0.2)
			(type default)
		)
		(fill no)
		(layer "In5.Cu")
	)
	(gr_circle
		(center 418.200332 -28.4353)
		(end 419.063932 -28.4353)
		(stroke
			(width 0.2)
			(type default)
		)
		(fill no)
		(layer "In5.Cu")
	)
	(gr_circle
		(center 418.347398 -25.764236)
		(end 419.236398 -25.764236)
		(stroke
			(width 0.2)
			(type default)
		)
		(fill no)
		(layer "In5.Cu")
	)
	(gr_circle
		(center 418.5412 -21.1328)
		(end 419.4302 -21.1328)
		(stroke
			(width 0.2)
			(type default)
		)
		(fill no)
		(layer "In5.Cu")
	)
	(gr_circle
		(center 418.5412 -20.3708)
		(end 419.4302 -20.3708)
		(stroke
			(width 0.2)
			(type default)
		)
		(fill no)
		(layer "In5.Cu")
	)
	(gr_circle
		(center 418.5412 -19.6088)
		(end 419.4302 -19.6088)
		(stroke
			(width 0.2)
			(type default)
		)
		(fill no)
		(layer "In5.Cu")
	)
	(gr_circle
		(center 418.550598 -30.940248)
		(end 419.439598 -30.940248)
		(stroke
			(width 0.2)
			(type default)
		)
		(fill no)
		(layer "In5.Cu")
	)
	(gr_line
		(start 418.593016 -156.777182)
		(end 420.117016 -158.301182)
		(stroke
			(width 1.016)
			(type default)
		)
		(layer "In5.Cu")
	)
	(gr_line
		(start 418.593016 -77.6478)
		(end 418.593016 -158.26867)
		(stroke
			(width 1.016)
			(type default)
		)
		(layer "In5.Cu")
	)
	(gr_circle
		(center 418.896038 -33.76041)
		(end 419.785038 -33.76041)
		(stroke
			(width 0.2)
			(type default)
		)
		(fill no)
		(layer "In5.Cu")
	)
	(gr_circle
		(center 418.973 -44.043092)
		(end 419.862 -44.043092)
		(stroke
			(width 0.2)
			(type default)
		)
		(fill no)
		(layer "In5.Cu")
	)
	(gr_circle
		(center 419.100508 -29.0703)
		(end 419.964108 -29.0703)
		(stroke
			(width 0.2)
			(type default)
		)
		(fill no)
		(layer "In5.Cu")
	)
	(gr_circle
		(center 419.100508 -28.4353)
		(end 419.964108 -28.4353)
		(stroke
			(width 0.2)
			(type default)
		)
		(fill no)
		(layer "In5.Cu")
	)
	(gr_circle
		(center 419.129718 -45.72)
		(end 420.018718 -45.72)
		(stroke
			(width 0.2)
			(type default)
		)
		(fill no)
		(layer "In5.Cu")
	)
	(gr_circle
		(center 419.35146 -30.996636)
		(end 420.24046 -30.996636)
		(stroke
			(width 0.2)
			(type default)
		)
		(fill no)
		(layer "In5.Cu")
	)
	(gr_circle
		(center 419.363398 -25.332436)
		(end 420.252398 -25.332436)
		(stroke
			(width 0.2)
			(type default)
		)
		(fill no)
		(layer "In5.Cu")
	)
	(gr_circle
		(center 419.43655 -31.769304)
		(end 420.32555 -31.769304)
		(stroke
			(width 0.2)
			(type default)
		)
		(fill no)
		(layer "In5.Cu")
	)
	(gr_circle
		(center 419.7604 -53.848)
		(end 420.6494 -53.848)
		(stroke
			(width 0.2)
			(type default)
		)
		(fill no)
		(layer "In5.Cu")
	)
	(gr_circle
		(center 420.116 -48.895)
		(end 421.005 -48.895)
		(stroke
			(width 0.2)
			(type default)
		)
		(fill no)
		(layer "In5.Cu")
	)
	(gr_circle
		(center 420.790878 -32.35071)
		(end 421.679878 -32.35071)
		(stroke
			(width 0.2)
			(type default)
		)
		(fill no)
		(layer "In5.Cu")
	)
	(gr_circle
		(center 420.8907 -29.65704)
		(end 421.7797 -29.65704)
		(stroke
			(width 0.2)
			(type default)
		)
		(fill no)
		(layer "In5.Cu")
	)
	(gr_circle
		(center 420.8907 -28.92044)
		(end 421.7797 -28.92044)
		(stroke
			(width 0.2)
			(type default)
		)
		(fill no)
		(layer "In5.Cu")
	)
	(gr_circle
		(center 420.8907 -26.00452)
		(end 421.7797 -26.00452)
		(stroke
			(width 0.2)
			(type default)
		)
		(fill no)
		(layer "In5.Cu")
	)
	(gr_circle
		(center 421.005 -48.641)
		(end 421.894 -48.641)
		(stroke
			(width 0.2)
			(type default)
		)
		(fill no)
		(layer "In5.Cu")
	)
	(gr_circle
		(center 421.132 -45.593)
		(end 422.021 -45.593)
		(stroke
			(width 0.2)
			(type default)
		)
		(fill no)
		(layer "In5.Cu")
	)
	(gr_circle
		(center 421.259 -35.052)
		(end 422.148 -35.052)
		(stroke
			(width 0.2)
			(type default)
		)
		(fill no)
		(layer "In5.Cu")
	)
	(gr_circle
		(center 421.64 -49.149)
		(end 422.529 -49.149)
		(stroke
			(width 0.2)
			(type default)
		)
		(fill no)
		(layer "In5.Cu")
	)
	(gr_circle
		(center 421.7035 -29.65704)
		(end 422.5925 -29.65704)
		(stroke
			(width 0.2)
			(type default)
		)
		(fill no)
		(layer "In5.Cu")
	)
	(gr_circle
		(center 421.7035 -28.92044)
		(end 422.5925 -28.92044)
		(stroke
			(width 0.2)
			(type default)
		)
		(fill no)
		(layer "In5.Cu")
	)
	(gr_circle
		(center 422.021 -50.546)
		(end 422.91 -50.546)
		(stroke
			(width 0.2)
			(type default)
		)
		(fill no)
		(layer "In5.Cu")
	)
	(gr_circle
		(center 422.148 -26.924)
		(end 423.037 -26.924)
		(stroke
			(width 0.2)
			(type default)
		)
		(fill no)
		(layer "In5.Cu")
	)
	(gr_circle
		(center 422.656 -51.435)
		(end 423.545 -51.435)
		(stroke
			(width 0.2)
			(type default)
		)
		(fill no)
		(layer "In5.Cu")
	)
	(gr_line
		(start 422.674542 -11.651742)
		(end 428.285656 -17.262856)
		(stroke
			(width 1.016)
			(type default)
		)
		(layer "In5.Cu")
	)
	(gr_line
		(start 422.674542 -1.491488)
		(end 421.150542 0.032512)
		(stroke
			(width 1.524)
			(type default)
		)
		(layer "In5.Cu")
	)
	(gr_line
		(start 422.674542 0)
		(end 422.674542 -11.651742)
		(stroke
			(width 1.016)
			(type default)
		)
		(layer "In5.Cu")
	)
	(gr_circle
		(center 423.418 -35.052)
		(end 424.307 -35.052)
		(stroke
			(width 0.2)
			(type default)
		)
		(fill no)
		(layer "In5.Cu")
	)
	(gr_circle
		(center 423.5704 -50.419)
		(end 424.4594 -50.419)
		(stroke
			(width 0.2)
			(type default)
		)
		(fill no)
		(layer "In5.Cu")
	)
	(gr_circle
		(center 423.69105 -48.133)
		(end 424.58005 -48.133)
		(stroke
			(width 0.2)
			(type default)
		)
		(fill no)
		(layer "In5.Cu")
	)
	(gr_circle
		(center 424.1292 -30.5816)
		(end 425.0182 -30.5816)
		(stroke
			(width 0.2)
			(type default)
		)
		(fill no)
		(layer "In5.Cu")
	)
	(gr_line
		(start 424.181524 0.015494)
		(end 422.674542 -1.491488)
		(stroke
			(width 1.524)
			(type default)
		)
		(layer "In5.Cu")
	)
	(gr_circle
		(center 424.7007 -46.1137)
		(end 425.5897 -46.1137)
		(stroke
			(width 0.2)
			(type default)
		)
		(fill no)
		(layer "In5.Cu")
	)
	(gr_circle
		(center 424.8912 -30.5816)
		(end 425.7802 -30.5816)
		(stroke
			(width 0.2)
			(type default)
		)
		(fill no)
		(layer "In5.Cu")
	)
	(gr_circle
		(center 425.6532 -30.5816)
		(end 426.5422 -30.5816)
		(stroke
			(width 0.2)
			(type default)
		)
		(fill no)
		(layer "In5.Cu")
	)
	(gr_circle
		(center 425.7929 -40.703754)
		(end 426.6819 -40.703754)
		(stroke
			(width 0.2)
			(type default)
		)
		(fill no)
		(layer "In5.Cu")
	)
	(gr_circle
		(center 426.510704 -49.46904)
		(end 427.399704 -49.46904)
		(stroke
			(width 0.2)
			(type default)
		)
		(fill no)
		(layer "In5.Cu")
	)
	(gr_circle
		(center 426.72 -39.751)
		(end 427.609 -39.751)
		(stroke
			(width 0.2)
			(type default)
		)
		(fill no)
		(layer "In5.Cu")
	)
	(gr_circle
		(center 427.355 -30.94355)
		(end 428.244 -30.94355)
		(stroke
			(width 0.2)
			(type default)
		)
		(fill no)
		(layer "In5.Cu")
	)
	(gr_circle
		(center 427.856904 -39.751)
		(end 428.745904 -39.751)
		(stroke
			(width 0.2)
			(type default)
		)
		(fill no)
		(layer "In5.Cu")
	)
	(gr_circle
		(center 427.99 -33.782)
		(end 428.879 -33.782)
		(stroke
			(width 0.2)
			(type default)
		)
		(fill no)
		(layer "In5.Cu")
	)
	(gr_circle
		(center 428.0154 -32.385)
		(end 428.9044 -32.385)
		(stroke
			(width 0.2)
			(type default)
		)
		(fill no)
		(layer "In5.Cu")
	)
	(gr_circle
		(center 428.23765 -47.371)
		(end 429.12665 -47.371)
		(stroke
			(width 0.2)
			(type default)
		)
		(fill no)
		(layer "In5.Cu")
	)
	(gr_circle
		(center 428.237904 -45.974)
		(end 429.126904 -45.974)
		(stroke
			(width 0.2)
			(type default)
		)
		(fill no)
		(layer "In5.Cu")
	)
	(gr_circle
		(center 428.237904 -44.577)
		(end 429.126904 -44.577)
		(stroke
			(width 0.2)
			(type default)
		)
		(fill no)
		(layer "In5.Cu")
	)
	(gr_circle
		(center 428.237904 -43.18)
		(end 429.126904 -43.18)
		(stroke
			(width 0.2)
			(type default)
		)
		(fill no)
		(layer "In5.Cu")
	)
	(gr_circle
		(center 428.237904 -41.783)
		(end 429.126904 -41.783)
		(stroke
			(width 0.2)
			(type default)
		)
		(fill no)
		(layer "In5.Cu")
	)
	(gr_circle
		(center 428.237904 -40.386)
		(end 429.126904 -40.386)
		(stroke
			(width 0.2)
			(type default)
		)
		(fill no)
		(layer "In5.Cu")
	)
	(gr_circle
		(center 428.237904 -38.989)
		(end 429.126904 -38.989)
		(stroke
			(width 0.2)
			(type default)
		)
		(fill no)
		(layer "In5.Cu")
	)
	(gr_circle
		(center 428.237904 -37.592)
		(end 429.126904 -37.592)
		(stroke
			(width 0.2)
			(type default)
		)
		(fill no)
		(layer "In5.Cu")
	)
	(gr_circle
		(center 428.7774 -46.79188)
		(end 429.6664 -46.79188)
		(stroke
			(width 0.2)
			(type default)
		)
		(fill no)
		(layer "In5.Cu")
	)
	(gr_circle
		(center 428.7774 -43.95724)
		(end 429.6664 -43.95724)
		(stroke
			(width 0.2)
			(type default)
		)
		(fill no)
		(layer "In5.Cu")
	)
	(gr_circle
		(center 428.7774 -41.16324)
		(end 429.6664 -41.16324)
		(stroke
			(width 0.2)
			(type default)
		)
		(fill no)
		(layer "In5.Cu")
	)
	(gr_circle
		(center 428.7774 -36.97224)
		(end 429.6664 -36.97224)
		(stroke
			(width 0.2)
			(type default)
		)
		(fill no)
		(layer "In5.Cu")
	)
	(gr_circle
		(center 429.2854 -32.35325)
		(end 430.1744 -32.35325)
		(stroke
			(width 0.2)
			(type default)
		)
		(fill no)
		(layer "In5.Cu")
	)
	(gr_circle
		(center 429.768 -19.44878)
		(end 430.657 -19.44878)
		(stroke
			(width 0.2)
			(type default)
		)
		(fill no)
		(layer "In5.Cu")
	)
	(gr_circle
		(center 429.9204 -34.53765)
		(end 430.8094 -34.53765)
		(stroke
			(width 0.2)
			(type default)
		)
		(fill no)
		(layer "In5.Cu")
	)
	(gr_circle
		(center 430.657 -19.431)
		(end 431.546 -19.431)
		(stroke
			(width 0.2)
			(type default)
		)
		(fill no)
		(layer "In5.Cu")
	)
	(gr_circle
		(center 430.9364 -30.226)
		(end 431.8254 -30.226)
		(stroke
			(width 0.2)
			(type default)
		)
		(fill no)
		(layer "In5.Cu")
	)
	(gr_circle
		(center 431.28565 -45.974)
		(end 432.17465 -45.974)
		(stroke
			(width 0.2)
			(type default)
		)
		(fill no)
		(layer "In5.Cu")
	)
	(gr_circle
		(center 431.285904 -44.577)
		(end 432.174904 -44.577)
		(stroke
			(width 0.2)
			(type default)
		)
		(fill no)
		(layer "In5.Cu")
	)
	(gr_circle
		(center 431.285904 -43.18)
		(end 432.174904 -43.18)
		(stroke
			(width 0.2)
			(type default)
		)
		(fill no)
		(layer "In5.Cu")
	)
	(gr_circle
		(center 431.285904 -41.783)
		(end 432.174904 -41.783)
		(stroke
			(width 0.2)
			(type default)
		)
		(fill no)
		(layer "In5.Cu")
	)
	(gr_circle
		(center 431.285904 -40.386)
		(end 432.174904 -40.386)
		(stroke
			(width 0.2)
			(type default)
		)
		(fill no)
		(layer "In5.Cu")
	)
	(gr_circle
		(center 431.285904 -38.989)
		(end 432.174904 -38.989)
		(stroke
			(width 0.2)
			(type default)
		)
		(fill no)
		(layer "In5.Cu")
	)
	(gr_circle
		(center 431.285904 -37.592)
		(end 432.174904 -37.592)
		(stroke
			(width 0.2)
			(type default)
		)
		(fill no)
		(layer "In5.Cu")
	)
	(gr_circle
		(center 432.054 -41.783)
		(end 432.943 -41.783)
		(stroke
			(width 0.2)
			(type default)
		)
		(fill no)
		(layer "In5.Cu")
	)
	(gr_circle
		(center 432.054 -40.386)
		(end 432.943 -40.386)
		(stroke
			(width 0.2)
			(type default)
		)
		(fill no)
		(layer "In5.Cu")
	)
	(gr_circle
		(center 432.0794 -46.228)
		(end 432.9684 -46.228)
		(stroke
			(width 0.2)
			(type default)
		)
		(fill no)
		(layer "In5.Cu")
	)
	(gr_circle
		(center 432.0794 -45.339)
		(end 432.9684 -45.339)
		(stroke
			(width 0.2)
			(type default)
		)
		(fill no)
		(layer "In5.Cu")
	)
	(gr_circle
		(center 432.1429 -29.0195)
		(end 433.0319 -29.0195)
		(stroke
			(width 0.2)
			(type default)
		)
		(fill no)
		(layer "In5.Cu")
	)
	(gr_circle
		(center 432.32705 -52.197)
		(end 433.21605 -52.197)
		(stroke
			(width 0.2)
			(type default)
		)
		(fill no)
		(layer "In5.Cu")
	)
	(gr_circle
		(center 432.44135 -32.893)
		(end 433.33035 -32.893)
		(stroke
			(width 0.2)
			(type default)
		)
		(fill no)
		(layer "In5.Cu")
	)
	(gr_circle
		(center 432.4604 -43.561)
		(end 433.3494 -43.561)
		(stroke
			(width 0.2)
			(type default)
		)
		(fill no)
		(layer "In5.Cu")
	)
	(gr_circle
		(center 432.9684 -51.181)
		(end 433.8574 -51.181)
		(stroke
			(width 0.2)
			(type default)
		)
		(fill no)
		(layer "In5.Cu")
	)
	(gr_circle
		(center 433.0954 -35.687)
		(end 433.9844 -35.687)
		(stroke
			(width 0.2)
			(type default)
		)
		(fill no)
		(layer "In5.Cu")
	)
	(gr_circle
		(center 433.3494 -23.368)
		(end 434.2384 -23.368)
		(stroke
			(width 0.2)
			(type default)
		)
		(fill no)
		(layer "In5.Cu")
	)
	(gr_circle
		(center 433.4764 -47.371)
		(end 434.3654 -47.371)
		(stroke
			(width 0.2)
			(type default)
		)
		(fill no)
		(layer "In5.Cu")
	)
	(gr_circle
		(center 433.6034 -36.195)
		(end 434.4924 -36.195)
		(stroke
			(width 0.2)
			(type default)
		)
		(fill no)
		(layer "In5.Cu")
	)
	(gr_circle
		(center 434.2384 -40.132)
		(end 435.1274 -40.132)
		(stroke
			(width 0.2)
			(type default)
		)
		(fill no)
		(layer "In5.Cu")
	)
	(gr_circle
		(center 434.60035 -47.498)
		(end 435.48935 -47.498)
		(stroke
			(width 0.2)
			(type default)
		)
		(fill no)
		(layer "In5.Cu")
	)
	(gr_circle
		(center 434.848 -38.862)
		(end 435.737 -38.862)
		(stroke
			(width 0.2)
			(type default)
		)
		(fill no)
		(layer "In5.Cu")
	)
	(gr_line
		(start 434.999892 -158.299912)
		(end 413.999934 -158.299912)
		(stroke
			(width 2.032)
			(type default)
		)
		(layer "In5.Cu")
	)
	(gr_arc
		(start 434.999892 -158.299912)
		(mid 438.535432 -156.835453)
		(end 439.999882 -153.299922)
		(stroke
			(width 2.032)
			(type default)
		)
		(layer "In5.Cu")
	)
	(gr_circle
		(center 435.235096 -30.353)
		(end 436.124096 -30.353)
		(stroke
			(width 0.2)
			(type default)
		)
		(fill no)
		(layer "In5.Cu")
	)
	(gr_circle
		(center 435.235096 -29.083)
		(end 436.124096 -29.083)
		(stroke
			(width 0.2)
			(type default)
		)
		(fill no)
		(layer "In5.Cu")
	)
	(gr_circle
		(center 435.235096 -27.813)
		(end 436.124096 -27.813)
		(stroke
			(width 0.2)
			(type default)
		)
		(fill no)
		(layer "In5.Cu")
	)
	(gr_circle
		(center 435.23535 -34.163)
		(end 436.12435 -34.163)
		(stroke
			(width 0.2)
			(type default)
		)
		(fill no)
		(layer "In5.Cu")
	)
	(gr_circle
		(center 435.23535 -32.893)
		(end 436.12435 -32.893)
		(stroke
			(width 0.2)
			(type default)
		)
		(fill no)
		(layer "In5.Cu")
	)
	(gr_line
		(start 435.235604 -17.262856)
		(end 428.285656 -17.262856)
		(stroke
			(width 1.016)
			(type default)
		)
		(layer "In5.Cu")
	)
	(gr_circle
		(center 435.3814 -36.81095)
		(end 436.2704 -36.81095)
		(stroke
			(width 0.2)
			(type default)
		)
		(fill no)
		(layer "In5.Cu")
	)
	(gr_circle
		(center 435.40045 -47.498)
		(end 436.28945 -47.498)
		(stroke
			(width 0.2)
			(type default)
		)
		(fill no)
		(layer "In5.Cu")
	)
	(gr_circle
		(center 435.74335 -42.799)
		(end 436.63235 -42.799)
		(stroke
			(width 0.2)
			(type default)
		)
		(fill no)
		(layer "In5.Cu")
	)
	(gr_circle
		(center 435.74335 -38.862)
		(end 436.63235 -38.862)
		(stroke
			(width 0.2)
			(type default)
		)
		(fill no)
		(layer "In5.Cu")
	)
	(gr_circle
		(center 436.2704 -40.132)
		(end 437.1594 -40.132)
		(stroke
			(width 0.2)
			(type default)
		)
		(fill no)
		(layer "In5.Cu")
	)
	(gr_circle
		(center 436.54345 -25.146)
		(end 437.43245 -25.146)
		(stroke
			(width 0.2)
			(type default)
		)
		(fill no)
		(layer "In5.Cu")
	)
	(gr_circle
		(center 436.54345 -23.749)
		(end 437.43245 -23.749)
		(stroke
			(width 0.2)
			(type default)
		)
		(fill no)
		(layer "In5.Cu")
	)
	(gr_circle
		(center 436.54345 -22.352)
		(end 437.43245 -22.352)
		(stroke
			(width 0.2)
			(type default)
		)
		(fill no)
		(layer "In5.Cu")
	)
	(gr_circle
		(center 436.64505 -28.448)
		(end 437.53405 -28.448)
		(stroke
			(width 0.2)
			(type default)
		)
		(fill no)
		(layer "In5.Cu")
	)
	(gr_circle
		(center 436.64505 -27.182064)
		(end 437.53405 -27.182064)
		(stroke
			(width 0.2)
			(type default)
		)
		(fill no)
		(layer "In5.Cu")
	)
	(gr_circle
		(center 436.9054 -45.593)
		(end 437.7944 -45.593)
		(stroke
			(width 0.2)
			(type default)
		)
		(fill no)
		(layer "In5.Cu")
	)
	(gr_circle
		(center 437.013096 -44.45)
		(end 437.902096 -44.45)
		(stroke
			(width 0.2)
			(type default)
		)
		(fill no)
		(layer "In5.Cu")
	)
	(gr_circle
		(center 437.134 -36.20135)
		(end 438.023 -36.20135)
		(stroke
			(width 0.2)
			(type default)
		)
		(fill no)
		(layer "In5.Cu")
	)
	(gr_circle
		(center 437.261 -52.07)
		(end 438.15 -52.07)
		(stroke
			(width 0.2)
			(type default)
		)
		(fill no)
		(layer "In5.Cu")
	)
	(gr_circle
		(center 437.2864 -50.419)
		(end 438.1754 -50.419)
		(stroke
			(width 0.2)
			(type default)
		)
		(fill no)
		(layer "In5.Cu")
	)
	(gr_circle
		(center 437.2864 -49.46904)
		(end 438.1754 -49.46904)
		(stroke
			(width 0.2)
			(type default)
		)
		(fill no)
		(layer "In5.Cu")
	)
	(gr_circle
		(center 437.30799 -24.36876)
		(end 438.19699 -24.36876)
		(stroke
			(width 0.2)
			(type default)
		)
		(fill no)
		(layer "In5.Cu")
	)
	(gr_circle
		(center 437.404002 -39.868348)
		(end 438.293002 -39.868348)
		(stroke
			(width 0.2)
			(type default)
		)
		(fill no)
		(layer "In5.Cu")
	)
	(gr_circle
		(center 438.105296 -52.140104)
		(end 438.994296 -52.140104)
		(stroke
			(width 0.2)
			(type default)
		)
		(fill no)
		(layer "In5.Cu")
	)
	(gr_circle
		(center 438.429146 -38.862)
		(end 439.318146 -38.862)
		(stroke
			(width 0.2)
			(type default)
		)
		(fill no)
		(layer "In5.Cu")
	)
	(gr_circle
		(center 438.6834 -41.72712)
		(end 439.5724 -41.72712)
		(stroke
			(width 0.2)
			(type default)
		)
		(fill no)
		(layer "In5.Cu")
	)
	(gr_circle
		(center 438.7088 -26.543)
		(end 439.5978 -26.543)
		(stroke
			(width 0.2)
			(type default)
		)
		(fill no)
		(layer "In5.Cu")
	)
	(gr_circle
		(center 439.03265 -44.45)
		(end 439.92165 -44.45)
		(stroke
			(width 0.2)
			(type default)
		)
		(fill no)
		(layer "In5.Cu")
	)
	(gr_circle
		(center 439.166 -46.609)
		(end 440.055 -46.609)
		(stroke
			(width 0.2)
			(type default)
		)
		(fill no)
		(layer "In5.Cu")
	)
	(gr_circle
		(center 439.270394 -40.426894)
		(end 440.159394 -40.426894)
		(stroke
			(width 0.2)
			(type default)
		)
		(fill no)
		(layer "In5.Cu")
	)
	(gr_circle
		(center 439.270394 -36.489894)
		(end 440.159394 -36.489894)
		(stroke
			(width 0.2)
			(type default)
		)
		(fill no)
		(layer "In5.Cu")
	)
	(gr_circle
		(center 439.90895 -50.546)
		(end 440.79795 -50.546)
		(stroke
			(width 0.2)
			(type default)
		)
		(fill no)
		(layer "In5.Cu")
	)
	(gr_line
		(start 439.999882 -136.77011)
		(end 439.999882 -153.299922)
		(stroke
			(width 2.032)
			(type default)
		)
		(layer "In5.Cu")
	)
	(gr_arc
		(start 439.999882 -11.770106)
		(mid 441.464509 -15.305648)
		(end 445.000126 -16.770096)
		(stroke
			(width 2.032)
			(type default)
		)
		(layer "In5.Cu")
	)
	(gr_arc
		(start 439.999882 -4.99999)
		(mid 438.535415 -1.464472)
		(end 434.999892 0)
		(stroke
			(width 2.032)
			(type default)
		)
		(layer "In5.Cu")
	)
	(gr_line
		(start 439.999882 -4.99999)
		(end 439.999882 -11.770106)
		(stroke
			(width 2.032)
			(type default)
		)
		(layer "In5.Cu")
	)
	(gr_circle
		(center 440.309 -44.13504)
		(end 441.198 -44.13504)
		(stroke
			(width 0.2)
			(type default)
		)
		(fill no)
		(layer "In5.Cu")
	)
	(gr_circle
		(center 441.452 -31.623)
		(end 442.341 -31.623)
		(stroke
			(width 0.2)
			(type default)
		)
		(fill no)
		(layer "In5.Cu")
	)
	(gr_circle
		(center 441.63996 -48.641)
		(end 442.52896 -48.641)
		(stroke
			(width 0.2)
			(type default)
		)
		(fill no)
		(layer "In5.Cu")
	)
	(gr_circle
		(center 442.1124 -65.532)
		(end 443.0014 -65.532)
		(stroke
			(width 0.2)
			(type default)
		)
		(fill no)
		(layer "In5.Cu")
	)
	(gr_circle
		(center 442.1124 -64.897)
		(end 443.0014 -64.897)
		(stroke
			(width 0.2)
			(type default)
		)
		(fill no)
		(layer "In5.Cu")
	)
	(gr_circle
		(center 442.1124 -64.262)
		(end 443.0014 -64.262)
		(stroke
			(width 0.2)
			(type default)
		)
		(fill no)
		(layer "In5.Cu")
	)
	(gr_circle
		(center 442.1124 -63.627)
		(end 443.0014 -63.627)
		(stroke
			(width 0.2)
			(type default)
		)
		(fill no)
		(layer "In5.Cu")
	)
	(gr_circle
		(center 442.1124 -62.992)
		(end 443.0014 -62.992)
		(stroke
			(width 0.2)
			(type default)
		)
		(fill no)
		(layer "In5.Cu")
	)
	(gr_circle
		(center 442.1124 -61.087)
		(end 443.0014 -61.087)
		(stroke
			(width 0.2)
			(type default)
		)
		(fill no)
		(layer "In5.Cu")
	)
	(gr_circle
		(center 442.1124 -60.452)
		(end 443.0014 -60.452)
		(stroke
			(width 0.2)
			(type default)
		)
		(fill no)
		(layer "In5.Cu")
	)
	(gr_circle
		(center 442.1124 -59.817)
		(end 443.0014 -59.817)
		(stroke
			(width 0.2)
			(type default)
		)
		(fill no)
		(layer "In5.Cu")
	)
	(gr_circle
		(center 442.1124 -59.182)
		(end 443.0014 -59.182)
		(stroke
			(width 0.2)
			(type default)
		)
		(fill no)
		(layer "In5.Cu")
	)
	(gr_circle
		(center 443.484 -48.57496)
		(end 444.373 -48.57496)
		(stroke
			(width 0.2)
			(type default)
		)
		(fill no)
		(layer "In5.Cu")
	)
	(gr_circle
		(center 443.97295 -51.816)
		(end 444.86195 -51.816)
		(stroke
			(width 0.2)
			(type default)
		)
		(fill no)
		(layer "In5.Cu")
	)
	(gr_circle
		(center 444.643002 -50.292)
		(end 445.532002 -50.292)
		(stroke
			(width 0.2)
			(type default)
		)
		(fill no)
		(layer "In5.Cu")
	)
	(gr_circle
		(center 444.9064 -65.532)
		(end 445.7954 -65.532)
		(stroke
			(width 0.2)
			(type default)
		)
		(fill no)
		(layer "In5.Cu")
	)
	(gr_circle
		(center 444.9064 -64.897)
		(end 445.7954 -64.897)
		(stroke
			(width 0.2)
			(type default)
		)
		(fill no)
		(layer "In5.Cu")
	)
	(gr_circle
		(center 444.9064 -64.262)
		(end 445.7954 -64.262)
		(stroke
			(width 0.2)
			(type default)
		)
		(fill no)
		(layer "In5.Cu")
	)
	(gr_circle
		(center 444.9064 -63.627)
		(end 445.7954 -63.627)
		(stroke
			(width 0.2)
			(type default)
		)
		(fill no)
		(layer "In5.Cu")
	)
	(gr_circle
		(center 444.9064 -62.992)
		(end 445.7954 -62.992)
		(stroke
			(width 0.2)
			(type default)
		)
		(fill no)
		(layer "In5.Cu")
	)
	(gr_circle
		(center 444.9064 -61.087)
		(end 445.7954 -61.087)
		(stroke
			(width 0.2)
			(type default)
		)
		(fill no)
		(layer "In5.Cu")
	)
	(gr_circle
		(center 444.9064 -60.452)
		(end 445.7954 -60.452)
		(stroke
			(width 0.2)
			(type default)
		)
		(fill no)
		(layer "In5.Cu")
	)
	(gr_circle
		(center 444.9064 -59.817)
		(end 445.7954 -59.817)
		(stroke
			(width 0.2)
			(type default)
		)
		(fill no)
		(layer "In5.Cu")
	)
	(gr_circle
		(center 444.9064 -59.182)
		(end 445.7954 -59.182)
		(stroke
			(width 0.2)
			(type default)
		)
		(fill no)
		(layer "In5.Cu")
	)
	(gr_arc
		(start 445.000126 -131.77012)
		(mid 441.464509 -133.234568)
		(end 439.999882 -136.77011)
		(stroke
			(width 2.032)
			(type default)
		)
		(layer "In5.Cu")
	)
	(gr_line
		(start 445.000126 -16.770096)
		(end 471.000074 -16.770096)
		(stroke
			(width 2.032)
			(type default)
		)
		(layer "In5.Cu")
	)
	(gr_circle
		(center 445.58204 -47.56404)
		(end 446.47104 -47.56404)
		(stroke
			(width 0.2)
			(type default)
		)
		(fill no)
		(layer "In5.Cu")
	)
	(gr_circle
		(center 445.75095 -51.562)
		(end 446.63995 -51.562)
		(stroke
			(width 0.2)
			(type default)
		)
		(fill no)
		(layer "In5.Cu")
	)
	(gr_circle
		(center 446.9384 -29.083)
		(end 447.8274 -29.083)
		(stroke
			(width 0.2)
			(type default)
		)
		(fill no)
		(layer "In5.Cu")
	)
	(gr_circle
		(center 447.02095 -45.4406)
		(end 447.90995 -45.4406)
		(stroke
			(width 0.2)
			(type default)
		)
		(fill no)
		(layer "In5.Cu")
	)
	(gr_circle
		(center 447.4464 -31.629096)
		(end 448.3354 -31.629096)
		(stroke
			(width 0.2)
			(type default)
		)
		(fill no)
		(layer "In5.Cu")
	)
	(gr_circle
		(center 447.82105 -45.4406)
		(end 448.71005 -45.4406)
		(stroke
			(width 0.2)
			(type default)
		)
		(fill no)
		(layer "In5.Cu")
	)
	(gr_circle
		(center 448.03695 -43.429936)
		(end 448.92595 -43.429936)
		(stroke
			(width 0.2)
			(type default)
		)
		(fill no)
		(layer "In5.Cu")
	)
	(gr_circle
		(center 448.03695 -39.492936)
		(end 448.92595 -39.492936)
		(stroke
			(width 0.2)
			(type default)
		)
		(fill no)
		(layer "In5.Cu")
	)
	(gr_circle
		(center 448.056 -40.13835)
		(end 448.945 -40.13835)
		(stroke
			(width 0.2)
			(type default)
		)
		(fill no)
		(layer "In5.Cu")
	)
	(gr_circle
		(center 448.056 -36.20135)
		(end 448.945 -36.20135)
		(stroke
			(width 0.2)
			(type default)
		)
		(fill no)
		(layer "In5.Cu")
	)
	(gr_circle
		(center 448.0814 -30.353)
		(end 448.9704 -30.353)
		(stroke
			(width 0.2)
			(type default)
		)
		(fill no)
		(layer "In5.Cu")
	)
	(gr_circle
		(center 448.673728 -63.576454)
		(end 449.562728 -63.576454)
		(stroke
			(width 0.2)
			(type default)
		)
		(fill no)
		(layer "In5.Cu")
	)
	(gr_circle
		(center 448.673728 -62.814454)
		(end 449.562728 -62.814454)
		(stroke
			(width 0.2)
			(type default)
		)
		(fill no)
		(layer "In5.Cu")
	)
	(gr_circle
		(center 448.677538 -61.670692)
		(end 449.566538 -61.670692)
		(stroke
			(width 0.2)
			(type default)
		)
		(fill no)
		(layer "In5.Cu")
	)
	(gr_circle
		(center 448.677538 -60.908692)
		(end 449.566538 -60.908692)
		(stroke
			(width 0.2)
			(type default)
		)
		(fill no)
		(layer "In5.Cu")
	)
	(gr_circle
		(center 448.79895 -46.101)
		(end 449.68795 -46.101)
		(stroke
			(width 0.2)
			(type default)
		)
		(fill no)
		(layer "In5.Cu")
	)
	(gr_circle
		(center 448.83705 -39.492936)
		(end 449.72605 -39.492936)
		(stroke
			(width 0.2)
			(type default)
		)
		(fill no)
		(layer "In5.Cu")
	)
	(gr_circle
		(center 448.92595 -34.798)
		(end 449.81495 -34.798)
		(stroke
			(width 0.2)
			(type default)
		)
		(fill no)
		(layer "In5.Cu")
	)
	(gr_circle
		(center 449.072 -47.56404)
		(end 449.961 -47.56404)
		(stroke
			(width 0.2)
			(type default)
		)
		(fill no)
		(layer "In5.Cu")
	)
	(gr_circle
		(center 449.199 -40.13835)
		(end 450.088 -40.13835)
		(stroke
			(width 0.2)
			(type default)
		)
		(fill no)
		(layer "In5.Cu")
	)
	(gr_circle
		(center 449.199 -36.20135)
		(end 450.088 -36.20135)
		(stroke
			(width 0.2)
			(type default)
		)
		(fill no)
		(layer "In5.Cu")
	)
	(gr_circle
		(center 449.43395 -51.562)
		(end 450.32295 -51.562)
		(stroke
			(width 0.2)
			(type default)
		)
		(fill no)
		(layer "In5.Cu")
	)
	(gr_circle
		(center 449.446904 -42.799)
		(end 450.335904 -42.799)
		(stroke
			(width 0.2)
			(type default)
		)
		(fill no)
		(layer "In5.Cu")
	)
	(gr_circle
		(center 449.59905 -46.101)
		(end 450.48805 -46.101)
		(stroke
			(width 0.2)
			(type default)
		)
		(fill no)
		(layer "In5.Cu")
	)
	(gr_circle
		(center 449.72605 -34.798)
		(end 450.61505 -34.798)
		(stroke
			(width 0.2)
			(type default)
		)
		(fill no)
		(layer "In5.Cu")
	)
	(gr_circle
		(center 450.215 -44.196)
		(end 451.104 -44.196)
		(stroke
			(width 0.2)
			(type default)
		)
		(fill no)
		(layer "In5.Cu")
	)
	(gr_circle
		(center 450.2404 -45.0342)
		(end 451.1294 -45.0342)
		(stroke
			(width 0.2)
			(type default)
		)
		(fill no)
		(layer "In5.Cu")
	)
	(gr_circle
		(center 450.342 -40.132)
		(end 451.231 -40.132)
		(stroke
			(width 0.2)
			(type default)
		)
		(fill no)
		(layer "In5.Cu")
	)
	(gr_circle
		(center 450.342 -36.20135)
		(end 451.231 -36.20135)
		(stroke
			(width 0.2)
			(type default)
		)
		(fill no)
		(layer "In5.Cu")
	)
	(gr_circle
		(center 450.469 -32.893)
		(end 451.358 -32.893)
		(stroke
			(width 0.2)
			(type default)
		)
		(fill no)
		(layer "In5.Cu")
	)
	(gr_circle
		(center 450.959728 -63.590678)
		(end 451.848728 -63.590678)
		(stroke
			(width 0.2)
			(type default)
		)
		(fill no)
		(layer "In5.Cu")
	)
	(gr_circle
		(center 450.959728 -62.828678)
		(end 451.848728 -62.828678)
		(stroke
			(width 0.2)
			(type default)
		)
		(fill no)
		(layer "In5.Cu")
	)
	(gr_circle
		(center 450.963538 -61.670692)
		(end 451.852538 -61.670692)
		(stroke
			(width 0.2)
			(type default)
		)
		(fill no)
		(layer "In5.Cu")
	)
	(gr_circle
		(center 450.963538 -60.908692)
		(end 451.852538 -60.908692)
		(stroke
			(width 0.2)
			(type default)
		)
		(fill no)
		(layer "In5.Cu")
	)
	(gr_circle
		(center 451.612 -48.133)
		(end 452.501 -48.133)
		(stroke
			(width 0.2)
			(type default)
		)
		(fill no)
		(layer "In5.Cu")
	)
	(gr_line
		(start 452.8566 -77.597)
		(end 405.6634 -77.597)
		(stroke
			(width 1.016)
			(type default)
		)
		(layer "In5.Cu")
	)
	(gr_line
		(start 452.923148 -34.9504)
		(end 435.235604 -17.262856)
		(stroke
			(width 1.016)
			(type default)
		)
		(layer "In5.Cu")
	)
	(gr_line
		(start 452.923148 -34.9504)
		(end 460.502 -34.9504)
		(stroke
			(width 1.016)
			(type default)
		)
		(layer "In5.Cu")
	)
	(gr_circle
		(center 453.118728 -63.590678)
		(end 454.007728 -63.590678)
		(stroke
			(width 0.2)
			(type default)
		)
		(fill no)
		(layer "In5.Cu")
	)
	(gr_circle
		(center 453.118728 -62.828678)
		(end 454.007728 -62.828678)
		(stroke
			(width 0.2)
			(type default)
		)
		(fill no)
		(layer "In5.Cu")
	)
	(gr_circle
		(center 453.122538 -61.670692)
		(end 454.011538 -61.670692)
		(stroke
			(width 0.2)
			(type default)
		)
		(fill no)
		(layer "In5.Cu")
	)
	(gr_circle
		(center 453.122538 -60.908692)
		(end 454.011538 -60.908692)
		(stroke
			(width 0.2)
			(type default)
		)
		(fill no)
		(layer "In5.Cu")
	)
	(gr_circle
		(center 454.5584 -62.738)
		(end 455.4474 -62.738)
		(stroke
			(width 0.2)
			(type default)
		)
		(fill no)
		(layer "In5.Cu")
	)
	(gr_circle
		(center 454.5584 -61.849)
		(end 455.4474 -61.849)
		(stroke
			(width 0.2)
			(type default)
		)
		(fill no)
		(layer "In5.Cu")
	)
	(gr_circle
		(center 457.2254 -47.625)
		(end 458.1144 -47.625)
		(stroke
			(width 0.2)
			(type default)
		)
		(fill no)
		(layer "In5.Cu")
	)
	(gr_circle
		(center 459.6384 -49.53)
		(end 460.5274 -49.53)
		(stroke
			(width 0.2)
			(type default)
		)
		(fill no)
		(layer "In5.Cu")
	)
	(gr_circle
		(center 460.121 -47.244)
		(end 461.01 -47.244)
		(stroke
			(width 0.2)
			(type default)
		)
		(fill no)
		(layer "In5.Cu")
	)
	(gr_line
		(start 460.502 -34.9504)
		(end 466.979 -41.4274)
		(stroke
			(width 1.016)
			(type default)
		)
		(layer "In5.Cu")
	)
	(gr_circle
		(center 461.645 -47.752)
		(end 462.534 -47.752)
		(stroke
			(width 0.2)
			(type default)
		)
		(fill no)
		(layer "In5.Cu")
	)
	(gr_line
		(start 466.979 -66.3702)
		(end 468.0458 -67.437)
		(stroke
			(width 1.016)
			(type default)
		)
		(layer "In5.Cu")
	)
	(gr_line
		(start 466.979 -41.4274)
		(end 466.979 -66.3702)
		(stroke
			(width 1.016)
			(type default)
		)
		(layer "In5.Cu")
	)
	(gr_line
		(start 468.0458 -67.437)
		(end 472.6686 -67.437)
		(stroke
			(width 1.016)
			(type default)
		)
		(layer "In5.Cu")
	)
	(gr_line
		(start 471.000074 -131.77012)
		(end 445.000126 -131.77012)
		(stroke
			(width 2.032)
			(type default)
		)
		(layer "In5.Cu")
	)
	(gr_arc
		(start 471.000074 -131.77012)
		(mid 474.535718 -130.305578)
		(end 476.000064 -126.769876)
		(stroke
			(width 2.032)
			(type default)
		)
		(layer "In5.Cu")
	)
	(gr_line
		(start 472.6686 -77.597)
		(end 452.8566 -77.597)
		(stroke
			(width 1.016)
			(type default)
		)
		(layer "In5.Cu")
	)
	(gr_line
		(start 472.6686 -67.437)
		(end 473.3036 -68.072)
		(stroke
			(width 1.016)
			(type default)
		)
		(layer "In5.Cu")
	)
	(gr_line
		(start 473.3036 -76.962)
		(end 472.6686 -77.597)
		(stroke
			(width 1.016)
			(type default)
		)
		(layer "In5.Cu")
	)
	(gr_line
		(start 473.3036 -68.072)
		(end 473.3036 -76.962)
		(stroke
			(width 1.016)
			(type default)
		)
		(layer "In5.Cu")
	)
	(gr_arc
		(start 476.000064 -21.770086)
		(mid 474.535594 -18.234577)
		(end 471.000074 -16.770096)
		(stroke
			(width 2.032)
			(type default)
		)
		(layer "In5.Cu")
	)
	(gr_line
		(start 476.000064 -21.770086)
		(end 476.000064 -126.769876)
		(stroke
			(width 2.032)
			(type default)
		)
		(layer "In5.Cu")
	)
	(gr_poly
		(pts
			(arc
				(start 192.800224 -51.05908)
				(mid 192.819747 -51.055179)
				(end 192.836292 -51.044094)
			)
			(arc
				(start 193.053462 -50.826924)
				(mid 193.064573 -50.81039)
				(end 193.068448 -50.790856)
			)
			(arc
				(start 193.068448 -46.88586)
				(mid 193.064547 -46.866337)
				(end 193.053462 -46.849792)
			)
			(arc
				(start 189.652656 -43.448986)
				(mid 189.636122 -43.437875)
				(end 189.616588 -43.434)
			)
			(arc
				(start 186.057794 -43.434)
				(mid 186.038271 -43.437901)
				(end 186.021726 -43.448986)
			)
			(arc
				(start 182.666386 -46.804326)
				(mid 182.655275 -46.82086)
				(end 182.6514 -46.840394)
			)
			(arc
				(start 182.6514 -50.663602)
				(mid 182.655301 -50.683125)
				(end 182.666386 -50.69967)
			)
			(arc
				(start 183.01081 -51.044094)
				(mid 183.027344 -51.055205)
				(end 183.046878 -51.05908)
			)
		)
		(stroke
			(width 0)
			(type solid)
		)
		(fill yes)
		(layer "In6.Cu")
		(net "P52V_2_FUSE_1")
	)
	(gr_poly
		(pts
			(arc
				(start 257.287522 -51.05908)
				(mid 257.307045 -51.055179)
				(end 257.32359 -51.044094)
			)
			(arc
				(start 257.668014 -50.69967)
				(mid 257.679125 -50.683136)
				(end 257.683 -50.663602)
			)
			(arc
				(start 257.683 -46.840394)
				(mid 257.679099 -46.820871)
				(end 257.668014 -46.804326)
			)
			(arc
				(start 254.312674 -43.448986)
				(mid 254.29614 -43.437875)
				(end 254.276606 -43.434)
			)
			(arc
				(start 250.717812 -43.434)
				(mid 250.698289 -43.437901)
				(end 250.681744 -43.448986)
			)
			(arc
				(start 247.280938 -46.849792)
				(mid 247.269827 -46.866326)
				(end 247.265952 -46.88586)
			)
			(arc
				(start 247.265952 -50.790856)
				(mid 247.269853 -50.810379)
				(end 247.280938 -50.826924)
			)
			(arc
				(start 247.498108 -51.044094)
				(mid 247.514642 -51.055205)
				(end 247.534176 -51.05908)
			)
		)
		(stroke
			(width 0)
			(type solid)
		)
		(fill yes)
		(layer "In6.Cu")
		(net "P52V_1_FUSE_1")
	)
	(gr_poly
		(pts
			(arc
				(start 136.007856 -80.01)
				(mid 136.027379 -80.006099)
				(end 136.043924 -79.995014)
			)
			(arc
				(start 136.343644 -79.695294)
				(mid 136.354755 -79.67876)
				(end 136.35863 -79.659226)
			)
			(arc
				(start 136.35863 -68.303902)
				(mid 136.397314 -68.109513)
				(end 136.507474 -67.944746)
			)
			(arc
				(start 137.49655 -66.95567)
				(mid 137.661318 -66.845512)
				(end 137.855706 -66.806826)
			)
			(arc
				(start 139.442444 -66.806826)
				(mid 139.460379 -66.803555)
				(end 139.475972 -66.794126)
			)
			(arc
				(start 139.475972 -66.794126)
				(mid 139.749442 -66.630021)
				(end 140.06322 -66.572892)
			)
			(arc
				(start 140.06322 -66.572892)
				(mid 140.377013 -66.629983)
				(end 140.650468 -66.794126)
			)
			(arc
				(start 140.650468 -66.794126)
				(mid 140.666078 -66.80351)
				(end 140.683996 -66.806826)
			)
			(arc
				(start 142.0876 -66.806826)
				(mid 142.123521 -66.791947)
				(end 142.1384 -66.756026)
			)
			(xy 142.1384 -64.131698)
			(arc
				(start 142.13713 -64.12611)
				(mid 142.120011 -64.026684)
				(end 142.11427 -63.925958)
			)
			(arc
				(start 142.11427 -63.925958)
				(mid 142.12002 -63.825234)
				(end 142.13713 -63.725806)
			)
			(xy 142.1384 -63.720218) (xy 142.1384 -63.025782)
			(arc
				(start 142.13713 -63.020194)
				(mid 142.120011 -62.920768)
				(end 142.11427 -62.820042)
			)
			(arc
				(start 142.11427 -62.820042)
				(mid 142.12002 -62.719318)
				(end 142.13713 -62.61989)
			)
			(xy 142.1384 -62.614302)
			(arc
				(start 142.1384 -47.729394)
				(mid 142.134499 -47.709871)
				(end 142.123414 -47.693326)
			)
			(arc
				(start 141.308074 -46.877986)
				(mid 141.29154 -46.866875)
				(end 141.272006 -46.863)
			)
			(arc
				(start 123.573794 -46.863)
				(mid 123.554271 -46.866901)
				(end 123.537726 -46.877986)
			)
			(arc
				(start 123.357386 -47.058326)
				(mid 123.346275 -47.07486)
				(end 123.3424 -47.094394)
			)
			(arc
				(start 123.3424 -79.651606)
				(mid 123.346301 -79.671129)
				(end 123.357386 -79.687674)
			)
			(arc
				(start 123.664726 -79.995014)
				(mid 123.68126 -80.006125)
				(end 123.700794 -80.01)
			)
		)
		(stroke
			(width 0)
			(type solid)
		)
		(fill yes)
		(layer "In6.Cu")
		(net "P52V_HS2_DRAIN_1")
	)
	(gr_poly
		(pts
			(arc
				(start 323.745606 -80.01)
				(mid 323.765129 -80.006099)
				(end 323.781674 -79.995014)
			)
			(arc
				(start 324.089014 -79.687674)
				(mid 324.100125 -79.67114)
				(end 324.104 -79.651606)
			)
			(arc
				(start 324.104 -47.094394)
				(mid 324.100099 -47.074871)
				(end 324.089014 -47.058326)
			)
			(arc
				(start 323.908674 -46.877986)
				(mid 323.89214 -46.866875)
				(end 323.872606 -46.863)
			)
			(arc
				(start 305.3588 -46.863)
				(mid 305.322879 -46.877879)
				(end 305.308 -46.9138)
			)
			(arc
				(start 305.308 -62.242954)
				(mid 305.310753 -62.259451)
				(end 305.318668 -62.274196)
			)
			(arc
				(start 305.318668 -62.274196)
				(mid 305.457751 -62.531519)
				(end 305.505866 -62.820042)
			)
			(arc
				(start 305.505866 -62.820042)
				(mid 305.462214 -63.095019)
				(end 305.335686 -63.343028)
			)
			(arc
				(start 305.335686 -63.343028)
				(mid 305.325927 -63.373)
				(end 305.335686 -63.402972)
			)
			(arc
				(start 305.335686 -63.402972)
				(mid 305.462208 -63.650983)
				(end 305.505866 -63.925958)
			)
			(arc
				(start 305.505866 -63.925958)
				(mid 305.45777 -64.214488)
				(end 305.318668 -64.471804)
			)
			(arc
				(start 305.318668 -64.471804)
				(mid 305.310697 -64.48653)
				(end 305.308 -64.503046)
			)
			(arc
				(start 305.308 -66.138806)
				(mid 305.311901 -66.158329)
				(end 305.322986 -66.174874)
			)
			(arc
				(start 305.969416 -66.821304)
				(mid 305.98595 -66.832415)
				(end 306.005484 -66.83629)
			)
			(arc
				(start 306.81422 -66.83629)
				(mid 306.833245 -66.832593)
				(end 306.849526 -66.822066)
			)
			(arc
				(start 306.849526 -66.822066)
				(mid 307.467 -66.57292)
				(end 308.084474 -66.822066)
			)
			(arc
				(start 308.084474 -66.822066)
				(mid 308.100741 -66.832627)
				(end 308.11978 -66.83629)
			)
			(arc
				(start 309.808372 -66.83629)
				(mid 310.002761 -66.874974)
				(end 310.167528 -66.985134)
			)
			(arc
				(start 311.081166 -67.898772)
				(mid 311.191324 -68.06354)
				(end 311.23001 -68.257928)
			)
			(arc
				(start 311.23001 -79.613252)
				(mid 311.233911 -79.632775)
				(end 311.244996 -79.64932)
			)
			(arc
				(start 311.59069 -79.995014)
				(mid 311.607224 -80.006125)
				(end 311.626758 -80.01)
			)
		)
		(stroke
			(width 0)
			(type solid)
		)
		(fill yes)
		(layer "In6.Cu")
		(net "P52V_HS1_DRAIN_1")
	)
	(gr_poly
		(pts
			(arc
				(start 141.221206 -45.847)
				(mid 141.240729 -45.843099)
				(end 141.257274 -45.832014)
			)
			(arc
				(start 142.123414 -44.965874)
				(mid 142.134525 -44.94934)
				(end 142.1384 -44.929806)
			)
			(arc
				(start 142.1384 -41.667176)
				(mid 142.131291 -41.641003)
				(end 142.11173 -41.622218)
			)
			(arc
				(start 142.11173 -41.622218)
				(mid 141.769734 -41.29524)
				(end 141.643862 -40.839136)
			)
			(arc
				(start 141.643862 -40.839136)
				(mid 141.647416 -40.759442)
				(end 141.658086 -40.680386)
			)
			(xy 141.660372 -40.66794) (xy 141.653006 -40.644318)
			(arc
				(start 141.511274 -40.502586)
				(mid 141.49474 -40.491475)
				(end 141.475206 -40.4876)
			)
			(arc
				(start 139.1666 -40.4876)
				(mid 138.972211 -40.448916)
				(end 138.807444 -40.338756)
			)
			(arc
				(start 137.689844 -39.221156)
				(mid 137.579686 -39.056388)
				(end 137.541 -38.862)
			)
			(arc
				(start 137.541 -33.8328)
				(mid 137.579684 -33.638411)
				(end 137.689844 -33.473644)
			)
			(arc
				(start 137.989564 -33.173924)
				(mid 138.154332 -33.063766)
				(end 138.34872 -33.02508)
			)
			(arc
				(start 139.38885 -33.02508)
				(mid 139.408704 -33.02104)
				(end 139.425426 -33.009586)
			)
			(arc
				(start 139.425426 -33.009586)
				(mid 140.06322 -32.740107)
				(end 140.701014 -33.009586)
			)
			(arc
				(start 140.701014 -33.009586)
				(mid 140.717722 -33.021073)
				(end 140.73759 -33.02508)
			)
			(arc
				(start 141.520926 -33.02508)
				(mid 141.540449 -33.021179)
				(end 141.556994 -33.010094)
			)
			(arc
				(start 142.123414 -32.443674)
				(mid 142.134525 -32.42714)
				(end 142.1384 -32.407606)
			)
			(xy 142.1384 -30.298898)
			(arc
				(start 142.13713 -30.29331)
				(mid 142.120011 -30.193884)
				(end 142.11427 -30.093158)
			)
			(arc
				(start 142.11427 -30.093158)
				(mid 142.12002 -29.992434)
				(end 142.13713 -29.893006)
			)
			(xy 142.1384 -29.887418) (xy 142.1384 -29.192982)
			(arc
				(start 142.13713 -29.187394)
				(mid 142.120011 -29.087968)
				(end 142.11427 -28.987242)
			)
			(arc
				(start 142.11427 -28.987242)
				(mid 142.12002 -28.886518)
				(end 142.13713 -28.78709)
			)
			(xy 142.1384 -28.781502)
			(arc
				(start 142.1384 -13.439394)
				(mid 142.134499 -13.419871)
				(end 142.123414 -13.403326)
			)
			(arc
				(start 141.689074 -12.968986)
				(mid 141.67254 -12.957875)
				(end 141.653006 -12.954)
			)
			(arc
				(start 123.700794 -12.954)
				(mid 123.681271 -12.957901)
				(end 123.664726 -12.968986)
			)
			(arc
				(start 123.357386 -13.276326)
				(mid 123.346275 -13.29286)
				(end 123.3424 -13.312394)
			)
			(arc
				(start 123.3424 -45.615606)
				(mid 123.346301 -45.635129)
				(end 123.357386 -45.651674)
			)
			(arc
				(start 123.537726 -45.832014)
				(mid 123.55426 -45.843125)
				(end 123.573794 -45.847)
			)
		)
		(stroke
			(width 0)
			(type solid)
		)
		(fill yes)
		(layer "In6.Cu")
		(net "P52V_HS2_DRAIN_2")
	)
	(gr_poly
		(pts
			(arc
				(start 323.872606 -45.847)
				(mid 323.892129 -45.843099)
				(end 323.908674 -45.832014)
			)
			(arc
				(start 324.089014 -45.651674)
				(mid 324.100125 -45.63514)
				(end 324.104 -45.615606)
			)
			(arc
				(start 324.104 -13.312394)
				(mid 324.100099 -13.292871)
				(end 324.089014 -13.276326)
			)
			(arc
				(start 323.781674 -12.968986)
				(mid 323.76514 -12.957875)
				(end 323.745606 -12.954)
			)
			(arc
				(start 305.793394 -12.954)
				(mid 305.773871 -12.957901)
				(end 305.757326 -12.968986)
			)
			(arc
				(start 305.322986 -13.403326)
				(mid 305.311875 -13.41986)
				(end 305.308 -13.439394)
			)
			(arc
				(start 305.308 -28.410154)
				(mid 305.310753 -28.426651)
				(end 305.318668 -28.441396)
			)
			(arc
				(start 305.318668 -28.441396)
				(mid 305.457751 -28.698719)
				(end 305.505866 -28.987242)
			)
			(arc
				(start 305.505866 -28.987242)
				(mid 305.462214 -29.262219)
				(end 305.335686 -29.510228)
			)
			(arc
				(start 305.335686 -29.510228)
				(mid 305.325927 -29.5402)
				(end 305.335686 -29.570172)
			)
			(arc
				(start 305.335686 -29.570172)
				(mid 305.462208 -29.818183)
				(end 305.505866 -30.093158)
			)
			(arc
				(start 305.505866 -30.093158)
				(mid 305.45777 -30.381688)
				(end 305.318668 -30.639004)
			)
			(arc
				(start 305.318668 -30.639004)
				(mid 305.310697 -30.65373)
				(end 305.308 -30.670246)
			)
			(arc
				(start 305.308 -32.712406)
				(mid 305.311901 -32.731929)
				(end 305.322986 -32.748474)
			)
			(arc
				(start 305.53152 -32.957008)
				(mid 305.548054 -32.968119)
				(end 305.567588 -32.971994)
			)
			(arc
				(start 306.848764 -32.971994)
				(mid 306.866531 -32.968786)
				(end 306.882038 -32.959548)
			)
			(arc
				(start 306.882038 -32.959548)
				(mid 307.467 -32.740071)
				(end 308.051962 -32.959548)
			)
			(arc
				(start 308.051962 -32.959548)
				(mid 308.067477 -32.968763)
				(end 308.085236 -32.971994)
			)
			(arc
				(start 309.723028 -32.971994)
				(mid 309.917417 -33.010678)
				(end 310.082184 -33.120838)
			)
			(arc
				(start 311.103518 -34.142172)
				(mid 311.213676 -34.30694)
				(end 311.252362 -34.501328)
			)
			(arc
				(start 311.252362 -39.039038)
				(mid 311.213678 -39.233427)
				(end 311.103518 -39.398194)
			)
			(arc
				(start 309.629556 -40.872156)
				(mid 309.464788 -40.982314)
				(end 309.2704 -41.021)
			)
			(arc
				(start 305.844194 -41.021)
				(mid 305.824671 -41.024901)
				(end 305.808126 -41.035986)
			)
			(xy 305.748944 -41.095168)
			(arc
				(start 305.745134 -41.102788)
				(mid 305.574995 -41.341081)
				(end 305.336702 -41.51122)
			)
			(xy 305.329082 -41.51503)
			(arc
				(start 305.322986 -41.521126)
				(mid 305.311875 -41.53766)
				(end 305.308 -41.557194)
			)
			(arc
				(start 305.308 -45.158406)
				(mid 305.311901 -45.177929)
				(end 305.322986 -45.194474)
			)
			(arc
				(start 305.960526 -45.832014)
				(mid 305.97706 -45.843125)
				(end 305.996594 -45.847)
			)
		)
		(stroke
			(width 0)
			(type solid)
		)
		(fill yes)
		(layer "In6.Cu")
		(net "P52V_HS1_DRAIN_2")
	)
	(gr_poly
		(pts
			(arc
				(start 301.02302 -66.83629)
				(mid 301.042045 -66.832593)
				(end 301.058326 -66.822066)
			)
			(arc
				(start 301.058326 -66.822066)
				(mid 301.6758 -66.57292)
				(end 302.293274 -66.822066)
			)
			(arc
				(start 302.293274 -66.822066)
				(mid 302.309541 -66.832627)
				(end 302.32858 -66.83629)
			)
			(arc
				(start 303.670716 -66.83629)
				(mid 303.690239 -66.832389)
				(end 303.706784 -66.821304)
			)
			(arc
				(start 304.277014 -66.251074)
				(mid 304.288125 -66.23454)
				(end 304.292 -66.215006)
			)
			(arc
				(start 304.292 -64.788288)
				(mid 304.283781 -64.760329)
				(end 304.26152 -64.741552)
			)
			(arc
				(start 304.26152 -64.741552)
				(mid 303.872479 -64.413552)
				(end 303.72685 -63.925958)
			)
			(arc
				(start 303.72685 -63.925958)
				(mid 303.770502 -63.650981)
				(end 303.89703 -63.402972)
			)
			(arc
				(start 303.89703 -63.402972)
				(mid 303.906789 -63.373)
				(end 303.89703 -63.343028)
			)
			(arc
				(start 303.89703 -63.343028)
				(mid 303.770508 -63.095017)
				(end 303.72685 -62.820042)
			)
			(arc
				(start 303.72685 -62.820042)
				(mid 303.872423 -62.33241)
				(end 304.26152 -62.004448)
			)
			(arc
				(start 304.26152 -62.004448)
				(mid 304.283721 -61.985633)
				(end 304.292 -61.957712)
			)
			(arc
				(start 304.292 -42.065194)
				(mid 304.288099 -42.045671)
				(end 304.277014 -42.029126)
			)
			(xy 303.762918 -41.51503)
			(arc
				(start 303.755298 -41.51122)
				(mid 303.517005 -41.341081)
				(end 303.346866 -41.102788)
			)
			(arc
				(start 303.346866 -41.102788)
				(mid 303.342572 -41.095678)
				(end 303.337214 -41.089326)
			)
			(arc
				(start 303.283874 -41.035986)
				(mid 303.26734 -41.024875)
				(end 303.247806 -41.021)
			)
			(arc
				(start 300.6852 -41.021)
				(mid 300.490811 -40.982316)
				(end 300.326044 -40.872156)
			)
			(arc
				(start 298.809156 -39.355268)
				(mid 298.698998 -39.1905)
				(end 298.660312 -38.996112)
			)
			(arc
				(start 298.660312 -33.576768)
				(mid 298.698996 -33.382379)
				(end 298.809156 -33.217612)
			)
			(arc
				(start 298.90593 -33.120838)
				(mid 299.070698 -33.01068)
				(end 299.265086 -32.971994)
			)
			(arc
				(start 301.057564 -32.971994)
				(mid 301.075331 -32.968786)
				(end 301.090838 -32.959548)
			)
			(arc
				(start 301.090838 -32.959548)
				(mid 301.6758 -32.740071)
				(end 302.260762 -32.959548)
			)
			(arc
				(start 302.260762 -32.959548)
				(mid 302.276277 -32.968763)
				(end 302.294036 -32.971994)
			)
			(arc
				(start 304.007012 -32.971994)
				(mid 304.026535 -32.968093)
				(end 304.04308 -32.957008)
			)
			(arc
				(start 304.277014 -32.723074)
				(mid 304.288125 -32.70654)
				(end 304.292 -32.687006)
			)
			(arc
				(start 304.292 -30.955488)
				(mid 304.283781 -30.927529)
				(end 304.26152 -30.908752)
			)
			(arc
				(start 304.26152 -30.908752)
				(mid 303.872479 -30.580752)
				(end 303.72685 -30.093158)
			)
			(arc
				(start 303.72685 -30.093158)
				(mid 303.770502 -29.818181)
				(end 303.89703 -29.570172)
			)
			(arc
				(start 303.89703 -29.570172)
				(mid 303.906789 -29.5402)
				(end 303.89703 -29.510228)
			)
			(arc
				(start 303.89703 -29.510228)
				(mid 303.770508 -29.262217)
				(end 303.72685 -28.987242)
			)
			(arc
				(start 303.72685 -28.987242)
				(mid 303.872423 -28.49961)
				(end 304.26152 -28.171648)
			)
			(arc
				(start 304.26152 -28.171648)
				(mid 304.283721 -28.152833)
				(end 304.292 -28.124912)
			)
			(arc
				(start 304.292 -13.439394)
				(mid 304.288099 -13.419871)
				(end 304.277014 -13.403326)
			)
			(arc
				(start 303.842674 -12.968986)
				(mid 303.82614 -12.957875)
				(end 303.806606 -12.954)
			)
			(arc
				(start 283.585412 -12.954)
				(mid 283.565889 -12.957901)
				(end 283.549344 -12.968986)
			)
			(arc
				(start 280.176986 -16.341344)
				(mid 280.165875 -16.357878)
				(end 280.162 -16.377412)
			)
			(arc
				(start 280.162 -27.182318)
				(mid 280.123316 -27.376707)
				(end 280.013156 -27.541474)
			)
			(arc
				(start 278.747474 -28.807156)
				(mid 278.582706 -28.917314)
				(end 278.388318 -28.956)
			)
			(arc
				(start 231.371394 -28.956)
				(mid 231.351871 -28.959901)
				(end 231.335326 -28.970986)
			)
			(arc
				(start 229.884986 -30.421326)
				(mid 229.873875 -30.43786)
				(end 229.87 -30.457394)
			)
			(arc
				(start 229.87 -46.758606)
				(mid 229.873901 -46.778129)
				(end 229.884986 -46.794674)
			)
			(arc
				(start 230.446326 -47.356014)
				(mid 230.46286 -47.367125)
				(end 230.482394 -47.371)
			)
			(arc
				(start 242.73256 -47.371)
				(mid 242.752083 -47.367099)
				(end 242.768628 -47.356014)
			)
			(arc
				(start 248.63425 -41.490392)
				(mid 248.799018 -41.380234)
				(end 248.993406 -41.341548)
			)
			(arc
				(start 255.891538 -41.341548)
				(mid 256.085927 -41.380232)
				(end 256.250694 -41.490392)
			)
			(arc
				(start 258.814316 -44.054014)
				(mid 258.83085 -44.065125)
				(end 258.850384 -44.069)
			)
			(arc
				(start 268.097 -44.069)
				(mid 268.291389 -44.107684)
				(end 268.456156 -44.217844)
			)
			(arc
				(start 282.440126 -58.201814)
				(mid 282.45666 -58.212925)
				(end 282.476194 -58.2168)
			)
			(arc
				(start 293.4208 -58.2168)
				(mid 293.615189 -58.255484)
				(end 293.779956 -58.365644)
			)
			(arc
				(start 297.081956 -61.667644)
				(mid 297.192114 -61.832412)
				(end 297.2308 -62.0268)
			)
			(arc
				(start 297.2308 -65.478406)
				(mid 297.234701 -65.497929)
				(end 297.245786 -65.514474)
			)
			(arc
				(start 298.552616 -66.821304)
				(mid 298.56915 -66.832415)
				(end 298.588684 -66.83629)
			)
		)
		(stroke
			(width 0)
			(type solid)
		)
		(fill yes)
		(layer "In6.Cu")
		(net "P52V_1")
	)
	(gr_poly
		(pts
			(xy 145.83537 -66.794126) (xy 145.867831 -66.766277) (xy 145.937206 -66.716243) (xy 146.011062 -66.673098)
			(xy 146.088718 -66.637241) (xy 146.169458 -66.609003) (xy 146.252535 -66.588645) (xy 146.337182 -66.576355)
			(xy 146.422618 -66.572245) (xy 146.508054 -66.576355) (xy 146.592701 -66.588645) (xy 146.675778 -66.609003)
			(xy 146.756518 -66.637241) (xy 146.834174 -66.673098) (xy 146.90803 -66.716243) (xy 146.977405 -66.766277)
			(xy 147.009866 -66.794126) (xy 147.043394 -66.806826) (xy 148.436838 -66.806826) (xy 148.446906 -66.806397)
			(xy 148.465503 -66.798675) (xy 148.472906 -66.79184) (xy 156.479494 -58.785252) (xy 156.48051 -58.784236)
			(xy 156.4894 -58.775092) (xy 159.388048 -55.876444) (xy 159.397192 -55.867554) (xy 159.398208 -55.866538)
			(xy 159.997902 -55.266844) (xy 160.021781 -55.243685) (xy 160.074544 -55.203175) (xy 160.132144 -55.1699)
			(xy 160.193596 -55.14443) (xy 160.257847 -55.127203) (xy 160.323798 -55.118512) (xy 160.357058 -55.118)
			(xy 175.181006 -55.118) (xy 175.191076 -55.117576) (xy 175.209679 -55.10986) (xy 175.217074 -55.103014)
			(xy 175.779176 -54.540912) (xy 175.786027 -54.533515) (xy 175.793769 -54.514917) (xy 175.794162 -54.504844)
			(xy 175.794162 -53.658516) (xy 175.793723 -53.648453) (xy 175.785983 -53.629875) (xy 175.779176 -53.622448)
			(xy 173.785022 -51.628294) (xy 173.777619 -51.62146) (xy 173.759021 -51.613755) (xy 173.748954 -51.613308)
			(xy 172.583348 -51.613308) (xy 172.550087 -51.61279) (xy 172.484133 -51.604108) (xy 172.419878 -51.586888)
			(xy 172.358423 -51.561423) (xy 172.300819 -51.528151) (xy 172.248054 -51.48764) (xy 172.224192 -51.464464)
			(xy 171.815506 -51.055778) (xy 171.792346 -51.0319) (xy 171.751833 -50.979138) (xy 171.718556 -50.921538)
			(xy 171.693086 -50.860086) (xy 171.675859 -50.795834) (xy 171.667169 -50.729883) (xy 171.666662 -50.696622)
			(xy 171.666662 -43.570398) (xy 171.667183 -43.537138) (xy 171.67587 -43.471187) (xy 171.693095 -43.406936)
			(xy 171.718563 -43.345483) (xy 171.751837 -43.287883) (xy 171.792348 -43.235122) (xy 171.815506 -43.211242)
			(xy 173.556676 -41.470072) (xy 173.580556 -41.446916) (xy 173.63332 -41.406411) (xy 173.690921 -41.373143)
			(xy 173.752373 -41.347681) (xy 173.816624 -41.330462) (xy 173.882573 -41.32178) (xy 173.915832 -41.321228)
			(xy 191.747394 -41.321228) (xy 191.780655 -41.321749) (xy 191.846606 -41.330434) (xy 191.910859 -41.347657)
			(xy 191.972313 -41.373123) (xy 192.029915 -41.406395) (xy 192.08268 -41.446904) (xy 192.10655 -41.470072)
			(xy 197.992492 -47.356014) (xy 197.999886 -47.362871) (xy 198.018485 -47.370622) (xy 198.02856 -47.371)
			(xy 209.852006 -47.371) (xy 209.862076 -47.370576) (xy 209.880679 -47.36286) (xy 209.888074 -47.356014)
			(xy 210.449414 -46.794674) (xy 210.456266 -46.787278) (xy 210.464004 -46.768679) (xy 210.4644 -46.758606)
			(xy 210.4644 -30.457394) (xy 210.463976 -30.447324) (xy 210.45626 -30.428721) (xy 210.449414 -30.421326)
			(xy 208.999074 -28.970986) (xy 208.991678 -28.964134) (xy 208.973079 -28.956396) (xy 208.963006 -28.956)
			(xy 161.946082 -28.956) (xy 161.912822 -28.955477) (xy 161.846873 -28.946788) (xy 161.782624 -28.929561)
			(xy 161.721174 -28.90409) (xy 161.663577 -28.870813) (xy 161.610819 -28.830299) (xy 161.586926 -28.807156)
			(xy 160.321244 -27.541474) (xy 160.298087 -27.517595) (xy 160.257578 -27.464831) (xy 160.224306 -27.407231)
			(xy 160.19884 -27.345779) (xy 160.181615 -27.281528) (xy 160.172927 -27.215578) (xy 160.1724 -27.182318)
			(xy 160.1724 -16.377412) (xy 160.171979 -16.367341) (xy 160.164268 -16.348733) (xy 160.157414 -16.341344)
			(xy 156.785056 -12.968986) (xy 156.777659 -12.962137) (xy 156.75906 -12.954405) (xy 156.748988 -12.954)
			(xy 143.639794 -12.954) (xy 143.629724 -12.954424) (xy 143.611121 -12.96214) (xy 143.603726 -12.968986)
			(xy 143.169386 -13.403326) (xy 143.162534 -13.410722) (xy 143.154796 -13.429321) (xy 143.1544 -13.439394)
			(xy 143.1544 -28.086812) (xy 143.176752 -28.114498) (xy 143.194278 -28.118308) (xy 143.236229 -28.128019)
			(xy 143.318173 -28.154495) (xy 143.397174 -28.188768) (xy 143.472493 -28.230517) (xy 143.543424 -28.279349)
			(xy 143.609303 -28.334808) (xy 143.669514 -28.396375) (xy 143.723492 -28.463473) (xy 143.770733 -28.535474)
			(xy 143.810793 -28.611704) (xy 143.843298 -28.691449) (xy 143.867943 -28.773962) (xy 143.884498 -28.858471)
			(xy 143.892807 -28.944184) (xy 143.893286 -28.987242) (xy 143.892835 -29.027187) (xy 143.885642 -29.106753)
			(xy 143.871344 -29.185353) (xy 143.850056 -29.262355) (xy 143.821949 -29.337138) (xy 143.787251 -29.4091)
			(xy 143.746241 -29.477661) (xy 143.723106 -29.510228) (xy 143.717172 -29.519192) (xy 143.712701 -29.5402)
			(xy 143.717172 -29.561208) (xy 143.723106 -29.570172) (xy 143.746258 -29.602728) (xy 143.787281 -29.671284)
			(xy 143.821987 -29.743245) (xy 143.850094 -29.81803) (xy 143.871376 -29.895036) (xy 143.885662 -29.973642)
			(xy 143.892835 -30.053212) (xy 143.893286 -30.093158) (xy 143.892778 -30.136213) (xy 143.884453 -30.22192)
			(xy 143.867886 -30.306421) (xy 143.843233 -30.388926) (xy 143.810723 -30.468664) (xy 143.770662 -30.544888)
			(xy 143.723424 -30.616884) (xy 143.669451 -30.68398) (xy 143.609247 -30.745547) (xy 143.543378 -30.80101)
			(xy 143.472457 -30.849849) (xy 143.39715 -30.891608) (xy 143.318161 -30.925895) (xy 143.236229 -30.95239)
			(xy 143.194278 -30.962092) (xy 143.176752 -30.965902) (xy 143.1544 -30.993588) (xy 143.1544 -32.458406)
			(xy 143.154824 -32.468476) (xy 143.16254 -32.487079) (xy 143.169386 -32.494474) (xy 143.685006 -33.010094)
			(xy 143.692405 -33.01694) (xy 143.711003 -33.024673) (xy 143.721074 -33.02508) (xy 145.18005 -33.02508)
			(xy 145.190294 -33.024611) (xy 145.209156 -33.016612) (xy 145.216626 -33.009586) (xy 145.246136 -32.979918)
			(xy 145.309846 -32.925658) (xy 145.37837 -32.877621) (xy 145.451103 -32.836233) (xy 145.527403 -32.801859)
			(xy 145.606593 -32.774803) (xy 145.687975 -32.755305) (xy 145.770828 -32.743537) (xy 145.85442 -32.739602)
			(xy 145.938012 -32.743537) (xy 146.020865 -32.755305) (xy 146.102247 -32.774803) (xy 146.181437 -32.801859)
			(xy 146.257737 -32.836233) (xy 146.33047 -32.877621) (xy 146.398994 -32.925658) (xy 146.462704 -32.979918)
			(xy 146.492214 -33.009586) (xy 146.499661 -33.016649) (xy 146.518536 -33.024665) (xy 146.52879 -33.02508)
			(xy 147.35048 -33.02508) (xy 147.383741 -33.0256) (xy 147.449692 -33.034285) (xy 147.513945 -33.051508)
			(xy 147.575399 -33.076974) (xy 147.633 -33.110248) (xy 147.685763 -33.150759) (xy 147.709636 -33.173924)
			(xy 148.212556 -33.676844) (xy 148.235712 -33.700724) (xy 148.276218 -33.753488) (xy 148.309489 -33.811089)
			(xy 148.334953 -33.87254) (xy 148.352175 -33.936791) (xy 148.360861 -34.002741) (xy 148.3614 -34.036)
			(xy 148.3614 -38.3794) (xy 148.360879 -38.41266) (xy 148.352191 -38.47861) (xy 148.334966 -38.542861)
			(xy 148.309497 -38.604312) (xy 148.276221 -38.661911) (xy 148.235708 -38.714671) (xy 148.212556 -38.738556)
			(xy 146.612356 -40.338756) (xy 146.588476 -40.361912) (xy 146.535712 -40.402418) (xy 146.478111 -40.435689)
			(xy 146.41666 -40.461153) (xy 146.352409 -40.478375) (xy 146.286459 -40.487061) (xy 146.2532 -40.4876)
			(xy 144.292574 -40.4876) (xy 144.280913 -40.48818) (xy 144.260011 -40.49852) (xy 144.252442 -40.507412)
			(xy 144.1958 -40.580564) (xy 144.191228 -40.60317) (xy 144.194276 -40.614854) (xy 144.203395 -40.651489)
			(xy 144.216151 -40.725904) (xy 144.222566 -40.801132) (xy 144.222978 -40.838882) (xy 144.222978 -40.839136)
			(xy 144.222502 -40.880237) (xy 144.214914 -40.962088) (xy 144.199806 -41.042889) (xy 144.177307 -41.121952)
			(xy 144.14761 -41.198602) (xy 144.110966 -41.272185) (xy 144.06769 -41.342073) (xy 144.01815 -41.407669)
			(xy 143.962768 -41.468415) (xy 143.902019 -41.523792) (xy 143.836418 -41.573327) (xy 143.766527 -41.616598)
			(xy 143.692942 -41.653236) (xy 143.61629 -41.682928) (xy 143.537225 -41.705421) (xy 143.456422 -41.720523)
			(xy 143.374571 -41.728105) (xy 143.33347 -41.728644) (xy 143.316052 -41.728547) (xy 143.281244 -41.727151)
			(xy 143.263874 -41.72585) (xy 143.253206 -41.725088) (xy 143.233394 -41.731946) (xy 143.170656 -41.790112)
			(xy 143.163326 -41.797585) (xy 143.15494 -41.816741) (xy 143.1544 -41.827196) (xy 143.1544 -60.8863)
			(xy 149.598403 -60.8863) (xy 149.602436 -60.801653) (xy 149.614496 -60.717772) (xy 149.634475 -60.635417)
			(xy 149.662192 -60.555335) (xy 149.697396 -60.47825) (xy 149.739767 -60.40486) (xy 149.788924 -60.33583)
			(xy 149.844419 -60.271786) (xy 149.90575 -60.213306) (xy 149.972363 -60.160922) (xy 150.043654 -60.115106)
			(xy 150.118977 -60.076275) (xy 150.19765 -60.044779) (xy 150.278961 -60.020904) (xy 150.362173 -60.004867)
			(xy 150.446532 -59.996812) (xy 150.488904 -59.996324) (xy 150.52977 -59.996769) (xy 150.611158 -60.004255)
			(xy 150.691516 -60.01918) (xy 150.730966 -60.029852) (xy 150.73884 -60.029852) (xy 150.754569 -60.028859)
			(xy 150.786072 -60.027841) (xy 150.801832 -60.02782) (xy 150.831775 -60.028149) (xy 150.891516 -60.032344)
			(xy 150.921212 -60.036202) (xy 150.926645 -60.036819) (xy 150.937541 -60.035916) (xy 150.942802 -60.034424)
			(xy 150.984607 -60.022329) (xy 151.069974 -60.005385) (xy 151.156588 -59.996862) (xy 151.200104 -59.996324)
			(xy 151.241943 -59.996835) (xy 151.325246 -60.004741) (xy 151.40744 -60.020426) (xy 151.447754 -60.03163)
			(xy 151.452605 -60.032865) (xy 151.462584 -60.033638) (xy 151.467566 -60.033154) (xy 151.491555 -60.030673)
			(xy 151.539715 -60.028007) (xy 151.563832 -60.02782) (xy 151.606191 -60.028361) (xy 151.690524 -60.036417)
			(xy 151.77371 -60.052453) (xy 151.854996 -60.076323) (xy 151.933644 -60.107811) (xy 152.008943 -60.146633)
			(xy 152.080211 -60.192436) (xy 152.146802 -60.244807) (xy 152.208114 -60.303269) (xy 152.263591 -60.367296)
			(xy 152.312731 -60.436305) (xy 152.355089 -60.509673) (xy 152.390281 -60.586735) (xy 152.417989 -60.666794)
			(xy 152.437961 -60.749123) (xy 152.450018 -60.832978) (xy 152.454049 -60.9176) (xy 152.450018 -61.002222)
			(xy 152.437961 -61.086077) (xy 152.417989 -61.168406) (xy 152.390281 -61.248465) (xy 152.355089 -61.325527)
			(xy 152.312731 -61.398895) (xy 152.263591 -61.467904) (xy 152.208114 -61.531931) (xy 152.146802 -61.590393)
			(xy 152.080211 -61.642764) (xy 152.008943 -61.688567) (xy 151.933644 -61.727389) (xy 151.854996 -61.758877)
			(xy 151.77371 -61.782747) (xy 151.690524 -61.798783) (xy 151.606191 -61.806839) (xy 151.563832 -61.807344)
			(xy 151.522302 -61.806838) (xy 151.439608 -61.799047) (xy 151.357999 -61.783584) (xy 151.31796 -61.772546)
			(xy 151.313172 -61.771327) (xy 151.303322 -61.770568) (xy 151.298402 -61.771022) (xy 151.273906 -61.773544)
			(xy 151.224729 -61.776215) (xy 151.200104 -61.776356) (xy 151.169652 -61.776085) (xy 151.108892 -61.771892)
			(xy 151.078692 -61.767974) (xy 151.073259 -61.767359) (xy 151.062363 -61.768262) (xy 151.057102 -61.769752)
			(xy 151.015613 -61.781676) (xy 150.930916 -61.798391) (xy 150.844997 -61.80681) (xy 150.801832 -61.807344)
			(xy 150.801578 -61.807344) (xy 150.761588 -61.806903) (xy 150.681934 -61.799687) (xy 150.603251 -61.785342)
			(xy 150.564596 -61.775086) (xy 150.557738 -61.773562) (xy 150.540558 -61.774847) (xy 150.506131 -61.776245)
			(xy 150.488904 -61.776356) (xy 150.446532 -61.775788) (xy 150.362173 -61.767733) (xy 150.278961 -61.751696)
			(xy 150.19765 -61.727821) (xy 150.118977 -61.696325) (xy 150.043654 -61.657494) (xy 149.972363 -61.611678)
			(xy 149.90575 -61.559294) (xy 149.844419 -61.500814) (xy 149.788924 -61.43677) (xy 149.739767 -61.36774)
			(xy 149.697396 -61.29435) (xy 149.662192 -61.217265) (xy 149.634475 -61.137183) (xy 149.614496 -61.054828)
			(xy 149.602436 -60.970947) (xy 149.598403 -60.8863) (xy 143.1544 -60.8863) (xy 143.1544 -61.919612)
			(xy 143.176752 -61.947298) (xy 143.194278 -61.951108) (xy 143.236229 -61.960819) (xy 143.318173 -61.987295)
			(xy 143.397174 -62.021568) (xy 143.472493 -62.063317) (xy 143.543424 -62.112149) (xy 143.609303 -62.167608)
			(xy 143.669514 -62.229175) (xy 143.723492 -62.296273) (xy 143.770733 -62.368274) (xy 143.810793 -62.444504)
			(xy 143.843298 -62.524249) (xy 143.867943 -62.606762) (xy 143.884498 -62.691271) (xy 143.892807 -62.776984)
			(xy 143.893286 -62.820042) (xy 143.892835 -62.859987) (xy 143.885642 -62.939553) (xy 143.871344 -63.018153)
			(xy 143.850056 -63.095155) (xy 143.821949 -63.169938) (xy 143.787251 -63.2419) (xy 143.746241 -63.310461)
			(xy 143.723106 -63.343028) (xy 143.717172 -63.351992) (xy 143.712701 -63.373) (xy 143.717172 -63.394008)
			(xy 143.723106 -63.402972) (xy 143.746258 -63.435528) (xy 143.787281 -63.504084) (xy 143.821987 -63.576045)
			(xy 143.850094 -63.65083) (xy 143.871376 -63.727836) (xy 143.885662 -63.806442) (xy 143.892835 -63.886012)
			(xy 143.893286 -63.925958) (xy 143.892778 -63.969013) (xy 143.884453 -64.05472) (xy 143.867886 -64.139221)
			(xy 143.843233 -64.221726) (xy 143.810723 -64.301464) (xy 143.770662 -64.377688) (xy 143.723424 -64.449684)
			(xy 143.669451 -64.51678) (xy 143.609247 -64.578347) (xy 143.543378 -64.63381) (xy 143.472457 -64.682649)
			(xy 143.39715 -64.724408) (xy 143.318161 -64.758695) (xy 143.236229 -64.78519) (xy 143.194278 -64.794892)
			(xy 143.176752 -64.798702) (xy 143.1544 -64.826388) (xy 143.1544 -66.756026) (xy 143.154893 -66.76603)
			(xy 143.162557 -66.784513) (xy 143.176709 -66.798658) (xy 143.195196 -66.806312) (xy 143.2052 -66.806826)
			(xy 145.801842 -66.806826)
		)
		(stroke
			(width 0)
			(type solid)
		)
		(fill yes)
		(layer "In6.Cu")
		(net "P52V_2")
	)
	(gr_poly
		(pts
			(xy 474.000068 -199.098154) (xy 474.055876 -199.097646) (xy 474.167179 -199.089307) (xy 474.277548 -199.072673)
			(xy 474.386365 -199.047838) (xy 474.493022 -199.01494) (xy 474.596923 -198.974164) (xy 474.697485 -198.925736)
			(xy 474.794147 -198.869929) (xy 474.886368 -198.807054) (xy 474.973633 -198.737463) (xy 475.055452 -198.661545)
			(xy 475.13137 -198.579725) (xy 475.20096 -198.49246) (xy 475.263834 -198.400239) (xy 475.319641 -198.303576)
			(xy 475.368068 -198.203014) (xy 475.408844 -198.099113) (xy 475.441741 -197.992456) (xy 475.466575 -197.883638)
			(xy 475.483208 -197.773269) (xy 475.491546 -197.661966) (xy 475.492064 -197.606158) (xy 475.492064 -135.770112)
			(xy 475.491555 -135.714305) (xy 475.483215 -135.603002) (xy 475.46658 -135.492634) (xy 475.441744 -135.383817)
			(xy 475.408845 -135.277161) (xy 475.368068 -135.173262) (xy 475.31964 -135.072701) (xy 475.263833 -134.97604)
			(xy 475.200958 -134.88382) (xy 475.131367 -134.796556) (xy 475.055449 -134.714737) (xy 474.973629 -134.63882)
			(xy 474.886364 -134.569231) (xy 474.794143 -134.506357) (xy 474.697481 -134.450551) (xy 474.596919 -134.402124)
			(xy 474.49302 -134.361348) (xy 474.386363 -134.328451) (xy 474.277546 -134.303616) (xy 474.167178 -134.286983)
			(xy 474.055875 -134.278644) (xy 474.000068 -134.278116) (xy 444.999872 -134.278116) (xy 444.929968 -134.278612)
			(xy 444.790381 -134.286463) (xy 444.651454 -134.302127) (xy 444.513624 -134.325555) (xy 444.377323 -134.356674)
			(xy 444.242982 -134.395385) (xy 444.111022 -134.441566) (xy 443.981859 -134.495074) (xy 443.855899 -134.555738)
			(xy 443.733538 -134.623368) (xy 443.615161 -134.697752) (xy 443.50114 -134.778656) (xy 443.391834 -134.865825)
			(xy 443.287587 -134.958985) (xy 443.188727 -135.057842) (xy 443.095565 -135.162087) (xy 443.008393 -135.27139)
			(xy 442.927487 -135.385409) (xy 442.8531 -135.503784) (xy 442.785466 -135.626144) (xy 442.724799 -135.752102)
			(xy 442.671289 -135.881264) (xy 442.625104 -136.013223) (xy 442.586389 -136.147563) (xy 442.555267 -136.283863)
			(xy 442.531836 -136.421693) (xy 442.516168 -136.56062) (xy 442.508314 -136.700206) (xy 442.507878 -136.77011)
			(xy 442.507878 -153.299922) (xy 442.507375 -153.422774) (xy 442.499335 -153.668345) (xy 442.483265 -153.913522)
			(xy 442.459181 -154.158042) (xy 442.42711 -154.401643) (xy 442.387085 -154.644065) (xy 442.33915 -154.885047)
			(xy 442.283356 -155.124331) (xy 442.219763 -155.361662) (xy 442.148438 -155.596785) (xy 442.069459 -155.829449)
			(xy 441.982909 -156.059404) (xy 441.888882 -156.286404) (xy 441.787478 -156.510205) (xy 441.678806 -156.73057)
			(xy 441.562982 -156.94726) (xy 441.44013 -157.160045) (xy 441.310381 -157.368697) (xy 441.173875 -157.572991)
			(xy 441.030758 -157.77271) (xy 440.881183 -157.967639) (xy 440.72531 -158.15757) (xy 440.563307 -158.342299)
			(xy 440.395346 -158.521628) (xy 440.221607 -158.695366) (xy 440.042277 -158.863327) (xy 439.857547 -159.02533)
			(xy 439.667615 -159.181202) (xy 439.472686 -159.330776) (xy 439.272966 -159.473893) (xy 439.068671 -159.610398)
			(xy 438.860019 -159.740145) (xy 438.647234 -159.862996) (xy 438.430543 -159.97882) (xy 438.210178 -160.087491)
			(xy 437.986376 -160.188894) (xy 437.759376 -160.28292) (xy 437.52942 -160.369469) (xy 437.296757 -160.448447)
			(xy 437.061633 -160.519771) (xy 436.824302 -160.583363) (xy 436.585017 -160.639156) (xy 436.344035 -160.68709)
			(xy 436.101614 -160.727114) (xy 435.858012 -160.759184) (xy 435.613492 -160.783267) (xy 435.368315 -160.799337)
			(xy 435.122744 -160.807376) (xy 434.999892 -160.807908) (xy 416.576256 -160.807908) (xy 416.506352 -160.808399)
			(xy 416.366764 -160.816241) (xy 416.227835 -160.831897) (xy 416.090003 -160.855317) (xy 415.9537 -160.88643)
			(xy 415.819357 -160.925136) (xy 415.687395 -160.971313) (xy 415.55823 -161.024817) (xy 415.432268 -161.085479)
			(xy 415.309905 -161.153108) (xy 415.191527 -161.227492) (xy 415.077506 -161.308396) (xy 414.968201 -161.395567)
			(xy 414.863955 -161.488728) (xy 414.765097 -161.587588) (xy 414.671937 -161.691836) (xy 414.584769 -161.801143)
			(xy 414.503867 -161.915166) (xy 414.429485 -162.033545) (xy 414.361858 -162.155909) (xy 414.301198 -162.281872)
			(xy 414.247697 -162.411038) (xy 414.201522 -162.543001) (xy 414.162818 -162.677345) (xy 414.131708 -162.813648)
			(xy 414.10829 -162.951481) (xy 414.092637 -163.09041) (xy 414.084798 -163.229998) (xy 414.084262 -163.299902)
			(xy 414.084262 -187.606178) (xy 414.083778 -187.676532) (xy 414.07589 -187.817019) (xy 414.060137 -187.956842)
			(xy 414.036568 -188.095562) (xy 414.005258 -188.232743) (xy 413.966306 -188.367952) (xy 413.919834 -188.500764)
			(xy 413.865987 -188.630762) (xy 413.804937 -188.757535) (xy 413.736874 -188.880686) (xy 413.662013 -188.999827)
			(xy 413.580589 -189.114583) (xy 413.492859 -189.224593) (xy 413.399098 -189.329511) (xy 413.299602 -189.429006)
			(xy 413.194684 -189.522766) (xy 413.084674 -189.610496) (xy 412.969917 -189.691919) (xy 412.850776 -189.76678)
			(xy 412.727625 -189.834842) (xy 412.600851 -189.895892) (xy 412.470853 -189.949738) (xy 412.33804 -189.99621)
			(xy 412.202831 -190.035161) (xy 412.065651 -190.06647) (xy 411.92693 -190.090038) (xy 411.787107 -190.105791)
			(xy 411.64662 -190.113679) (xy 411.576266 -190.114174) (xy 351.499932 -190.114174) (xy 351.429578 -190.113691)
			(xy 351.28909 -190.105803) (xy 351.149266 -190.09005) (xy 351.010545 -190.066482) (xy 350.873364 -190.035172)
			(xy 350.738154 -189.996221) (xy 350.605341 -189.949748) (xy 350.475343 -189.895903) (xy 350.348569 -189.834852)
			(xy 350.225417 -189.766789) (xy 350.106275 -189.691929) (xy 349.991518 -189.610505) (xy 349.881507 -189.522775)
			(xy 349.776589 -189.429014) (xy 349.677092 -189.329519) (xy 349.583332 -189.2246) (xy 349.495601 -189.11459)
			(xy 349.414177 -188.999833) (xy 349.339316 -188.880692) (xy 349.271252 -188.75754) (xy 349.210202 -188.630766)
			(xy 349.156355 -188.500768) (xy 349.109883 -188.367955) (xy 349.07093 -188.232746) (xy 349.03962 -188.095565)
			(xy 349.016052 -187.956844) (xy 349.000298 -187.81702) (xy 348.99241 -187.676532) (xy 348.991936 -187.606178)
			(xy 348.991936 -110.499906) (xy 348.991437 -110.399374) (xy 348.983341 -110.198474) (xy 348.967162 -109.998063)
			(xy 348.942927 -109.798466) (xy 348.910674 -109.600006) (xy 348.870457 -109.403006) (xy 348.822339 -109.207786)
			(xy 348.7664 -109.014661) (xy 348.702729 -108.823945) (xy 348.631431 -108.635948) (xy 348.552621 -108.450974)
			(xy 348.466427 -108.269323) (xy 348.372988 -108.09129) (xy 348.272456 -107.917165) (xy 348.164995 -107.747228)
			(xy 348.050777 -107.581757) (xy 347.92999 -107.421018) (xy 347.802828 -107.265274) (xy 347.669498 -107.114776)
			(xy 347.530217 -106.969769) (xy 347.385209 -106.830488) (xy 347.234711 -106.697159) (xy 347.078966 -106.569998)
			(xy 346.918227 -106.449211) (xy 346.752755 -106.334994) (xy 346.582818 -106.227533) (xy 346.408692 -106.127002)
			(xy 346.230659 -106.033564) (xy 346.049008 -105.947371) (xy 345.864034 -105.868561) (xy 345.676036 -105.797264)
			(xy 345.48532 -105.733594) (xy 345.292195 -105.677656) (xy 345.096974 -105.629539) (xy 344.899974 -105.589322)
			(xy 344.701514 -105.55707) (xy 344.501917 -105.532836) (xy 344.301506 -105.516658) (xy 344.100606 -105.508563)
			(xy 344.000074 -105.508044) (xy 293.310056 -105.508044) (xy 293.254251 -105.508567) (xy 293.142952 -105.516911)
			(xy 293.032588 -105.533549) (xy 292.923776 -105.558388) (xy 292.817125 -105.591289) (xy 292.713231 -105.632068)
			(xy 292.612674 -105.680497) (xy 292.516018 -105.736305) (xy 292.423802 -105.799181) (xy 292.336543 -105.868771)
			(xy 292.254729 -105.944688) (xy 292.178817 -106.026507) (xy 292.109231 -106.11377) (xy 292.046361 -106.205989)
			(xy 291.990558 -106.302648) (xy 291.942135 -106.403208) (xy 291.901361 -106.507104) (xy 291.868466 -106.613758)
			(xy 291.843634 -106.722571) (xy 291.827002 -106.832936) (xy 291.818664 -106.944235) (xy 291.81806 -107.00004)
			(xy 291.81806 -121.780046) (xy 291.817562 -121.863539) (xy 291.809615 -122.030336) (xy 291.793739 -122.196566)
			(xy 291.769973 -122.361852) (xy 291.738368 -122.52582) (xy 291.698998 -122.688098) (xy 291.65195 -122.848319)
			(xy 291.597333 -123.006121) (xy 291.535268 -123.161144) (xy 291.465898 -123.313039) (xy 291.389379 -123.461461)
			(xy 291.305884 -123.606075) (xy 291.215603 -123.746551) (xy 291.11874 -123.882573) (xy 291.015514 -124.013832)
			(xy 290.90616 -124.14003) (xy 290.790925 -124.260882) (xy 290.670071 -124.376114) (xy 290.54387 -124.485465)
			(xy 290.412609 -124.588688) (xy 290.276585 -124.685548) (xy 290.136106 -124.775826) (xy 289.991491 -124.859317)
			(xy 289.843067 -124.935833) (xy 289.691171 -125.0052) (xy 289.536146 -125.067261) (xy 289.378343 -125.121875)
			(xy 289.218121 -125.168919) (xy 289.055841 -125.208285) (xy 288.891873 -125.239886) (xy 288.726586 -125.263649)
			(xy 288.560356 -125.27952) (xy 288.393559 -125.287464) (xy 288.310066 -125.28804) (xy 139.910058 -125.28804)
			(xy 139.826564 -125.287542) (xy 139.659766 -125.279595) (xy 139.493535 -125.26372) (xy 139.328247 -125.239954)
			(xy 139.164277 -125.20835) (xy 139.001997 -125.168979) (xy 138.841774 -125.121932) (xy 138.683971 -125.067315)
			(xy 138.528946 -125.005251) (xy 138.377049 -124.935881) (xy 138.228625 -124.859362) (xy 138.08401 -124.775868)
			(xy 137.943531 -124.685588) (xy 137.807507 -124.588725) (xy 137.676246 -124.4855) (xy 137.550046 -124.376146)
			(xy 137.429191 -124.260912) (xy 137.313956 -124.140057) (xy 137.204603 -124.013857) (xy 137.101377 -123.882596)
			(xy 137.004515 -123.746572) (xy 136.914234 -123.606094) (xy 136.830739 -123.461479) (xy 136.75422 -123.313055)
			(xy 136.68485 -123.161158) (xy 136.622786 -123.006132) (xy 136.568169 -122.848329) (xy 136.521122 -122.688106)
			(xy 136.481751 -122.525826) (xy 136.450147 -122.361857) (xy 136.42638 -122.196569) (xy 136.410505 -122.030338)
			(xy 136.402558 -121.86354) (xy 136.402064 -121.780046) (xy 136.402064 -107.00004) (xy 136.401556 -106.944232)
			(xy 136.393218 -106.832928) (xy 136.376585 -106.722558) (xy 136.35175 -106.61374) (xy 136.318853 -106.507082)
			(xy 136.278076 -106.403181) (xy 136.229649 -106.302618) (xy 136.173842 -106.205955) (xy 136.110967 -106.113733)
			(xy 136.041377 -106.026468) (xy 135.965459 -105.944647) (xy 135.883638 -105.868729) (xy 135.796373 -105.799137)
			(xy 135.704152 -105.736262) (xy 135.607489 -105.680455) (xy 135.506926 -105.632027) (xy 135.403025 -105.59125)
			(xy 135.296368 -105.558352) (xy 135.18755 -105.533517) (xy 135.07718 -105.516883) (xy 134.965876 -105.508544)
			(xy 134.910068 -105.508044) (xy 95.999808 -105.508044) (xy 95.899276 -105.508543) (xy 95.698376 -105.516639)
			(xy 95.497964 -105.532817) (xy 95.298366 -105.557053) (xy 95.099907 -105.589305) (xy 94.902906 -105.629523)
			(xy 94.707685 -105.67764) (xy 94.51456 -105.73358) (xy 94.323844 -105.79725) (xy 94.135846 -105.868548)
			(xy 93.950872 -105.947358) (xy 93.769221 -106.033552) (xy 93.591188 -106.126991) (xy 93.417061 -106.227522)
			(xy 93.247124 -106.334984) (xy 93.081652 -106.449201) (xy 92.920913 -106.569988) (xy 92.765169 -106.69715)
			(xy 92.61467 -106.83048) (xy 92.469663 -106.969761) (xy 92.330381 -107.114769) (xy 92.197051 -107.265267)
			(xy 92.06989 -107.421012) (xy 91.949102 -107.581751) (xy 91.834885 -107.747223) (xy 91.727424 -107.91716)
			(xy 91.626892 -108.091286) (xy 91.533453 -108.269319) (xy 91.447259 -108.45097) (xy 91.368448 -108.635944)
			(xy 91.29715 -108.823942) (xy 91.23348 -109.014658) (xy 91.177541 -109.207783) (xy 91.129423 -109.403004)
			(xy 91.089206 -109.600005) (xy 91.056953 -109.798465) (xy 91.032718 -109.998062) (xy 91.016539 -110.198474)
			(xy 91.008443 -110.399374) (xy 91.007946 -110.499906) (xy 91.007946 -187.606178) (xy 91.007462 -187.676532)
			(xy 90.999574 -187.817018) (xy 90.983821 -187.956841) (xy 90.960252 -188.095561) (xy 90.928942 -188.232741)
			(xy 90.88999 -188.36795) (xy 90.843517 -188.500762) (xy 90.789671 -188.630759) (xy 90.72862 -188.757532)
			(xy 90.660557 -188.880683) (xy 90.585696 -188.999823) (xy 90.504272 -189.114579) (xy 90.416542 -189.224588)
			(xy 90.322781 -189.329506) (xy 90.223285 -189.429) (xy 90.118367 -189.52276) (xy 90.008357 -189.610489)
			(xy 89.8936 -189.691911) (xy 89.774459 -189.766771) (xy 89.651307 -189.834833) (xy 89.524533 -189.895882)
			(xy 89.394536 -189.949727) (xy 89.261723 -189.996198) (xy 89.126514 -190.035149) (xy 88.989334 -190.066457)
			(xy 88.850614 -190.090024) (xy 88.71079 -190.105776) (xy 88.570304 -190.113663) (xy 88.49995 -190.114174)
			(xy 28.42387 -190.114174) (xy 28.353517 -190.11368) (xy 28.213033 -190.105789) (xy 28.073211 -190.090033)
			(xy 27.934494 -190.066462) (xy 27.797316 -190.035151) (xy 27.66211 -189.996197) (xy 27.5293 -189.949723)
			(xy 27.399305 -189.895876) (xy 27.272534 -189.834824) (xy 27.149386 -189.766761) (xy 27.030248 -189.691899)
			(xy 26.915494 -189.610476) (xy 26.805487 -189.522746) (xy 26.700572 -189.428986) (xy 26.601078 -189.329491)
			(xy 26.507321 -189.224573) (xy 26.419593 -189.114564) (xy 26.338172 -188.999809) (xy 26.263313 -188.880669)
			(xy 26.195252 -188.757519) (xy 26.134203 -188.630747) (xy 26.080358 -188.500751) (xy 26.033887 -188.367941)
			(xy 25.994936 -188.232734) (xy 25.963628 -188.095555) (xy 25.94006 -187.956837) (xy 25.924307 -187.817016)
			(xy 25.916419 -187.676531) (xy 25.915874 -187.606178) (xy 25.915874 -163.299902) (xy 25.915393 -163.229997)
			(xy 25.907553 -163.090407) (xy 25.8919 -162.951476) (xy 25.868481 -162.813642) (xy 25.83737 -162.677337)
			(xy 25.798666 -162.542992) (xy 25.752489 -162.411028) (xy 25.698986 -162.28186) (xy 25.638325 -162.155896)
			(xy 25.570696 -162.033531) (xy 25.496312 -161.915151) (xy 25.415408 -161.801128) (xy 25.328237 -161.69182)
			(xy 25.235075 -161.587572) (xy 25.136214 -161.488712) (xy 25.031966 -161.395551) (xy 24.922658 -161.308381)
			(xy 24.808634 -161.227478) (xy 24.690253 -161.153095) (xy 24.567888 -161.085467) (xy 24.441923 -161.024807)
			(xy 24.312756 -160.971304) (xy 24.180791 -160.925129) (xy 24.046445 -160.886426) (xy 23.91014 -160.855316)
			(xy 23.772306 -160.831898) (xy 23.633375 -160.816245) (xy 23.493785 -160.808407) (xy 23.42388 -160.807908)
			(xy 1.999996 -160.807908) (xy 1.944189 -160.80843) (xy 1.832887 -160.816771) (xy 1.72252 -160.833407)
			(xy 1.613705 -160.858243) (xy 1.50705 -160.891142) (xy 1.403152 -160.93192) (xy 1.302591 -160.980347)
			(xy 1.205931 -161.036154) (xy 1.113712 -161.099029) (xy 1.026449 -161.168619) (xy 0.94463 -161.244536)
			(xy 0.868714 -161.326355) (xy 0.799124 -161.413618) (xy 0.73625 -161.505838) (xy 0.680444 -161.602499)
			(xy 0.632016 -161.703059) (xy 0.59124 -161.806958) (xy 0.558341 -161.913613) (xy 0.533505 -162.022428)
			(xy 0.51687 -162.132795) (xy 0.50853 -162.244097) (xy 0.508 -162.299904) (xy 0.508 -194.670734) (xy 2.904225 -194.670734)
			(xy 2.904225 -194.541594) (xy 2.912175 -194.412699) (xy 2.928045 -194.284539) (xy 2.951774 -194.157598)
			(xy 2.983273 -194.032359) (xy 3.022422 -193.909296) (xy 3.069073 -193.788877) (xy 3.123048 -193.671558)
			(xy 3.184143 -193.557784) (xy 3.252126 -193.447987) (xy 3.32674 -193.342584) (xy 3.407701 -193.241974)
			(xy 3.494701 -193.146539) (xy 3.587412 -193.05664) (xy 3.685482 -192.972619) (xy 3.788537 -192.894795)
			(xy 3.896188 -192.823463) (xy 4.008027 -192.758893) (xy 4.123628 -192.701331) (xy 4.242553 -192.650994)
			(xy 4.364352 -192.608074) (xy 4.488562 -192.572733) (xy 4.614711 -192.545106) (xy 4.742323 -192.525297)
			(xy 4.870912 -192.513381) (xy 4.99999 -192.509405) (xy 5.129068 -192.513381) (xy 5.257657 -192.525297)
			(xy 5.385269 -192.545106) (xy 5.511418 -192.572733) (xy 5.635628 -192.608074) (xy 5.757427 -192.650994)
			(xy 5.876352 -192.701331) (xy 5.991953 -192.758893) (xy 6.103792 -192.823463) (xy 6.211443 -192.894795)
			(xy 6.314498 -192.972619) (xy 6.412568 -193.05664) (xy 6.505279 -193.146539) (xy 6.592279 -193.241974)
			(xy 6.67324 -193.342584) (xy 6.747854 -193.447987) (xy 6.815837 -193.557784) (xy 6.876932 -193.671558)
			(xy 6.930907 -193.788877) (xy 6.977558 -193.909296) (xy 7.016707 -194.032359) (xy 7.048206 -194.157598)
			(xy 7.071935 -194.284539) (xy 7.087805 -194.412699) (xy 7.095755 -194.541594) (xy 7.096252 -194.606164)
			(xy 7.095755 -194.670734) (xy 468.904309 -194.670734) (xy 468.904309 -194.541594) (xy 468.912259 -194.412699)
			(xy 468.928129 -194.284539) (xy 468.951858 -194.157598) (xy 468.983357 -194.032359) (xy 469.022506 -193.909296)
			(xy 469.069157 -193.788877) (xy 469.123132 -193.671558) (xy 469.184227 -193.557784) (xy 469.25221 -193.447987)
			(xy 469.326824 -193.342584) (xy 469.407785 -193.241974) (xy 469.494785 -193.146539) (xy 469.587496 -193.05664)
			(xy 469.685566 -192.972619) (xy 469.788621 -192.894795) (xy 469.896272 -192.823463) (xy 470.008111 -192.758893)
			(xy 470.123712 -192.701331) (xy 470.242637 -192.650994) (xy 470.364436 -192.608074) (xy 470.488646 -192.572733)
			(xy 470.614795 -192.545106) (xy 470.742407 -192.525297) (xy 470.870996 -192.513381) (xy 471.000074 -192.509405)
			(xy 471.129152 -192.513381) (xy 471.257741 -192.525297) (xy 471.385353 -192.545106) (xy 471.511502 -192.572733)
			(xy 471.635712 -192.608074) (xy 471.757511 -192.650994) (xy 471.876436 -192.701331) (xy 471.992037 -192.758893)
			(xy 472.103876 -192.823463) (xy 472.211527 -192.894795) (xy 472.314582 -192.972619) (xy 472.412652 -193.05664)
			(xy 472.505363 -193.146539) (xy 472.592363 -193.241974) (xy 472.673324 -193.342584) (xy 472.747938 -193.447987)
			(xy 472.815921 -193.557784) (xy 472.877016 -193.671558) (xy 472.930991 -193.788877) (xy 472.977642 -193.909296)
			(xy 473.016791 -194.032359) (xy 473.04829 -194.157598) (xy 473.072019 -194.284539) (xy 473.087889 -194.412699)
			(xy 473.095839 -194.541594) (xy 473.096336 -194.606164) (xy 473.095839 -194.670734) (xy 473.087889 -194.799629)
			(xy 473.072019 -194.927789) (xy 473.04829 -195.05473) (xy 473.016791 -195.179969) (xy 472.977642 -195.303032)
			(xy 472.930991 -195.423451) (xy 472.877016 -195.54077) (xy 472.815921 -195.654544) (xy 472.747938 -195.764341)
			(xy 472.673324 -195.869744) (xy 472.592363 -195.970354) (xy 472.505363 -196.065789) (xy 472.412652 -196.155688)
			(xy 472.314582 -196.239709) (xy 472.211527 -196.317533) (xy 472.103876 -196.388865) (xy 471.992037 -196.453435)
			(xy 471.876436 -196.510997) (xy 471.757511 -196.561334) (xy 471.635712 -196.604254) (xy 471.511502 -196.639595)
			(xy 471.385353 -196.667222) (xy 471.257741 -196.687031) (xy 471.129152 -196.698947) (xy 471.000074 -196.702924)
			(xy 470.870996 -196.698947) (xy 470.742407 -196.687031) (xy 470.614795 -196.667222) (xy 470.488646 -196.639595)
			(xy 470.364436 -196.604254) (xy 470.242637 -196.561334) (xy 470.123712 -196.510997) (xy 470.008111 -196.453435)
			(xy 469.896272 -196.388865) (xy 469.788621 -196.317533) (xy 469.685566 -196.239709) (xy 469.587496 -196.155688)
			(xy 469.494785 -196.065789) (xy 469.407785 -195.970354) (xy 469.326824 -195.869744) (xy 469.25221 -195.764341)
			(xy 469.184227 -195.654544) (xy 469.123132 -195.54077) (xy 469.069157 -195.423451) (xy 469.022506 -195.303032)
			(xy 468.983357 -195.179969) (xy 468.951858 -195.05473) (xy 468.928129 -194.927789) (xy 468.912259 -194.799629)
			(xy 468.904309 -194.670734) (xy 7.095755 -194.670734) (xy 7.087805 -194.799629) (xy 7.071935 -194.927789)
			(xy 7.048206 -195.05473) (xy 7.016707 -195.179969) (xy 6.977558 -195.303032) (xy 6.930907 -195.423451)
			(xy 6.876932 -195.54077) (xy 6.815837 -195.654544) (xy 6.747854 -195.764341) (xy 6.67324 -195.869744)
			(xy 6.592279 -195.970354) (xy 6.505279 -196.065789) (xy 6.412568 -196.155688) (xy 6.314498 -196.239709)
			(xy 6.211443 -196.317533) (xy 6.103792 -196.388865) (xy 5.991953 -196.453435) (xy 5.876352 -196.510997)
			(xy 5.757427 -196.561334) (xy 5.635628 -196.604254) (xy 5.511418 -196.639595) (xy 5.385269 -196.667222)
			(xy 5.257657 -196.687031) (xy 5.129068 -196.698947) (xy 4.99999 -196.702924) (xy 4.870912 -196.698947)
			(xy 4.742323 -196.687031) (xy 4.614711 -196.667222) (xy 4.488562 -196.639595) (xy 4.364352 -196.604254)
			(xy 4.242553 -196.561334) (xy 4.123628 -196.510997) (xy 4.008027 -196.453435) (xy 3.896188 -196.388865)
			(xy 3.788537 -196.317533) (xy 3.685482 -196.239709) (xy 3.587412 -196.155688) (xy 3.494701 -196.065789)
			(xy 3.407701 -195.970354) (xy 3.32674 -195.869744) (xy 3.252126 -195.764341) (xy 3.184143 -195.654544)
			(xy 3.123048 -195.54077) (xy 3.069073 -195.423451) (xy 3.022422 -195.303032) (xy 2.983273 -195.179969)
			(xy 2.951774 -195.05473) (xy 2.928045 -194.927789) (xy 2.912175 -194.799629) (xy 2.904225 -194.670734)
			(xy 0.508 -194.670734) (xy 0.508 -197.606158) (xy 0.508522 -197.661965) (xy 0.516863 -197.773267)
			(xy 0.533498 -197.883634) (xy 0.558335 -197.99245) (xy 0.591234 -198.099105) (xy 0.632011 -198.203004)
			(xy 0.680438 -198.303564) (xy 0.736246 -198.400225) (xy 0.79912 -198.492445) (xy 0.86871 -198.579708)
			(xy 0.944627 -198.661527) (xy 1.026446 -198.737444) (xy 1.113709 -198.807034) (xy 1.205929 -198.869908)
			(xy 1.30259 -198.925716) (xy 1.40315 -198.974143) (xy 1.507049 -199.01492) (xy 1.613704 -199.047819)
			(xy 1.72252 -199.072656) (xy 1.832887 -199.089291) (xy 1.944189 -199.097632) (xy 1.999996 -199.098154)
		)
		(stroke
			(width 0)
			(type solid)
		)
		(fill yes)
		(layer "In6.Cu")
		(net "GND3")
	)
	(gr_poly
		(pts
			(xy 75.000104 -171.140882) (xy 75.095437 -171.140376) (xy 75.285932 -171.132284) (xy 75.475912 -171.116114)
			(xy 75.665035 -171.091896) (xy 75.852959 -171.059673) (xy 76.039346 -171.019503) (xy 76.223861 -170.971459)
			(xy 76.40617 -170.915628) (xy 76.585945 -170.852109) (xy 76.762863 -170.781017) (xy 76.936604 -170.702482)
			(xy 77.106855 -170.616643) (xy 77.27331 -170.523655) (xy 77.435668 -170.423687) (xy 77.593638 -170.316919)
			(xy 77.746933 -170.203542) (xy 77.895279 -170.083761) (xy 78.038407 -169.957793) (xy 78.17606 -169.825863)
			(xy 78.30799 -169.68821) (xy 78.433959 -169.545082) (xy 78.55374 -169.396736) (xy 78.667117 -169.243441)
			(xy 78.773885 -169.085472) (xy 78.873853 -168.923113) (xy 78.966841 -168.756659) (xy 79.05268 -168.586408)
			(xy 79.131216 -168.412667) (xy 79.202307 -168.235749) (xy 79.265826 -168.055974) (xy 79.321658 -167.873665)
			(xy 79.369702 -167.68915) (xy 79.409872 -167.502763) (xy 79.442095 -167.314839) (xy 79.466314 -167.125716)
			(xy 79.482484 -166.935736) (xy 79.490576 -166.745241) (xy 79.491078 -166.649908) (xy 79.491078 -161.28111)
			(xy 79.497763 -161.194561) (xy 79.518105 -161.022146) (xy 79.546364 -160.850851) (xy 79.582482 -160.681039)
			(xy 79.626381 -160.51307) (xy 79.677968 -160.347301) (xy 79.737135 -160.184083) (xy 79.803755 -160.023764)
			(xy 79.877687 -159.866682) (xy 79.958774 -159.713171) (xy 80.046845 -159.563557) (xy 80.141711 -159.418158)
			(xy 80.243173 -159.277281) (xy 80.351014 -159.141227) (xy 80.465007 -159.010282) (xy 80.584908 -158.884726)
			(xy 80.710464 -158.764825) (xy 80.841408 -158.650833) (xy 80.977463 -158.542992) (xy 81.11834 -158.44153)
			(xy 81.263739 -158.346663) (xy 81.413353 -158.258593) (xy 81.566864 -158.177506) (xy 81.723946 -158.103574)
			(xy 81.884265 -158.036954) (xy 82.047483 -157.977788) (xy 82.213252 -157.9262) (xy 82.381221 -157.882301)
			(xy 82.551033 -157.846184) (xy 82.722328 -157.817924) (xy 82.894743 -157.797583) (xy 82.981292 -157.790896)
			(xy 83.49996 -157.790896) (xy 83.595294 -157.790398) (xy 83.785791 -157.782307) (xy 83.975773 -157.766139)
			(xy 84.164897 -157.741923) (xy 84.352823 -157.709701) (xy 84.539213 -157.669533) (xy 84.723729 -157.62149)
			(xy 84.90604 -157.565659) (xy 85.085818 -157.502142) (xy 85.262738 -157.431051) (xy 85.436481 -157.352516)
			(xy 85.606734 -157.266677) (xy 85.773191 -157.173691) (xy 85.935552 -157.073723) (xy 86.093523 -156.966955)
			(xy 86.246821 -156.853578) (xy 86.395169 -156.733797) (xy 86.538299 -156.607828) (xy 86.675955 -156.475898)
			(xy 86.807886 -156.338245) (xy 86.933857 -156.195116) (xy 87.05364 -156.04677) (xy 87.167019 -155.893474)
			(xy 87.273789 -155.735504) (xy 87.373759 -155.573145) (xy 87.466748 -155.406689) (xy 87.552589 -155.236437)
			(xy 87.631127 -155.062695) (xy 87.70222 -154.885776) (xy 87.76574 -154.705999) (xy 87.821573 -154.523689)
			(xy 87.869618 -154.339173) (xy 87.909789 -154.152784) (xy 87.942013 -153.964858) (xy 87.966233 -153.775734)
			(xy 87.982404 -153.585753) (xy 87.990497 -153.395256) (xy 87.990934 -153.299922) (xy 87.990934 -110.499906)
			(xy 87.991432 -110.374101) (xy 87.999343 -110.122617) (xy 88.015149 -109.871504) (xy 88.038834 -109.621013)
			(xy 88.070376 -109.371388) (xy 88.109743 -109.122878) (xy 88.156896 -108.875727) (xy 88.211788 -108.630178)
			(xy 88.274366 -108.386475) (xy 88.344568 -108.144858) (xy 88.422324 -107.905565) (xy 88.507557 -107.668832)
			(xy 88.600185 -107.434893) (xy 88.700114 -107.203979) (xy 88.807248 -106.976318) (xy 88.921479 -106.752134)
			(xy 89.042695 -106.531649) (xy 89.170776 -106.315079) (xy 89.305597 -106.10264) (xy 89.447024 -105.89454)
			(xy 89.594918 -105.690985) (xy 89.749132 -105.492175) (xy 89.909514 -105.298308) (xy 90.075907 -105.109574)
			(xy 90.248145 -104.926159) (xy 90.42606 -104.748244) (xy 90.609475 -104.576006) (xy 90.798209 -104.409613)
			(xy 90.992077 -104.249231) (xy 91.190887 -104.095017) (xy 91.394442 -103.947123) (xy 91.602542 -103.805696)
			(xy 91.814981 -103.670875) (xy 92.03155 -103.542794) (xy 92.252036 -103.421578) (xy 92.47622 -103.307347)
			(xy 92.703881 -103.200214) (xy 92.934795 -103.100284) (xy 93.168734 -103.007657) (xy 93.405467 -102.922423)
			(xy 93.64476 -102.844667) (xy 93.886377 -102.774465) (xy 94.13008 -102.711888) (xy 94.375628 -102.656995)
			(xy 94.62278 -102.609842) (xy 94.87129 -102.570476) (xy 95.120915 -102.538934) (xy 95.371406 -102.515249)
			(xy 95.622519 -102.499443) (xy 95.874003 -102.491532) (xy 95.999808 -102.491032) (xy 318.10579 -102.491032)
			(xy 318.106806 -102.492048) (xy 319.051686 -102.492048) (xy 319.052702 -102.491032) (xy 344.000074 -102.491032)
			(xy 344.12588 -102.491521) (xy 344.377368 -102.499423) (xy 344.628483 -102.515221) (xy 344.878979 -102.538899)
			(xy 345.128607 -102.570434) (xy 345.377121 -102.609794) (xy 345.624276 -102.656941) (xy 345.869829 -102.711827)
			(xy 346.113536 -102.7744) (xy 346.355158 -102.844597) (xy 346.594455 -102.922349) (xy 346.831192 -103.007579)
			(xy 347.065135 -103.100203) (xy 347.296054 -103.20013) (xy 347.523719 -103.30726) (xy 347.747907 -103.421489)
			(xy 347.968397 -103.542704) (xy 348.18497 -103.670784) (xy 348.397413 -103.805604) (xy 348.605517 -103.947031)
			(xy 348.809076 -104.094924) (xy 349.007888 -104.249139) (xy 349.201759 -104.409522) (xy 349.36105 -104.549956)
			(xy 422.484046 -104.549956) (xy 422.488076 -104.407621) (xy 422.500151 -104.265741) (xy 422.520234 -104.124773)
			(xy 422.548261 -103.985166) (xy 422.584141 -103.847368) (xy 422.627759 -103.711821) (xy 422.678976 -103.578959)
			(xy 422.737627 -103.449207) (xy 422.803525 -103.322981) (xy 422.876459 -103.200685) (xy 422.956196 -103.082712)
			(xy 423.042478 -102.969439) (xy 423.135031 -102.861228) (xy 423.233558 -102.758427) (xy 423.337743 -102.661365)
			(xy 423.447252 -102.570353) (xy 423.561735 -102.485681) (xy 423.680825 -102.407623) (xy 423.80414 -102.336427)
			(xy 423.931286 -102.272321) (xy 424.061855 -102.215512) (xy 424.195429 -102.16618) (xy 424.33158 -102.124484)
			(xy 424.469871 -102.090558) (xy 424.609861 -102.06451) (xy 424.7511 -102.046424) (xy 424.893136 -102.036357)
			(xy 425.035514 -102.034342) (xy 425.177778 -102.040385) (xy 425.319472 -102.054467) (xy 425.460142 -102.076543)
			(xy 425.599339 -102.106543) (xy 425.736615 -102.144369) (xy 425.871531 -102.189901) (xy 426.003655 -102.242992)
			(xy 426.132564 -102.303474) (xy 426.257845 -102.371152) (xy 426.379096 -102.445809) (xy 426.495929 -102.527207)
			(xy 426.60797 -102.615084) (xy 426.71486 -102.709159) (xy 426.816257 -102.809131) (xy 426.911835 -102.914679)
			(xy 427.001289 -103.025465) (xy 427.084331 -103.141134) (xy 427.160697 -103.261317) (xy 427.230141 -103.385627)
			(xy 427.292441 -103.513668) (xy 427.347397 -103.645027) (xy 427.394834 -103.779286) (xy 427.434598 -103.916013)
			(xy 427.466564 -104.054771) (xy 427.490629 -104.195115) (xy 427.506715 -104.336596) (xy 427.51477 -104.47876)
			(xy 427.515274 -104.549956) (xy 427.51477 -104.621152) (xy 427.506715 -104.763316) (xy 427.490629 -104.904797)
			(xy 427.466564 -105.045141) (xy 427.434598 -105.183899) (xy 427.394834 -105.320626) (xy 427.347397 -105.454885)
			(xy 427.292441 -105.586244) (xy 427.230141 -105.714285) (xy 427.160697 -105.838595) (xy 427.084331 -105.958778)
			(xy 427.001289 -106.074447) (xy 426.911835 -106.185233) (xy 426.816257 -106.290781) (xy 426.71486 -106.390753)
			(xy 426.60797 -106.484828) (xy 426.495929 -106.572705) (xy 426.379096 -106.654103) (xy 426.257845 -106.72876)
			(xy 426.132564 -106.796438) (xy 426.003655 -106.85692) (xy 425.871531 -106.910011) (xy 425.736615 -106.955543)
			(xy 425.599339 -106.993369) (xy 425.460142 -107.023369) (xy 425.319472 -107.045445) (xy 425.177778 -107.059527)
			(xy 425.035514 -107.06557) (xy 424.893136 -107.063555) (xy 424.7511 -107.053488) (xy 424.609861 -107.035402)
			(xy 424.469871 -107.009354) (xy 424.33158 -106.975428) (xy 424.195429 -106.933732) (xy 424.061855 -106.8844)
			(xy 423.931286 -106.827591) (xy 423.80414 -106.763485) (xy 423.680825 -106.692289) (xy 423.561735 -106.614231)
			(xy 423.447252 -106.529559) (xy 423.337743 -106.438547) (xy 423.233558 -106.341485) (xy 423.135031 -106.238684)
			(xy 423.042478 -106.130473) (xy 422.956196 -106.0172) (xy 422.876459 -105.899227) (xy 422.803525 -105.776931)
			(xy 422.737627 -105.650705) (xy 422.678976 -105.520953) (xy 422.627759 -105.388091) (xy 422.584141 -105.252544)
			(xy 422.548261 -105.114746) (xy 422.520234 -104.975139) (xy 422.500151 -104.834171) (xy 422.488076 -104.692291)
			(xy 422.484046 -104.549956) (xy 349.36105 -104.549956) (xy 349.390496 -104.575916) (xy 349.573914 -104.748156)
			(xy 349.75183 -104.926072) (xy 349.924071 -105.109489) (xy 350.090465 -105.298226) (xy 350.250849 -105.492096)
			(xy 350.405064 -105.690908) (xy 350.552958 -105.894467) (xy 350.694385 -106.10257) (xy 350.829205 -106.315013)
			(xy 350.957286 -106.531586) (xy 351.078501 -106.752075) (xy 351.192731 -106.976263) (xy 351.299862 -107.203928)
			(xy 351.399789 -107.434846) (xy 351.492414 -107.668789) (xy 351.577645 -107.905526) (xy 351.655397 -108.144823)
			(xy 351.725595 -108.386444) (xy 351.788168 -108.630152) (xy 351.843055 -108.875704) (xy 351.890203 -109.122859)
			(xy 351.929563 -109.371373) (xy 351.961098 -109.621001) (xy 351.984777 -109.871497) (xy 352.000576 -110.122612)
			(xy 352.008479 -110.3741) (xy 352.008948 -110.499906) (xy 352.008948 -111.879888) (xy 377.061232 -111.879888)
			(xy 377.065214 -111.789938) (xy 377.077131 -111.700691) (xy 377.096889 -111.612847) (xy 377.124333 -111.527093)
			(xy 377.159249 -111.4441) (xy 377.201363 -111.364518) (xy 377.250346 -111.288969) (xy 377.305814 -111.218045)
			(xy 377.367334 -111.1523) (xy 377.434423 -111.09225) (xy 377.506557 -111.038365) (xy 377.583171 -110.991065)
			(xy 377.663665 -110.950722) (xy 377.74741 -110.91765) (xy 377.833751 -110.89211) (xy 377.92201 -110.8743)
			(xy 378.011499 -110.86436) (xy 378.101515 -110.862369) (xy 378.191356 -110.86834) (xy 378.280317 -110.882229)
			(xy 378.367702 -110.903925) (xy 378.452828 -110.93326) (xy 378.535028 -110.970003) (xy 378.613659 -111.013867)
			(xy 378.688106 -111.064509) (xy 378.757786 -111.121533) (xy 378.822153 -111.184492) (xy 378.880704 -111.252893)
			(xy 378.932981 -111.326201) (xy 378.978574 -111.403843) (xy 379.017127 -111.48521) (xy 379.048338 -111.569666)
			(xy 379.071962 -111.65655) (xy 379.087815 -111.745182) (xy 379.095772 -111.834869) (xy 379.09627 -111.879888)
			(xy 396.619232 -111.879888) (xy 396.623214 -111.789938) (xy 396.635131 -111.700691) (xy 396.654889 -111.612847)
			(xy 396.682333 -111.527093) (xy 396.717249 -111.4441) (xy 396.759363 -111.364518) (xy 396.808346 -111.288969)
			(xy 396.863814 -111.218045) (xy 396.925334 -111.1523) (xy 396.992423 -111.09225) (xy 397.064557 -111.038365)
			(xy 397.141171 -110.991065) (xy 397.221665 -110.950722) (xy 397.30541 -110.91765) (xy 397.391751 -110.89211)
			(xy 397.48001 -110.8743) (xy 397.569499 -110.86436) (xy 397.659515 -110.862369) (xy 397.749356 -110.86834)
			(xy 397.838317 -110.882229) (xy 397.925702 -110.903925) (xy 398.010828 -110.93326) (xy 398.093028 -110.970003)
			(xy 398.171659 -111.013867) (xy 398.246106 -111.064509) (xy 398.315786 -111.121533) (xy 398.380153 -111.184492)
			(xy 398.438704 -111.252893) (xy 398.490981 -111.326201) (xy 398.536574 -111.403843) (xy 398.575127 -111.48521)
			(xy 398.606338 -111.569666) (xy 398.629962 -111.65655) (xy 398.645815 -111.745182) (xy 398.653772 -111.834869)
			(xy 398.65427 -111.879888) (xy 398.653772 -111.924907) (xy 398.645815 -112.014594) (xy 398.629962 -112.103226)
			(xy 398.606338 -112.19011) (xy 398.575127 -112.274566) (xy 398.536574 -112.355933) (xy 398.490981 -112.433575)
			(xy 398.438704 -112.506883) (xy 398.380153 -112.575284) (xy 398.315786 -112.638243) (xy 398.246106 -112.695267)
			(xy 398.171659 -112.745909) (xy 398.093028 -112.789773) (xy 398.010828 -112.826516) (xy 397.925702 -112.855851)
			(xy 397.838317 -112.877547) (xy 397.749356 -112.891436) (xy 397.659515 -112.897407) (xy 397.569499 -112.895416)
			(xy 397.48001 -112.885476) (xy 397.391751 -112.867666) (xy 397.30541 -112.842126) (xy 397.221665 -112.809054)
			(xy 397.141171 -112.768711) (xy 397.064557 -112.721411) (xy 396.992423 -112.667526) (xy 396.925334 -112.607476)
			(xy 396.863814 -112.541731) (xy 396.808346 -112.470807) (xy 396.759363 -112.395258) (xy 396.717249 -112.315676)
			(xy 396.682333 -112.232683) (xy 396.654889 -112.146929) (xy 396.635131 -112.059085) (xy 396.623214 -111.969838)
			(xy 396.619232 -111.879888) (xy 379.09627 -111.879888) (xy 379.095772 -111.924907) (xy 379.087815 -112.014594)
			(xy 379.071962 -112.103226) (xy 379.048338 -112.19011) (xy 379.017127 -112.274566) (xy 378.978574 -112.355933)
			(xy 378.932981 -112.433575) (xy 378.880704 -112.506883) (xy 378.822153 -112.575284) (xy 378.757786 -112.638243)
			(xy 378.688106 -112.695267) (xy 378.613659 -112.745909) (xy 378.535028 -112.789773) (xy 378.452828 -112.826516)
			(xy 378.367702 -112.855851) (xy 378.280317 -112.877547) (xy 378.191356 -112.891436) (xy 378.101515 -112.897407)
			(xy 378.011499 -112.895416) (xy 377.92201 -112.885476) (xy 377.833751 -112.867666) (xy 377.74741 -112.842126)
			(xy 377.663665 -112.809054) (xy 377.583171 -112.768711) (xy 377.506557 -112.721411) (xy 377.434423 -112.667526)
			(xy 377.367334 -112.607476) (xy 377.305814 -112.541731) (xy 377.250346 -112.470807) (xy 377.201363 -112.395258)
			(xy 377.159249 -112.315676) (xy 377.124333 -112.232683) (xy 377.096889 -112.146929) (xy 377.077131 -112.059085)
			(xy 377.065214 -111.969838) (xy 377.061232 -111.879888) (xy 352.008948 -111.879888) (xy 352.008948 -119.38)
			(xy 376.553741 -119.38) (xy 376.557716 -119.269941) (xy 376.569624 -119.160455) (xy 376.5894 -119.052114)
			(xy 376.616943 -118.945483) (xy 376.652108 -118.841117) (xy 376.694712 -118.73956) (xy 376.744533 -118.641343)
			(xy 376.801312 -118.546976) (xy 376.864751 -118.456952) (xy 376.934522 -118.371741) (xy 377.010259 -118.291786)
			(xy 377.091568 -118.217505) (xy 377.178025 -118.149285) (xy 377.269179 -118.08748) (xy 377.364556 -118.032415)
			(xy 377.463657 -117.984375) (xy 377.565966 -117.943611) (xy 377.67095 -117.910336) (xy 377.778061 -117.884723)
			(xy 377.886741 -117.866906) (xy 377.996424 -117.856977) (xy 378.106537 -117.854989) (xy 378.216507 -117.860951)
			(xy 378.32576 -117.874833) (xy 378.433726 -117.896563) (xy 378.539843 -117.926026) (xy 378.643557 -117.963069)
			(xy 378.744328 -118.0075) (xy 378.84163 -118.059087) (xy 378.934956 -118.117559) (xy 379.023819 -118.182614)
			(xy 379.107757 -118.253912) (xy 379.186332 -118.33108) (xy 379.259133 -118.413717) (xy 379.325781 -118.501391)
			(xy 379.38593 -118.593647) (xy 379.439264 -118.690002) (xy 379.485507 -118.789954) (xy 379.524417 -118.892982)
			(xy 379.555791 -118.99855) (xy 379.579466 -119.106106) (xy 379.595318 -119.21509) (xy 379.603265 -119.324934)
			(xy 379.603762 -119.38) (xy 396.111741 -119.38) (xy 396.115716 -119.269941) (xy 396.127624 -119.160455)
			(xy 396.1474 -119.052114) (xy 396.174943 -118.945483) (xy 396.210108 -118.841117) (xy 396.252712 -118.73956)
			(xy 396.302533 -118.641343) (xy 396.359312 -118.546976) (xy 396.422751 -118.456952) (xy 396.492522 -118.371741)
			(xy 396.568259 -118.291786) (xy 396.649568 -118.217505) (xy 396.736025 -118.149285) (xy 396.827179 -118.08748)
			(xy 396.922556 -118.032415) (xy 397.021657 -117.984375) (xy 397.123966 -117.943611) (xy 397.22895 -117.910336)
			(xy 397.336061 -117.884723) (xy 397.444741 -117.866906) (xy 397.554424 -117.856977) (xy 397.664537 -117.854989)
			(xy 397.774507 -117.860951) (xy 397.88376 -117.874833) (xy 397.991726 -117.896563) (xy 398.097843 -117.926026)
			(xy 398.201557 -117.963069) (xy 398.302328 -118.0075) (xy 398.39963 -118.059087) (xy 398.492956 -118.117559)
			(xy 398.581819 -118.182614) (xy 398.665757 -118.253912) (xy 398.744332 -118.33108) (xy 398.817133 -118.413717)
			(xy 398.883781 -118.501391) (xy 398.94393 -118.593647) (xy 398.997264 -118.690002) (xy 399.043507 -118.789954)
			(xy 399.082417 -118.892982) (xy 399.113791 -118.99855) (xy 399.137466 -119.106106) (xy 399.153318 -119.21509)
			(xy 399.161265 -119.324934) (xy 399.161762 -119.38) (xy 399.161265 -119.435066) (xy 399.153318 -119.54491)
			(xy 399.137466 -119.653894) (xy 399.113791 -119.76145) (xy 399.082417 -119.867018) (xy 399.043507 -119.970046)
			(xy 398.997264 -120.069998) (xy 398.94393 -120.166353) (xy 398.883781 -120.258609) (xy 398.817133 -120.346283)
			(xy 398.744332 -120.42892) (xy 398.665757 -120.506088) (xy 398.581819 -120.577386) (xy 398.492956 -120.642441)
			(xy 398.39963 -120.700913) (xy 398.302328 -120.7525) (xy 398.201557 -120.796931) (xy 398.097843 -120.833974)
			(xy 397.991726 -120.863437) (xy 397.88376 -120.885167) (xy 397.774507 -120.899049) (xy 397.664537 -120.905011)
			(xy 397.554424 -120.903023) (xy 397.444741 -120.893094) (xy 397.336061 -120.875277) (xy 397.22895 -120.849664)
			(xy 397.123966 -120.816389) (xy 397.021657 -120.775625) (xy 396.922556 -120.727585) (xy 396.827179 -120.67252)
			(xy 396.736025 -120.610715) (xy 396.649568 -120.542495) (xy 396.568259 -120.468214) (xy 396.492522 -120.388259)
			(xy 396.422751 -120.303048) (xy 396.359312 -120.213024) (xy 396.302533 -120.118657) (xy 396.252712 -120.02044)
			(xy 396.210108 -119.918883) (xy 396.174943 -119.814517) (xy 396.1474 -119.707886) (xy 396.127624 -119.599545)
			(xy 396.115716 -119.490059) (xy 396.111741 -119.38) (xy 379.603762 -119.38) (xy 379.603265 -119.435066)
			(xy 379.595318 -119.54491) (xy 379.579466 -119.653894) (xy 379.555791 -119.76145) (xy 379.524417 -119.867018)
			(xy 379.485507 -119.970046) (xy 379.439264 -120.069998) (xy 379.38593 -120.166353) (xy 379.325781 -120.258609)
			(xy 379.259133 -120.346283) (xy 379.186332 -120.42892) (xy 379.107757 -120.506088) (xy 379.023819 -120.577386)
			(xy 378.934956 -120.642441) (xy 378.84163 -120.700913) (xy 378.744328 -120.7525) (xy 378.643557 -120.796931)
			(xy 378.539843 -120.833974) (xy 378.433726 -120.863437) (xy 378.32576 -120.885167) (xy 378.216507 -120.899049)
			(xy 378.106537 -120.905011) (xy 377.996424 -120.903023) (xy 377.886741 -120.893094) (xy 377.778061 -120.875277)
			(xy 377.67095 -120.849664) (xy 377.565966 -120.816389) (xy 377.463657 -120.775625) (xy 377.364556 -120.727585)
			(xy 377.269179 -120.67252) (xy 377.178025 -120.610715) (xy 377.091568 -120.542495) (xy 377.010259 -120.468214)
			(xy 376.934522 -120.388259) (xy 376.864751 -120.303048) (xy 376.801312 -120.213024) (xy 376.744533 -120.118657)
			(xy 376.694712 -120.02044) (xy 376.652108 -119.918883) (xy 376.616943 -119.814517) (xy 376.5894 -119.707886)
			(xy 376.569624 -119.599545) (xy 376.557716 -119.490059) (xy 376.553741 -119.38) (xy 352.008948 -119.38)
			(xy 352.008948 -132.199888) (xy 377.061232 -132.199888) (xy 377.065214 -132.109938) (xy 377.077131 -132.020691)
			(xy 377.096889 -131.932847) (xy 377.124333 -131.847093) (xy 377.159249 -131.7641) (xy 377.201363 -131.684518)
			(xy 377.250346 -131.608969) (xy 377.305814 -131.538045) (xy 377.367334 -131.4723) (xy 377.434423 -131.41225)
			(xy 377.506557 -131.358365) (xy 377.583171 -131.311065) (xy 377.663665 -131.270722) (xy 377.74741 -131.23765)
			(xy 377.833751 -131.21211) (xy 377.92201 -131.1943) (xy 378.011499 -131.18436) (xy 378.101515 -131.182369)
			(xy 378.191356 -131.18834) (xy 378.280317 -131.202229) (xy 378.367702 -131.223925) (xy 378.452828 -131.25326)
			(xy 378.535028 -131.290003) (xy 378.613659 -131.333867) (xy 378.688106 -131.384509) (xy 378.757786 -131.441533)
			(xy 378.822153 -131.504492) (xy 378.880704 -131.572893) (xy 378.932981 -131.646201) (xy 378.978574 -131.723843)
			(xy 379.017127 -131.80521) (xy 379.048338 -131.889666) (xy 379.071962 -131.97655) (xy 379.087815 -132.065182)
			(xy 379.095772 -132.154869) (xy 379.09627 -132.199888) (xy 396.619232 -132.199888) (xy 396.623214 -132.109938)
			(xy 396.635131 -132.020691) (xy 396.654889 -131.932847) (xy 396.682333 -131.847093) (xy 396.717249 -131.7641)
			(xy 396.759363 -131.684518) (xy 396.808346 -131.608969) (xy 396.863814 -131.538045) (xy 396.925334 -131.4723)
			(xy 396.992423 -131.41225) (xy 397.064557 -131.358365) (xy 397.141171 -131.311065) (xy 397.221665 -131.270722)
			(xy 397.30541 -131.23765) (xy 397.391751 -131.21211) (xy 397.48001 -131.1943) (xy 397.569499 -131.18436)
			(xy 397.659515 -131.182369) (xy 397.749356 -131.18834) (xy 397.838317 -131.202229) (xy 397.925702 -131.223925)
			(xy 398.010828 -131.25326) (xy 398.093028 -131.290003) (xy 398.171659 -131.333867) (xy 398.246106 -131.384509)
			(xy 398.315786 -131.441533) (xy 398.380153 -131.504492) (xy 398.438704 -131.572893) (xy 398.490981 -131.646201)
			(xy 398.536574 -131.723843) (xy 398.575127 -131.80521) (xy 398.606338 -131.889666) (xy 398.629962 -131.97655)
			(xy 398.645815 -132.065182) (xy 398.653772 -132.154869) (xy 398.65427 -132.199888) (xy 398.653772 -132.244907)
			(xy 398.645815 -132.334594) (xy 398.629962 -132.423226) (xy 398.606338 -132.51011) (xy 398.575127 -132.594566)
			(xy 398.536574 -132.675933) (xy 398.490981 -132.753575) (xy 398.438704 -132.826883) (xy 398.380153 -132.895284)
			(xy 398.315786 -132.958243) (xy 398.246106 -133.015267) (xy 398.171659 -133.065909) (xy 398.093028 -133.109773)
			(xy 398.010828 -133.146516) (xy 397.925702 -133.175851) (xy 397.838317 -133.197547) (xy 397.749356 -133.211436)
			(xy 397.659515 -133.217407) (xy 397.569499 -133.215416) (xy 397.48001 -133.205476) (xy 397.391751 -133.187666)
			(xy 397.30541 -133.162126) (xy 397.221665 -133.129054) (xy 397.141171 -133.088711) (xy 397.064557 -133.041411)
			(xy 396.992423 -132.987526) (xy 396.925334 -132.927476) (xy 396.863814 -132.861731) (xy 396.808346 -132.790807)
			(xy 396.759363 -132.715258) (xy 396.717249 -132.635676) (xy 396.682333 -132.552683) (xy 396.654889 -132.466929)
			(xy 396.635131 -132.379085) (xy 396.623214 -132.289838) (xy 396.619232 -132.199888) (xy 379.09627 -132.199888)
			(xy 379.095772 -132.244907) (xy 379.087815 -132.334594) (xy 379.071962 -132.423226) (xy 379.048338 -132.51011)
			(xy 379.017127 -132.594566) (xy 378.978574 -132.675933) (xy 378.932981 -132.753575) (xy 378.880704 -132.826883)
			(xy 378.822153 -132.895284) (xy 378.757786 -132.958243) (xy 378.688106 -133.015267) (xy 378.613659 -133.065909)
			(xy 378.535028 -133.109773) (xy 378.452828 -133.146516) (xy 378.367702 -133.175851) (xy 378.280317 -133.197547)
			(xy 378.191356 -133.211436) (xy 378.101515 -133.217407) (xy 378.011499 -133.215416) (xy 377.92201 -133.205476)
			(xy 377.833751 -133.187666) (xy 377.74741 -133.162126) (xy 377.663665 -133.129054) (xy 377.583171 -133.088711)
			(xy 377.506557 -133.041411) (xy 377.434423 -132.987526) (xy 377.367334 -132.927476) (xy 377.305814 -132.861731)
			(xy 377.250346 -132.790807) (xy 377.201363 -132.715258) (xy 377.159249 -132.635676) (xy 377.124333 -132.552683)
			(xy 377.096889 -132.466929) (xy 377.077131 -132.379085) (xy 377.065214 -132.289838) (xy 377.061232 -132.199888)
			(xy 352.008948 -132.199888) (xy 352.008948 -139.7) (xy 376.553741 -139.7) (xy 376.557716 -139.589941)
			(xy 376.569624 -139.480455) (xy 376.5894 -139.372114) (xy 376.616943 -139.265483) (xy 376.652108 -139.161117)
			(xy 376.694712 -139.05956) (xy 376.744533 -138.961343) (xy 376.801312 -138.866976) (xy 376.864751 -138.776952)
			(xy 376.934522 -138.691741) (xy 377.010259 -138.611786) (xy 377.091568 -138.537505) (xy 377.178025 -138.469285)
			(xy 377.269179 -138.40748) (xy 377.364556 -138.352415) (xy 377.463657 -138.304375) (xy 377.565966 -138.263611)
			(xy 377.67095 -138.230336) (xy 377.778061 -138.204723) (xy 377.886741 -138.186906) (xy 377.996424 -138.176977)
			(xy 378.106537 -138.174989) (xy 378.216507 -138.180951) (xy 378.32576 -138.194833) (xy 378.433726 -138.216563)
			(xy 378.539843 -138.246026) (xy 378.643557 -138.283069) (xy 378.744328 -138.3275) (xy 378.84163 -138.379087)
			(xy 378.934956 -138.437559) (xy 379.023819 -138.502614) (xy 379.107757 -138.573912) (xy 379.186332 -138.65108)
			(xy 379.259133 -138.733717) (xy 379.325781 -138.821391) (xy 379.38593 -138.913647) (xy 379.439264 -139.010002)
			(xy 379.485507 -139.109954) (xy 379.524417 -139.212982) (xy 379.555791 -139.31855) (xy 379.579466 -139.426106)
			(xy 379.595318 -139.53509) (xy 379.603265 -139.644934) (xy 379.603762 -139.7) (xy 396.111741 -139.7)
			(xy 396.115716 -139.589941) (xy 396.127624 -139.480455) (xy 396.1474 -139.372114) (xy 396.174943 -139.265483)
			(xy 396.210108 -139.161117) (xy 396.252712 -139.05956) (xy 396.302533 -138.961343) (xy 396.359312 -138.866976)
			(xy 396.422751 -138.776952) (xy 396.492522 -138.691741) (xy 396.568259 -138.611786) (xy 396.649568 -138.537505)
			(xy 396.736025 -138.469285) (xy 396.827179 -138.40748) (xy 396.922556 -138.352415) (xy 397.021657 -138.304375)
			(xy 397.123966 -138.263611) (xy 397.22895 -138.230336) (xy 397.336061 -138.204723) (xy 397.444741 -138.186906)
			(xy 397.554424 -138.176977) (xy 397.664537 -138.174989) (xy 397.774507 -138.180951) (xy 397.88376 -138.194833)
			(xy 397.991726 -138.216563) (xy 398.097843 -138.246026) (xy 398.201557 -138.283069) (xy 398.302328 -138.3275)
			(xy 398.39963 -138.379087) (xy 398.492956 -138.437559) (xy 398.581819 -138.502614) (xy 398.665757 -138.573912)
			(xy 398.744332 -138.65108) (xy 398.817133 -138.733717) (xy 398.883781 -138.821391) (xy 398.94393 -138.913647)
			(xy 398.997264 -139.010002) (xy 399.043507 -139.109954) (xy 399.082417 -139.212982) (xy 399.113791 -139.31855)
			(xy 399.137466 -139.426106) (xy 399.153318 -139.53509) (xy 399.161265 -139.644934) (xy 399.161762 -139.7)
			(xy 399.161265 -139.755066) (xy 399.153318 -139.86491) (xy 399.137466 -139.973894) (xy 399.113791 -140.08145)
			(xy 399.082417 -140.187018) (xy 399.043507 -140.290046) (xy 398.997264 -140.389998) (xy 398.94393 -140.486353)
			(xy 398.883781 -140.578609) (xy 398.817133 -140.666283) (xy 398.744332 -140.74892) (xy 398.665757 -140.826088)
			(xy 398.581819 -140.897386) (xy 398.492956 -140.962441) (xy 398.39963 -141.020913) (xy 398.302328 -141.0725)
			(xy 398.201557 -141.116931) (xy 398.097843 -141.153974) (xy 397.991726 -141.183437) (xy 397.88376 -141.205167)
			(xy 397.774507 -141.219049) (xy 397.664537 -141.225011) (xy 397.554424 -141.223023) (xy 397.444741 -141.213094)
			(xy 397.336061 -141.195277) (xy 397.22895 -141.169664) (xy 397.123966 -141.136389) (xy 397.021657 -141.095625)
			(xy 396.922556 -141.047585) (xy 396.827179 -140.99252) (xy 396.736025 -140.930715) (xy 396.649568 -140.862495)
			(xy 396.568259 -140.788214) (xy 396.492522 -140.708259) (xy 396.422751 -140.623048) (xy 396.359312 -140.533024)
			(xy 396.302533 -140.438657) (xy 396.252712 -140.34044) (xy 396.210108 -140.238883) (xy 396.174943 -140.134517)
			(xy 396.1474 -140.027886) (xy 396.127624 -139.919545) (xy 396.115716 -139.810059) (xy 396.111741 -139.7)
			(xy 379.603762 -139.7) (xy 379.603265 -139.755066) (xy 379.595318 -139.86491) (xy 379.579466 -139.973894)
			(xy 379.555791 -140.08145) (xy 379.524417 -140.187018) (xy 379.485507 -140.290046) (xy 379.439264 -140.389998)
			(xy 379.38593 -140.486353) (xy 379.325781 -140.578609) (xy 379.259133 -140.666283) (xy 379.186332 -140.74892)
			(xy 379.107757 -140.826088) (xy 379.023819 -140.897386) (xy 378.934956 -140.962441) (xy 378.84163 -141.020913)
			(xy 378.744328 -141.0725) (xy 378.643557 -141.116931) (xy 378.539843 -141.153974) (xy 378.433726 -141.183437)
			(xy 378.32576 -141.205167) (xy 378.216507 -141.219049) (xy 378.106537 -141.225011) (xy 377.996424 -141.223023)
			(xy 377.886741 -141.213094) (xy 377.778061 -141.195277) (xy 377.67095 -141.169664) (xy 377.565966 -141.136389)
			(xy 377.463657 -141.095625) (xy 377.364556 -141.047585) (xy 377.269179 -140.99252) (xy 377.178025 -140.930715)
			(xy 377.091568 -140.862495) (xy 377.010259 -140.788214) (xy 376.934522 -140.708259) (xy 376.864751 -140.623048)
			(xy 376.801312 -140.533024) (xy 376.744533 -140.438657) (xy 376.694712 -140.34044) (xy 376.652108 -140.238883)
			(xy 376.616943 -140.134517) (xy 376.5894 -140.027886) (xy 376.569624 -139.919545) (xy 376.557716 -139.810059)
			(xy 376.553741 -139.7) (xy 352.008948 -139.7) (xy 352.008948 -153.299922) (xy 352.009454 -153.395255)
			(xy 352.017547 -153.585749) (xy 352.033718 -153.775728) (xy 352.057937 -153.964849) (xy 352.09016 -154.152772)
			(xy 352.130331 -154.339159) (xy 352.178375 -154.523672) (xy 352.234207 -154.70598) (xy 352.297727 -154.885754)
			(xy 352.368818 -155.062671) (xy 352.447355 -155.23641) (xy 352.533194 -155.40666) (xy 352.626182 -155.573114)
			(xy 352.72615 -155.735471) (xy 352.832919 -155.893439) (xy 352.946296 -156.046733) (xy 353.066077 -156.195077)
			(xy 353.192045 -156.338204) (xy 353.323975 -156.475856) (xy 353.461628 -156.607784) (xy 353.604756 -156.733752)
			(xy 353.753102 -156.853531) (xy 353.906397 -156.966907) (xy 354.064366 -157.073674) (xy 354.226724 -157.173641)
			(xy 354.393179 -157.266627) (xy 354.563429 -157.352464) (xy 354.73717 -157.430999) (xy 354.914087 -157.502089)
			(xy 355.093862 -157.565606) (xy 355.27617 -157.621437) (xy 355.460684 -157.66948) (xy 355.647071 -157.709648)
			(xy 355.834994 -157.74187) (xy 356.024116 -157.766087) (xy 356.214095 -157.782255) (xy 356.404589 -157.790347)
			(xy 356.499922 -157.790896) (xy 357.000048 -157.790896) (xy 357.083565 -157.791394) (xy 357.250411 -157.799344)
			(xy 357.416689 -157.815224) (xy 357.582024 -157.838998) (xy 357.746039 -157.870611) (xy 357.908365 -157.909993)
			(xy 358.068633 -157.957054) (xy 358.226481 -158.011687) (xy 358.38155 -158.07377) (xy 358.53349 -158.14316)
			(xy 358.681955 -158.219701) (xy 358.826611 -158.30322) (xy 358.967129 -158.393527) (xy 359.10319 -158.490418)
			(xy 359.234488 -158.593673) (xy 359.360723 -158.703059) (xy 359.481611 -158.818327) (xy 359.492747 -158.830006)
			(xy 361.785893 -158.830006) (xy 361.789998 -158.730238) (xy 361.802285 -158.631143) (xy 361.822671 -158.533393)
			(xy 361.85102 -158.437649) (xy 361.887138 -158.344557) (xy 361.930782 -158.254747) (xy 361.981657 -158.168826)
			(xy 362.039419 -158.087375) (xy 362.103677 -158.010945) (xy 362.173997 -157.940052) (xy 362.21162 -157.907228)
			(xy 362.219631 -157.899646) (xy 362.228855 -157.879636) (xy 362.2294 -157.86862) (xy 362.2294 -157.791404)
			(xy 362.22886 -157.780385) (xy 362.219642 -157.760369) (xy 362.21162 -157.752796) (xy 362.175695 -157.72148)
			(xy 362.108323 -157.65406) (xy 362.046446 -157.581563) (xy 361.990445 -157.504438) (xy 361.940665 -157.423158)
			(xy 361.897412 -157.338225) (xy 361.860953 -157.250162) (xy 361.831512 -157.15951) (xy 361.809271 -157.066829)
			(xy 361.794367 -156.972689) (xy 361.786891 -156.87767) (xy 361.786424 -156.830014) (xy 361.786965 -156.779837)
			(xy 361.79525 -156.679825) (xy 361.811765 -156.580838) (xy 361.836396 -156.483554) (xy 361.868976 -156.388635)
			(xy 361.909282 -156.29673) (xy 361.957039 -156.208467) (xy 362.01192 -156.124449) (xy 362.073551 -156.045249)
			(xy 362.141512 -155.971408) (xy 362.215337 -155.903431) (xy 362.294523 -155.841782) (xy 362.378528 -155.786881)
			(xy 362.46678 -155.739104) (xy 362.558676 -155.698777) (xy 362.653587 -155.666176) (xy 362.750866 -155.641522)
			(xy 362.849849 -155.624985) (xy 362.949859 -155.616677) (xy 363.000036 -155.616148) (xy 363.047698 -155.616657)
			(xy 363.142727 -155.624138) (xy 363.236876 -155.639052) (xy 363.329565 -155.661306) (xy 363.420222 -155.690763)
			(xy 363.508289 -155.727242) (xy 363.593222 -155.770518) (xy 363.674499 -155.820323) (xy 363.751617 -155.876352)
			(xy 363.824103 -155.938258) (xy 363.891508 -156.005661) (xy 363.922818 -156.041598) (xy 363.930385 -156.049627)
			(xy 363.950406 -156.058842) (xy 363.961426 -156.059378) (xy 364.038642 -156.059378) (xy 364.049665 -156.05887)
			(xy 364.069681 -156.04963) (xy 364.07725 -156.041598) (xy 364.108538 -156.005641) (xy 364.175953 -155.938249)
			(xy 364.248446 -155.876351) (xy 364.32557 -155.820329) (xy 364.406849 -155.770527) (xy 364.491784 -155.727252)
			(xy 364.579851 -155.690771) (xy 364.670507 -155.661309) (xy 364.763194 -155.639047) (xy 364.857342 -155.624122)
			(xy 364.95237 -155.616626) (xy 365.000032 -155.616148) (xy 365.050199 -155.616675) (xy 365.150189 -155.624962)
			(xy 365.249154 -155.641476) (xy 365.346418 -155.666105) (xy 365.441316 -155.69868) (xy 365.5332 -155.738979)
			(xy 365.621444 -155.786728) (xy 365.705443 -155.841599) (xy 365.784626 -155.903218) (xy 365.85845 -155.971164)
			(xy 365.926413 -156.044974) (xy 365.988049 -156.124143) (xy 366.042938 -156.208131) (xy 366.090705 -156.296364)
			(xy 366.131025 -156.38824) (xy 366.16362 -156.483131) (xy 366.18827 -156.580389) (xy 366.204806 -156.679351)
			(xy 366.213114 -156.779339) (xy 366.213644 -156.829506) (xy 366.213644 -156.830014) (xy 366.21318 -156.877671)
			(xy 366.205711 -156.972691) (xy 366.190811 -157.066833) (xy 366.168573 -157.159516) (xy 366.139134 -157.250169)
			(xy 366.102675 -157.338233) (xy 366.059421 -157.423167) (xy 366.009638 -157.504446) (xy 365.953632 -157.58157)
			(xy 365.891751 -157.654063) (xy 365.824373 -157.721479) (xy 365.788448 -157.752796) (xy 365.780421 -157.760364)
			(xy 365.771207 -157.780384) (xy 365.770668 -157.791404) (xy 365.770668 -157.86862) (xy 365.771205 -157.879639)
			(xy 365.780426 -157.899654) (xy 365.788448 -157.907228) (xy 365.826082 -157.94004) (xy 365.896405 -158.010933)
			(xy 365.960665 -158.087364) (xy 366.018429 -158.168815) (xy 366.069306 -158.254737) (xy 366.112952 -158.344548)
			(xy 366.149072 -158.437642) (xy 366.177421 -158.533388) (xy 366.197809 -158.63114) (xy 366.210097 -158.730236)
			(xy 366.214202 -158.830006) (xy 367.785885 -158.830006) (xy 367.78999 -158.730238) (xy 367.802277 -158.631144)
			(xy 367.822663 -158.533394) (xy 367.851011 -158.43765) (xy 367.887129 -158.344558) (xy 367.930773 -158.254748)
			(xy 367.981647 -158.168827) (xy 368.039408 -158.087376) (xy 368.103666 -158.010945) (xy 368.173985 -157.940052)
			(xy 368.211608 -157.907228) (xy 368.219618 -157.899644) (xy 368.228843 -157.879636) (xy 368.229388 -157.86862)
			(xy 368.229388 -157.791404) (xy 368.228852 -157.780385) (xy 368.219631 -157.760368) (xy 368.211608 -157.752796)
			(xy 368.17568 -157.721483) (xy 368.108309 -157.654062) (xy 368.046432 -157.581565) (xy 367.990432 -157.504439)
			(xy 367.940652 -157.423159) (xy 367.897399 -157.338226) (xy 367.86094 -157.250162) (xy 367.8315 -157.15951)
			(xy 367.809259 -157.066829) (xy 367.794355 -156.972689) (xy 367.786879 -156.87767) (xy 367.786412 -156.830014)
			(xy 367.786965 -156.779837) (xy 367.79525 -156.679826) (xy 367.811765 -156.58084) (xy 367.836396 -156.483556)
			(xy 367.868975 -156.388637) (xy 367.909281 -156.296733) (xy 367.957037 -156.208471) (xy 368.011917 -156.124453)
			(xy 368.073548 -156.045253) (xy 368.141507 -155.971413) (xy 368.215332 -155.903435) (xy 368.294517 -155.841786)
			(xy 368.378521 -155.786885) (xy 368.466772 -155.739108) (xy 368.558667 -155.698781) (xy 368.653578 -155.666178)
			(xy 368.750856 -155.641524) (xy 368.849838 -155.624986) (xy 368.949847 -155.616677) (xy 369.000024 -155.616148)
			(xy 369.047687 -155.616593) (xy 369.142718 -155.624081) (xy 369.236868 -155.639002) (xy 369.329558 -155.661263)
			(xy 369.420216 -155.690726) (xy 369.508283 -155.727212) (xy 369.593216 -155.770493) (xy 369.674492 -155.820305)
			(xy 369.751609 -155.876339) (xy 369.824093 -155.938251) (xy 369.891497 -156.005658) (xy 369.922806 -156.041598)
			(xy 369.930378 -156.049622) (xy 369.950395 -156.05884) (xy 369.961414 -156.059378) (xy 370.03863 -156.059378)
			(xy 370.049652 -156.058864) (xy 370.069669 -156.049628) (xy 370.077238 -156.041598) (xy 370.108532 -156.005647)
			(xy 370.175947 -155.938254) (xy 370.248439 -155.876356) (xy 370.325562 -155.820334) (xy 370.406841 -155.770531)
			(xy 370.491775 -155.727256) (xy 370.579841 -155.690775) (xy 370.670497 -155.661312) (xy 370.763183 -155.639049)
			(xy 370.857331 -155.624123) (xy 370.952359 -155.616626) (xy 371.00002 -155.616148) (xy 371.050186 -155.616687)
			(xy 371.150177 -155.624972) (xy 371.249142 -155.641486) (xy 371.346405 -155.666113) (xy 371.441303 -155.698688)
			(xy 371.533187 -155.738987) (xy 371.621431 -155.786734) (xy 371.70543 -155.841604) (xy 371.784613 -155.903223)
			(xy 371.858438 -155.971169) (xy 371.9264 -156.044978) (xy 371.988036 -156.124147) (xy 372.042926 -156.208134)
			(xy 372.090693 -156.296366) (xy 372.131012 -156.388242) (xy 372.163608 -156.483132) (xy 372.188258 -156.58039)
			(xy 372.204794 -156.679351) (xy 372.213102 -156.77934) (xy 372.213632 -156.829506) (xy 372.213632 -156.830014)
			(xy 372.213173 -156.877671) (xy 372.205703 -156.972691) (xy 372.190803 -157.066833) (xy 372.168565 -157.159516)
			(xy 372.139126 -157.250169) (xy 372.102666 -157.338234) (xy 372.059411 -157.423168) (xy 372.009628 -157.504447)
			(xy 371.953622 -157.58157) (xy 371.89174 -157.654063) (xy 371.824361 -157.721479) (xy 371.788436 -157.752796)
			(xy 371.780407 -157.760362) (xy 371.771194 -157.780384) (xy 371.770656 -157.791404) (xy 371.770656 -157.86862)
			(xy 371.771165 -157.879643) (xy 371.780403 -157.89966) (xy 371.788436 -157.907228) (xy 371.82687 -157.940727)
			(xy 371.898577 -158.013215) (xy 371.963952 -158.091462) (xy 372.022533 -158.174916) (xy 372.073908 -158.26299)
			(xy 372.096284 -158.308802) (xy 372.100856 -158.318454) (xy 372.116858 -158.332424) (xy 372.199154 -158.357316)
			(xy 372.209416 -158.359985) (xy 372.230452 -158.357503) (xy 372.239794 -158.35249) (xy 372.285756 -158.325685)
			(xy 372.380859 -158.27795) (xy 372.479133 -158.237137) (xy 372.580073 -158.203457) (xy 372.683163 -158.17708)
			(xy 372.787875 -158.158142) (xy 372.893673 -158.146741) (xy 373.000016 -158.142934) (xy 373.106359 -158.146741)
			(xy 373.212157 -158.158142) (xy 373.316869 -158.17708) (xy 373.419959 -158.203457) (xy 373.520899 -158.237137)
			(xy 373.619173 -158.27795) (xy 373.714276 -158.325685) (xy 373.760238 -158.35249) (xy 373.769622 -158.357377)
			(xy 373.79061 -158.359868) (xy 373.800878 -158.357316) (xy 373.883174 -158.332424) (xy 373.899176 -158.318454)
			(xy 373.903748 -158.308802) (xy 373.926127 -158.262992) (xy 373.977496 -158.174915) (xy 374.036076 -158.091459)
			(xy 374.101453 -158.013214) (xy 374.173165 -157.940731) (xy 374.211596 -157.907228) (xy 374.219604 -157.899642)
			(xy 374.228831 -157.879636) (xy 374.229376 -157.86862) (xy 374.229376 -157.791404) (xy 374.228843 -157.780384)
			(xy 374.219621 -157.760367) (xy 374.211596 -157.752796) (xy 374.175666 -157.721486) (xy 374.108295 -157.654064)
			(xy 374.046419 -157.581567) (xy 373.990418 -157.504441) (xy 373.940639 -157.423161) (xy 373.897386 -157.338227)
			(xy 373.860928 -157.250163) (xy 373.831488 -157.159511) (xy 373.809247 -157.066829) (xy 373.794343 -156.972689)
			(xy 373.786867 -156.87767) (xy 373.7864 -156.830014) (xy 373.786965 -156.779837) (xy 373.79525 -156.679827)
			(xy 373.811764 -156.580841) (xy 373.836395 -156.483558) (xy 373.868974 -156.38864) (xy 373.909279 -156.296736)
			(xy 373.957035 -156.208474) (xy 374.011915 -156.124457) (xy 374.073545 -156.045257) (xy 374.141503 -155.971417)
			(xy 374.215327 -155.90344) (xy 374.294511 -155.84179) (xy 374.378515 -155.786889) (xy 374.466765 -155.739112)
			(xy 374.558659 -155.698784) (xy 374.653568 -155.666181) (xy 374.750846 -155.641526) (xy 374.849827 -155.624988)
			(xy 374.949835 -155.616678) (xy 375.000012 -155.616148) (xy 375.047675 -155.616602) (xy 375.142705 -155.624089)
			(xy 375.236856 -155.639009) (xy 375.329545 -155.661268) (xy 375.420203 -155.690731) (xy 375.50827 -155.727216)
			(xy 375.593203 -155.770497) (xy 375.674479 -155.820308) (xy 375.751597 -155.876341) (xy 375.824081 -155.938252)
			(xy 375.891484 -156.005658) (xy 375.922794 -156.041598) (xy 375.930371 -156.049616) (xy 375.950384 -156.058837)
			(xy 375.961402 -156.059378) (xy 376.038618 -156.059378) (xy 376.049639 -156.058857) (xy 376.069656 -156.049626)
			(xy 376.077226 -156.041598) (xy 376.108527 -156.005653) (xy 376.175941 -155.93826) (xy 376.248432 -155.876362)
			(xy 376.325555 -155.820339) (xy 376.406833 -155.770536) (xy 376.491766 -155.72726) (xy 376.579831 -155.690779)
			(xy 376.670486 -155.661315) (xy 376.763173 -155.639051) (xy 376.857319 -155.624124) (xy 376.952347 -155.616626)
			(xy 377.000008 -155.616148) (xy 377.050174 -155.616698) (xy 377.150164 -155.624983) (xy 377.249129 -155.641495)
			(xy 377.346392 -155.666122) (xy 377.44129 -155.698696) (xy 377.533174 -155.738994) (xy 377.621418 -155.78674)
			(xy 377.705417 -155.84161) (xy 377.7846 -155.903228) (xy 377.858425 -155.971173) (xy 377.926387 -156.044982)
			(xy 377.988024 -156.12415) (xy 378.042913 -156.208137) (xy 378.090681 -156.296369) (xy 378.131 -156.388243)
			(xy 378.163596 -156.483134) (xy 378.188246 -156.580391) (xy 378.204782 -156.679352) (xy 378.21309 -156.77934)
			(xy 378.21362 -156.829506) (xy 378.21362 -156.830014) (xy 378.213165 -156.877671) (xy 378.205695 -156.972692)
			(xy 378.190795 -157.066834) (xy 378.168557 -157.159517) (xy 378.139117 -157.25017) (xy 378.102657 -157.338235)
			(xy 378.059402 -157.423168) (xy 378.009618 -157.504447) (xy 377.953612 -157.581571) (xy 377.891728 -157.654064)
			(xy 377.82435 -157.721479) (xy 377.788424 -157.752796) (xy 377.780393 -157.76036) (xy 377.771182 -157.780384)
			(xy 377.770644 -157.791404) (xy 377.770644 -157.86862) (xy 377.771157 -157.879642) (xy 377.780393 -157.899659)
			(xy 377.788424 -157.907228) (xy 377.826059 -157.94004) (xy 377.896383 -158.010932) (xy 377.960645 -158.087362)
			(xy 378.01841 -158.168813) (xy 378.069288 -158.254735) (xy 378.112934 -158.344547) (xy 378.149055 -158.43764)
			(xy 378.177405 -158.533387) (xy 378.197793 -158.631139) (xy 378.210081 -158.730235) (xy 378.214186 -158.830006)
			(xy 378.21008 -158.929778) (xy 378.197791 -159.028874) (xy 378.177402 -159.126626) (xy 378.149051 -159.222372)
			(xy 378.112929 -159.315465) (xy 378.069281 -159.405276) (xy 378.018403 -159.491197) (xy 377.960637 -159.572648)
			(xy 377.896374 -159.649078) (xy 377.82605 -159.719969) (xy 377.788424 -159.752792) (xy 377.780395 -159.760358)
			(xy 377.771183 -159.78038) (xy 377.770644 -159.7914) (xy 377.770644 -159.868616) (xy 377.771159 -159.879638)
			(xy 377.780393 -159.899655) (xy 377.788424 -159.907224) (xy 377.824368 -159.938518) (xy 377.891738 -160.005942)
			(xy 377.953613 -160.078441) (xy 378.009613 -160.155569) (xy 378.059391 -160.236851) (xy 378.102642 -160.321787)
			(xy 378.139099 -160.409852) (xy 378.168538 -160.500505) (xy 378.190777 -160.593188) (xy 378.205679 -160.687329)
			(xy 378.213153 -160.782349) (xy 378.21362 -160.830006) (xy 381.986028 -160.830006) (xy 381.986502 -160.782344)
			(xy 381.993988 -160.687314) (xy 382.008905 -160.593164) (xy 382.031164 -160.500475) (xy 382.060625 -160.409817)
			(xy 382.097107 -160.321751) (xy 382.140386 -160.236817) (xy 382.190195 -160.155541) (xy 382.246226 -160.078423)
			(xy 382.308135 -160.005939) (xy 382.375539 -159.938534) (xy 382.411478 -159.907224) (xy 382.4195 -159.899652)
			(xy 382.428716 -159.879634) (xy 382.429258 -159.868616) (xy 382.429258 -159.7914) (xy 382.428734 -159.780379)
			(xy 382.419506 -159.760362) (xy 382.411478 -159.752792) (xy 382.375537 -159.721486) (xy 382.308145 -159.654072)
			(xy 382.246247 -159.581581) (xy 382.190224 -159.504459) (xy 382.140421 -159.423182) (xy 382.097145 -159.338249)
			(xy 382.060663 -159.250184) (xy 382.031199 -159.15953) (xy 382.008934 -159.066844) (xy 381.994006 -158.972698)
			(xy 381.986507 -158.877671) (xy 381.986028 -158.83001) (xy 381.986505 -158.782348) (xy 381.99399 -158.687318)
			(xy 382.008908 -158.593168) (xy 382.031165 -158.500479) (xy 382.060626 -158.409822) (xy 382.097108 -158.321755)
			(xy 382.140387 -158.236822) (xy 382.190196 -158.155546) (xy 382.246227 -158.078427) (xy 382.308135 -158.005943)
			(xy 382.37554 -157.938538) (xy 382.411478 -157.907228) (xy 382.419499 -157.899655) (xy 382.428715 -157.879638)
			(xy 382.429258 -157.86862) (xy 382.429258 -157.791404) (xy 382.428731 -157.780383) (xy 382.419505 -157.760366)
			(xy 382.411478 -157.752796) (xy 382.375539 -157.721488) (xy 382.308147 -157.654074) (xy 382.246249 -157.581583)
			(xy 382.190226 -157.504462) (xy 382.140423 -157.423184) (xy 382.097147 -157.338252) (xy 382.060664 -157.250187)
			(xy 382.0312 -157.159533) (xy 382.008935 -157.066848) (xy 381.994007 -156.972702) (xy 381.986507 -156.877675)
			(xy 381.986028 -156.830014) (xy 381.986552 -156.779829) (xy 381.994839 -156.679803) (xy 382.011358 -156.580802)
			(xy 382.035996 -156.483504) (xy 382.068585 -156.388573) (xy 382.108902 -156.296657) (xy 382.156672 -156.208384)
			(xy 382.211568 -156.124358) (xy 382.273215 -156.045152) (xy 382.341193 -155.971307) (xy 382.415037 -155.903328)
			(xy 382.494242 -155.84168) (xy 382.578267 -155.786782) (xy 382.666539 -155.739011) (xy 382.758454 -155.698693)
			(xy 382.853385 -155.666102) (xy 382.950683 -155.641462) (xy 383.049683 -155.624942) (xy 383.149709 -155.616653)
			(xy 383.199894 -155.616148) (xy 383.247556 -155.616615) (xy 383.342587 -155.624101) (xy 383.436737 -155.639019)
			(xy 383.529426 -155.661277) (xy 383.620084 -155.690739) (xy 383.708151 -155.727222) (xy 383.793084 -155.770502)
			(xy 383.87436 -155.820311) (xy 383.951478 -155.876344) (xy 384.023962 -155.938253) (xy 384.091366 -156.005659)
			(xy 384.122676 -156.041598) (xy 384.13026 -156.049608) (xy 384.150268 -156.058834) (xy 384.161284 -156.059378)
			(xy 384.2385 -156.059378) (xy 384.24952 -156.058847) (xy 384.269537 -156.049623) (xy 384.277108 -156.041598)
			(xy 384.308419 -156.005661) (xy 384.375832 -155.938269) (xy 384.448322 -155.87637) (xy 384.525443 -155.820346)
			(xy 384.60672 -155.770543) (xy 384.691652 -155.727267) (xy 384.779717 -155.690784) (xy 384.870371 -155.661319)
			(xy 384.963056 -155.639054) (xy 385.057202 -155.624126) (xy 385.152229 -155.616627) (xy 385.19989 -155.616148)
			(xy 385.250075 -155.616648) (xy 385.350103 -155.624936) (xy 385.449105 -155.641456) (xy 385.546404 -155.666095)
			(xy 385.641336 -155.698684) (xy 385.733253 -155.739003) (xy 385.821526 -155.786773) (xy 385.905553 -155.841671)
			(xy 385.984759 -155.90332) (xy 386.058604 -155.971299) (xy 386.126583 -156.045144) (xy 386.188232 -156.12435)
			(xy 386.243129 -156.208377) (xy 386.290899 -156.296651) (xy 386.331217 -156.388568) (xy 386.363807 -156.4835)
			(xy 386.388445 -156.580799) (xy 386.404965 -156.679801) (xy 386.413252 -156.779829) (xy 386.413756 -156.830014)
			(xy 386.413302 -156.877677) (xy 386.405815 -156.972707) (xy 386.390895 -157.066858) (xy 386.368635 -157.159547)
			(xy 386.339172 -157.250205) (xy 386.302688 -157.338272) (xy 386.259407 -157.423205) (xy 386.209596 -157.504481)
			(xy 386.153563 -157.581599) (xy 386.091652 -157.654083) (xy 386.024245 -157.721486) (xy 385.988306 -157.752796)
			(xy 385.980288 -157.760372) (xy 385.971066 -157.780386) (xy 385.970526 -157.791404) (xy 385.970526 -157.86862)
			(xy 385.971045 -157.879641) (xy 385.980277 -157.899658) (xy 385.988306 -157.907228) (xy 386.024253 -157.938527)
			(xy 386.091646 -158.005941) (xy 386.153544 -158.078433) (xy 386.209567 -158.155555) (xy 386.259369 -158.236834)
			(xy 386.302644 -158.321767) (xy 386.339126 -158.409833) (xy 386.36859 -158.500488) (xy 386.390853 -158.593174)
			(xy 386.40578 -158.687321) (xy 386.413278 -158.782349) (xy 386.413756 -158.83001) (xy 386.413299 -158.877672)
			(xy 386.405812 -158.972703) (xy 386.390893 -159.066853) (xy 386.368633 -159.159543) (xy 386.339171 -159.250201)
			(xy 386.302686 -159.338268) (xy 386.259406 -159.423201) (xy 386.209595 -159.504477) (xy 386.153562 -159.581594)
			(xy 386.091652 -159.654079) (xy 386.024245 -159.721482) (xy 385.988306 -159.752792) (xy 385.980289 -159.76037)
			(xy 385.971067 -159.780382) (xy 385.970526 -159.7914) (xy 385.970526 -159.868616) (xy 385.971047 -159.879637)
			(xy 385.980278 -159.899654) (xy 385.988306 -159.907224) (xy 386.024251 -159.938525) (xy 386.091644 -160.005939)
			(xy 386.153542 -160.078431) (xy 386.209565 -160.155553) (xy 386.259368 -160.236831) (xy 386.302643 -160.321764)
			(xy 386.339125 -160.409829) (xy 386.368589 -160.500484) (xy 386.390852 -160.593171) (xy 386.405779 -160.687317)
			(xy 386.413277 -160.782345) (xy 386.413756 -160.830006) (xy 386.41359 -160.852381) (xy 386.411813 -160.897097)
			(xy 386.4102 -160.919414) (xy 386.4102 -160.919668) (xy 386.409958 -160.928551) (xy 386.414832 -160.945627)
			(xy 386.425194 -160.960048) (xy 386.432298 -160.965388) (xy 386.50545 -161.014664) (xy 386.512994 -161.019448)
			(xy 386.530299 -161.023851) (xy 386.548064 -161.022055) (xy 386.55625 -161.018474) (xy 386.556504 -161.01822)
			(xy 386.606586 -160.994237) (xy 386.709718 -160.953049) (xy 386.815678 -160.919811) (xy 386.923857 -160.894713)
			(xy 387.033629 -160.877899) (xy 387.14436 -160.869468) (xy 387.255412 -160.869468) (xy 387.366143 -160.877899)
			(xy 387.475915 -160.894713) (xy 387.584094 -160.919811) (xy 387.690054 -160.953049) (xy 387.793186 -160.994237)
			(xy 387.843268 -161.01822) (xy 387.843522 -161.018474) (xy 387.851694 -161.022085) (xy 387.869464 -161.023863)
			(xy 387.886764 -161.019431) (xy 387.894322 -161.014664) (xy 387.967474 -160.965388) (xy 387.974676 -160.960145)
			(xy 387.985104 -160.945713) (xy 387.989919 -160.928571) (xy 387.989572 -160.919668) (xy 387.989572 -160.91916)
			(xy 387.987965 -160.896906) (xy 387.986188 -160.852317) (xy 387.986016 -160.830006) (xy 387.986494 -160.782344)
			(xy 387.99398 -160.687314) (xy 388.008897 -160.593165) (xy 388.031155 -160.500476) (xy 388.060616 -160.409818)
			(xy 388.097098 -160.321752) (xy 388.140377 -160.236818) (xy 388.190185 -160.155542) (xy 388.246216 -160.078424)
			(xy 388.308124 -160.005939) (xy 388.375528 -159.938534) (xy 388.411466 -159.907224) (xy 388.419487 -159.89965)
			(xy 388.428704 -159.879634) (xy 388.429246 -159.868616) (xy 388.429246 -159.7914) (xy 388.428725 -159.780379)
			(xy 388.419496 -159.760361) (xy 388.411466 -159.752792) (xy 388.375523 -159.721489) (xy 388.308131 -159.654075)
			(xy 388.246233 -159.581583) (xy 388.19021 -159.504461) (xy 388.140408 -159.423183) (xy 388.097133 -159.33825)
			(xy 388.06065 -159.250185) (xy 388.031186 -159.15953) (xy 388.008922 -159.066845) (xy 387.993994 -158.972698)
			(xy 387.986495 -158.877671) (xy 387.986016 -158.83001) (xy 387.986497 -158.782348) (xy 387.993982 -158.687318)
			(xy 388.0089 -158.593169) (xy 388.031157 -158.50048) (xy 388.060618 -158.409823) (xy 388.097099 -158.321756)
			(xy 388.140378 -158.236823) (xy 388.190186 -158.155546) (xy 388.246216 -158.078428) (xy 388.308124 -158.005943)
			(xy 388.375528 -157.938538) (xy 388.411466 -157.907228) (xy 388.419485 -157.899653) (xy 388.428703 -157.879638)
			(xy 388.429246 -157.86862) (xy 388.429246 -157.791404) (xy 388.428723 -157.780383) (xy 388.419495 -157.760366)
			(xy 388.411466 -157.752796) (xy 388.375525 -157.721491) (xy 388.308133 -157.654077) (xy 388.246235 -157.581585)
			(xy 388.190212 -157.504463) (xy 388.14041 -157.423186) (xy 388.097134 -157.338253) (xy 388.060652 -157.250188)
			(xy 388.031187 -157.159534) (xy 388.008923 -157.066848) (xy 387.993995 -156.972702) (xy 387.986495 -156.877675)
			(xy 387.986016 -156.830014) (xy 387.986566 -156.77983) (xy 387.994853 -156.679805) (xy 388.011372 -156.580807)
			(xy 388.036009 -156.48351) (xy 388.068597 -156.38858) (xy 388.108913 -156.296666) (xy 388.156682 -156.208395)
			(xy 388.211577 -156.12437) (xy 388.273223 -156.045165) (xy 388.341199 -155.971321) (xy 388.415041 -155.903343)
			(xy 388.494244 -155.841695) (xy 388.578267 -155.786798) (xy 388.666537 -155.739027) (xy 388.758451 -155.698709)
			(xy 388.853379 -155.666118) (xy 388.950675 -155.641478) (xy 389.049674 -155.624957) (xy 389.149698 -155.616667)
			(xy 389.199882 -155.616148) (xy 389.247544 -155.616624) (xy 389.342574 -155.624108) (xy 389.436724 -155.639026)
			(xy 389.529414 -155.661283) (xy 389.620071 -155.690744) (xy 389.708138 -155.727226) (xy 389.793071 -155.770505)
			(xy 389.874347 -155.820314) (xy 389.951465 -155.876345) (xy 390.02395 -155.938254) (xy 390.091354 -156.005659)
			(xy 390.122664 -156.041598) (xy 390.130253 -156.049603) (xy 390.150257 -156.058831) (xy 390.161272 -156.059378)
			(xy 390.238488 -156.059378) (xy 390.249507 -156.05884) (xy 390.269524 -156.049622) (xy 390.277096 -156.041598)
			(xy 390.308413 -156.005667) (xy 390.375826 -155.938274) (xy 390.448315 -155.876375) (xy 390.525436 -155.820351)
			(xy 390.606712 -155.770548) (xy 390.691643 -155.727271) (xy 390.779707 -155.690787) (xy 390.870361 -155.661322)
			(xy 390.963045 -155.639057) (xy 391.057191 -155.624128) (xy 391.152217 -155.616628) (xy 391.199878 -155.616148)
			(xy 391.250063 -155.61666) (xy 391.35009 -155.624946) (xy 391.449092 -155.641465) (xy 391.546391 -155.666103)
			(xy 391.641323 -155.698692) (xy 391.73324 -155.73901) (xy 391.821513 -155.78678) (xy 391.90554 -155.841676)
			(xy 391.984746 -155.903324) (xy 392.058591 -155.971303) (xy 392.12657 -156.045147) (xy 392.188219 -156.124354)
			(xy 392.243116 -156.20838) (xy 392.290887 -156.296653) (xy 392.331205 -156.388569) (xy 392.363794 -156.483501)
			(xy 392.388433 -156.5808) (xy 392.404953 -156.679802) (xy 392.41324 -156.779829) (xy 392.413744 -156.830014)
			(xy 392.413294 -156.877677) (xy 392.405807 -156.972708) (xy 392.390887 -157.066858) (xy 392.368627 -157.159548)
			(xy 392.339164 -157.250206) (xy 392.302679 -157.338273) (xy 392.259397 -157.423206) (xy 392.209586 -157.504482)
			(xy 392.153552 -157.581599) (xy 392.091641 -157.654083) (xy 392.024234 -157.721487) (xy 391.988294 -157.752796)
			(xy 391.980274 -157.760371) (xy 391.971054 -157.780386) (xy 391.970514 -157.791404) (xy 391.970514 -157.86862)
			(xy 391.971036 -157.879641) (xy 391.980266 -157.899658) (xy 391.988294 -157.907228) (xy 392.024239 -157.93853)
			(xy 392.091631 -158.005944) (xy 392.15353 -158.078435) (xy 392.209553 -158.155557) (xy 392.259356 -158.236835)
			(xy 392.302632 -158.321768) (xy 392.339114 -158.409833) (xy 392.368577 -158.500488) (xy 392.390841 -158.593175)
			(xy 392.405768 -158.687321) (xy 392.413266 -158.782349) (xy 392.413744 -158.83001) (xy 392.413291 -158.877673)
			(xy 392.405804 -158.972703) (xy 392.390885 -159.066854) (xy 392.368625 -159.159544) (xy 392.339162 -159.250202)
			(xy 392.302678 -159.338268) (xy 392.259396 -159.423202) (xy 392.209585 -159.504478) (xy 392.153552 -159.581595)
			(xy 392.091641 -159.654079) (xy 392.024234 -159.721482) (xy 391.988294 -159.752792) (xy 391.980276 -159.760368)
			(xy 391.971055 -159.780382) (xy 391.970514 -159.7914) (xy 391.970514 -159.868616) (xy 391.971038 -159.879637)
			(xy 391.980267 -159.899653) (xy 391.988294 -159.907224) (xy 392.024237 -159.938528) (xy 392.09163 -160.005941)
			(xy 392.153528 -160.078433) (xy 392.209552 -160.155554) (xy 392.259354 -160.236832) (xy 392.30263 -160.321765)
			(xy 392.339112 -160.40983) (xy 392.368576 -160.500485) (xy 392.39084 -160.593171) (xy 392.405767 -160.687318)
			(xy 392.413265 -160.782345) (xy 392.413744 -160.830006) (xy 392.413267 -160.880192) (xy 392.404978 -160.98022)
			(xy 392.388457 -161.079222) (xy 392.363817 -161.176522) (xy 392.331225 -161.271455) (xy 392.290906 -161.363372)
			(xy 392.243134 -161.451646) (xy 392.188235 -161.535673) (xy 392.126585 -161.614879) (xy 392.058604 -161.688724)
			(xy 391.984758 -161.756703) (xy 391.90555 -161.818351) (xy 391.821522 -161.873248) (xy 391.733247 -161.921018)
			(xy 391.641329 -161.961335) (xy 391.546395 -161.993925) (xy 391.449095 -162.018563) (xy 391.350092 -162.035082)
			(xy 391.250064 -162.043368) (xy 391.199878 -162.043872) (xy 391.152216 -162.043418) (xy 391.057185 -162.03593)
			(xy 390.963035 -162.02101) (xy 390.870345 -161.99875) (xy 390.779688 -161.969287) (xy 390.691621 -161.932803)
			(xy 390.606688 -161.889522) (xy 390.525412 -161.839711) (xy 390.448294 -161.783678) (xy 390.37581 -161.721767)
			(xy 390.308406 -161.654361) (xy 390.277096 -161.618422) (xy 390.269535 -161.610387) (xy 390.249509 -161.601178)
			(xy 390.238488 -161.600642) (xy 390.161272 -161.600642) (xy 390.150249 -161.601151) (xy 390.130232 -161.61039)
			(xy 390.122664 -161.618422) (xy 390.091374 -161.654377) (xy 390.023958 -161.721768) (xy 389.951465 -161.783666)
			(xy 389.874341 -161.839688) (xy 389.793062 -161.88949) (xy 389.708128 -161.932764) (xy 389.620062 -161.969245)
			(xy 389.529406 -161.998708) (xy 389.436719 -162.020971) (xy 389.342571 -162.035897) (xy 389.247544 -162.043394)
			(xy 389.199882 -162.043872) (xy 389.145602 -162.043262) (xy 389.037477 -162.03354) (xy 388.930654 -162.014192)
			(xy 388.825987 -161.985374) (xy 388.77494 -161.96691) (xy 388.761986 -161.962084) (xy 388.73557 -161.966656)
			(xy 388.646416 -162.040316) (xy 388.637018 -162.06597) (xy 388.639304 -162.079432) (xy 388.648117 -162.132911)
			(xy 388.65875 -162.240785) (xy 388.66136 -162.34915) (xy 388.655931 -162.457411) (xy 388.642494 -162.564971)
			(xy 388.621122 -162.67124) (xy 388.591933 -162.775633) (xy 388.555087 -162.877575) (xy 388.510788 -162.976507)
			(xy 388.459279 -163.071883) (xy 388.400842 -163.163179) (xy 388.335801 -163.249894) (xy 388.264511 -163.331549)
			(xy 388.187366 -163.407697) (xy 388.10479 -163.477918) (xy 388.017236 -163.541825) (xy 387.925187 -163.599069)
			(xy 387.829149 -163.649333) (xy 387.729649 -163.692341) (xy 387.627236 -163.727856) (xy 387.522472 -163.755684)
			(xy 387.415934 -163.775672) (xy 387.308208 -163.787708) (xy 387.199886 -163.791727) (xy 387.091564 -163.787708)
			(xy 386.983838 -163.775672) (xy 386.8773 -163.755684) (xy 386.772536 -163.727856) (xy 386.670123 -163.692341)
			(xy 386.570623 -163.649333) (xy 386.474585 -163.599069) (xy 386.382536 -163.541825) (xy 386.294982 -163.477918)
			(xy 386.212406 -163.407697) (xy 386.135261 -163.331549) (xy 386.063971 -163.249894) (xy 385.99893 -163.163179)
			(xy 385.940493 -163.071883) (xy 385.888984 -162.976507) (xy 385.844685 -162.877575) (xy 385.807839 -162.775633)
			(xy 385.77865 -162.67124) (xy 385.757278 -162.564971) (xy 385.743841 -162.457411) (xy 385.738412 -162.34915)
			(xy 385.741022 -162.240785) (xy 385.751655 -162.132911) (xy 385.760468 -162.079432) (xy 385.762754 -162.06597)
			(xy 385.753356 -162.040316) (xy 385.664202 -161.966656) (xy 385.637786 -161.962084) (xy 385.624832 -161.96691)
			(xy 385.573782 -161.985364) (xy 385.469113 -162.014163) (xy 385.362291 -162.033508) (xy 385.254169 -162.043246)
			(xy 385.19989 -162.043872) (xy 385.152228 -162.04341) (xy 385.057197 -162.035923) (xy 384.963047 -162.021004)
			(xy 384.870358 -161.998744) (xy 384.7797 -161.969282) (xy 384.691634 -161.932798) (xy 384.6067 -161.889518)
			(xy 384.525424 -161.839709) (xy 384.448307 -161.783676) (xy 384.375822 -161.721766) (xy 384.308418 -161.654361)
			(xy 384.277108 -161.618422) (xy 384.269543 -161.610392) (xy 384.24952 -161.601181) (xy 384.2385 -161.600642)
			(xy 384.161284 -161.600642) (xy 384.150262 -161.601158) (xy 384.130245 -161.610391) (xy 384.122676 -161.618422)
			(xy 384.091379 -161.654371) (xy 384.023964 -161.721763) (xy 383.951472 -161.78366) (xy 383.874349 -161.839683)
			(xy 383.793071 -161.889485) (xy 383.708137 -161.93276) (xy 383.620071 -161.969242) (xy 383.529416 -161.998705)
			(xy 383.43673 -162.020969) (xy 383.342583 -162.035895) (xy 383.247555 -162.043394) (xy 383.199894 -162.043872)
			(xy 383.14971 -162.043353) (xy 383.049684 -162.035065) (xy 382.950684 -162.018544) (xy 382.853387 -161.993905)
			(xy 382.758456 -161.961315) (xy 382.666541 -161.920997) (xy 382.57827 -161.873226) (xy 382.494245 -161.81833)
			(xy 382.41504 -161.756682) (xy 382.341196 -161.688704) (xy 382.273218 -161.61486) (xy 382.21157 -161.535655)
			(xy 382.156674 -161.45163) (xy 382.108903 -161.363359) (xy 382.068585 -161.271444) (xy 382.035995 -161.176513)
			(xy 382.011356 -161.079216) (xy 381.994835 -160.980216) (xy 381.986547 -160.88019) (xy 381.986028 -160.830006)
			(xy 378.21362 -160.830006) (xy 378.213154 -160.880185) (xy 378.204867 -160.9802) (xy 378.188349 -161.07919)
			(xy 378.163715 -161.176478) (xy 378.131132 -161.271399) (xy 378.090823 -161.363306) (xy 378.043062 -161.451571)
			(xy 377.988176 -161.535591) (xy 377.92654 -161.614791) (xy 377.858576 -161.688633) (xy 377.784746 -161.75661)
			(xy 377.705555 -161.818259) (xy 377.621544 -161.873158) (xy 377.533288 -161.920934) (xy 377.441387 -161.961259)
			(xy 377.346471 -161.993858) (xy 377.249188 -162.018508) (xy 377.150201 -162.035042) (xy 377.050187 -162.043345)
			(xy 377.000008 -162.043872) (xy 376.952346 -162.043397) (xy 376.857316 -162.035911) (xy 376.763166 -162.020993)
			(xy 376.670477 -161.998736) (xy 376.57982 -161.969275) (xy 376.491753 -161.932792) (xy 376.40682 -161.889513)
			(xy 376.325543 -161.839705) (xy 376.248425 -161.783673) (xy 376.175941 -161.721765) (xy 376.108536 -161.65436)
			(xy 376.077226 -161.618422) (xy 376.069653 -161.6104) (xy 376.049636 -161.601184) (xy 376.038618 -161.600642)
			(xy 375.961402 -161.600642) (xy 375.950381 -161.601168) (xy 375.930364 -161.610394) (xy 375.922794 -161.618422)
			(xy 375.891487 -161.654362) (xy 375.824073 -161.721754) (xy 375.751582 -161.783652) (xy 375.67446 -161.839675)
			(xy 375.593183 -161.889478) (xy 375.50825 -161.932754) (xy 375.420186 -161.969236) (xy 375.329532 -161.998701)
			(xy 375.236846 -162.020965) (xy 375.1427 -162.035893) (xy 375.047673 -162.043393) (xy 375.000012 -162.043872)
			(xy 374.950031 -162.043367) (xy 374.850408 -162.035131) (xy 374.7518 -162.01873) (xy 374.654875 -161.994275)
			(xy 374.56029 -161.961933) (xy 374.468684 -161.921921) (xy 374.380679 -161.874511) (xy 374.296872 -161.820025)
			(xy 374.217828 -161.758831) (xy 374.144086 -161.691345) (xy 374.076142 -161.618022) (xy 374.014459 -161.53936)
			(xy 373.959454 -161.455892) (xy 373.911499 -161.368183) (xy 373.87092 -161.276828) (xy 373.83799 -161.182445)
			(xy 373.812935 -161.085673) (xy 373.803926 -161.036508) (xy 373.801331 -161.024879) (xy 373.787304 -161.005662)
			(xy 373.777002 -160.999678) (xy 373.693436 -160.957514) (xy 373.669814 -160.95726) (xy 373.658892 -160.962594)
			(xy 373.611617 -160.985464) (xy 373.514417 -161.025256) (xy 373.414651 -161.058087) (xy 373.312816 -161.083794)
			(xy 373.20942 -161.102248) (xy 373.10498 -161.113358) (xy 373.000016 -161.117067) (xy 372.895052 -161.113358)
			(xy 372.790612 -161.102248) (xy 372.687216 -161.083794) (xy 372.585381 -161.058087) (xy 372.485615 -161.025256)
			(xy 372.388415 -160.985464) (xy 372.34114 -160.962594) (xy 372.330237 -160.95791) (xy 372.306532 -160.958058)
			(xy 372.295674 -160.962848) (xy 372.22303 -160.999678) (xy 372.212755 -161.0057) (xy 372.198706 -161.024888)
			(xy 372.196106 -161.036508) (xy 372.187109 -161.085678) (xy 372.16207 -161.182458) (xy 372.129154 -161.276851)
			(xy 372.088584 -161.368216) (xy 372.040637 -161.455934) (xy 371.985635 -161.539411) (xy 371.923954 -161.61808)
			(xy 371.856009 -161.691408) (xy 371.782263 -161.758898) (xy 371.703215 -161.820093) (xy 371.619401 -161.874578)
			(xy 371.531389 -161.921984) (xy 371.439775 -161.961989) (xy 371.345181 -161.994321) (xy 371.248248 -162.018763)
			(xy 371.149633 -162.035148) (xy 371.050004 -162.043365) (xy 371.00002 -162.043872) (xy 370.952358 -162.043388)
			(xy 370.857328 -162.035903) (xy 370.763179 -162.020987) (xy 370.67049 -161.99873) (xy 370.579832 -161.96927)
			(xy 370.491766 -161.932788) (xy 370.406832 -161.88951) (xy 370.325556 -161.839702) (xy 370.248438 -161.783672)
			(xy 370.175953 -161.721764) (xy 370.108548 -161.65436) (xy 370.077238 -161.618422) (xy 370.06966 -161.610406)
			(xy 370.049647 -161.601186) (xy 370.03863 -161.600642) (xy 369.961414 -161.600642) (xy 369.950394 -161.601175)
			(xy 369.930377 -161.610396) (xy 369.922806 -161.618422) (xy 369.891493 -161.654356) (xy 369.824079 -161.721748)
			(xy 369.751589 -161.783647) (xy 369.674468 -161.83967) (xy 369.593191 -161.889473) (xy 369.508259 -161.93275)
			(xy 369.420196 -161.969233) (xy 369.329542 -161.998698) (xy 369.236857 -162.020963) (xy 369.142711 -162.035892)
			(xy 369.047685 -162.043392) (xy 369.000024 -162.043872) (xy 368.949856 -162.043371) (xy 368.849863 -162.035088)
			(xy 368.750895 -162.018577) (xy 368.653628 -161.99395) (xy 368.558727 -161.961376) (xy 368.466839 -161.921078)
			(xy 368.378593 -161.873329) (xy 368.294591 -161.818457) (xy 368.215407 -161.756836) (xy 368.141581 -161.688887)
			(xy 368.073618 -161.615075) (xy 368.011981 -161.535903) (xy 367.957093 -161.451911) (xy 367.909327 -161.363675)
			(xy 367.86901 -161.271795) (xy 367.836418 -161.1769) (xy 367.811772 -161.079638) (xy 367.795241 -160.980674)
			(xy 367.786939 -160.880682) (xy 367.786412 -160.830514) (xy 367.786412 -160.830006) (xy 367.786905 -160.78235)
			(xy 367.794373 -160.687331) (xy 367.80927 -160.59319) (xy 367.831506 -160.500508) (xy 367.860943 -160.409856)
			(xy 367.897399 -160.321791) (xy 367.94065 -160.236858) (xy 367.99043 -160.155578) (xy 368.046432 -160.078454)
			(xy 368.108311 -160.00596) (xy 368.175685 -159.938542) (xy 368.211608 -159.907224) (xy 368.219619 -159.899642)
			(xy 368.228844 -159.879632) (xy 368.229388 -159.868616) (xy 368.229388 -159.7914) (xy 368.228854 -159.780381)
			(xy 368.219632 -159.760364) (xy 368.211608 -159.752792) (xy 368.173995 -159.719957) (xy 368.103675 -159.649064)
			(xy 368.039416 -159.572635) (xy 367.981654 -159.491184) (xy 367.930779 -159.405264) (xy 367.887134 -159.315454)
			(xy 367.851015 -159.222363) (xy 367.822666 -159.126619) (xy 367.802279 -159.028869) (xy 367.789991 -158.929775)
			(xy 367.785885 -158.830006) (xy 366.214202 -158.830006) (xy 366.210096 -158.929777) (xy 366.197807 -159.028873)
			(xy 366.177418 -159.126625) (xy 366.149068 -159.22237) (xy 366.112947 -159.315464) (xy 366.0693 -159.405274)
			(xy 366.018422 -159.491196) (xy 365.960657 -159.572647) (xy 365.896396 -159.649077) (xy 365.826073 -159.719969)
			(xy 365.788448 -159.752792) (xy 365.780422 -159.760361) (xy 365.771208 -159.780381) (xy 365.770668 -159.7914)
			(xy 365.770668 -159.868616) (xy 365.771207 -159.879634) (xy 365.780427 -159.89965) (xy 365.788448 -159.907224)
			(xy 365.824398 -159.938513) (xy 365.891767 -160.005937) (xy 365.953641 -160.078437) (xy 366.00964 -160.155566)
			(xy 366.059417 -160.236849) (xy 366.102668 -160.321785) (xy 366.139124 -160.409851) (xy 366.168563 -160.500505)
			(xy 366.190801 -160.593187) (xy 366.205703 -160.687329) (xy 366.213177 -160.782349) (xy 366.213644 -160.830006)
			(xy 366.213154 -160.880184) (xy 366.204867 -160.980199) (xy 366.18835 -161.079187) (xy 366.163717 -161.176473)
			(xy 366.131134 -161.271394) (xy 366.090826 -161.3633) (xy 366.043066 -161.451564) (xy 365.988182 -161.535583)
			(xy 365.926547 -161.614783) (xy 365.858584 -161.688624) (xy 365.784756 -161.756601) (xy 365.705567 -161.81825)
			(xy 365.621558 -161.87315) (xy 365.533303 -161.920926) (xy 365.441404 -161.961252) (xy 365.34649 -161.993852)
			(xy 365.249208 -162.018504) (xy 365.150223 -162.035039) (xy 365.05021 -162.043344) (xy 365.000032 -162.043872)
			(xy 364.95237 -162.043379) (xy 364.857341 -162.035896) (xy 364.763192 -162.02098) (xy 364.670502 -161.998724)
			(xy 364.579845 -161.969265) (xy 364.491778 -161.932784) (xy 364.406845 -161.889507) (xy 364.325569 -161.8397)
			(xy 364.24845 -161.78367) (xy 364.175965 -161.721763) (xy 364.10856 -161.65436) (xy 364.07725 -161.618422)
			(xy 364.069668 -161.610411) (xy 364.049658 -161.601189) (xy 364.038642 -161.600642) (xy 363.961426 -161.600642)
			(xy 363.950407 -161.601181) (xy 363.93039 -161.610398) (xy 363.922818 -161.618422) (xy 363.891498 -161.65435)
			(xy 363.824086 -161.721743) (xy 363.751596 -161.783641) (xy 363.674476 -161.839665) (xy 363.5932 -161.889469)
			(xy 363.508268 -161.932746) (xy 363.420205 -161.969229) (xy 363.329552 -161.998695) (xy 363.236868 -162.020961)
			(xy 363.142723 -162.035891) (xy 363.047697 -162.043392) (xy 363.000036 -162.043872) (xy 362.949868 -162.04336)
			(xy 362.849875 -162.035078) (xy 362.750907 -162.018567) (xy 362.653641 -161.993942) (xy 362.55874 -161.961369)
			(xy 362.466852 -161.92107) (xy 362.378606 -161.873323) (xy 362.294604 -161.818451) (xy 362.21542 -161.756831)
			(xy 362.141594 -161.688883) (xy 362.07363 -161.615071) (xy 362.011994 -161.535899) (xy 361.957105 -161.451909)
			(xy 361.909339 -161.363672) (xy 361.869022 -161.271793) (xy 361.83643 -161.176899) (xy 361.811784 -161.079638)
			(xy 361.795253 -160.980673) (xy 361.786951 -160.880682) (xy 361.786424 -160.830514) (xy 361.786424 -160.830006)
			(xy 361.786913 -160.78235) (xy 361.794381 -160.687331) (xy 361.809279 -160.59319) (xy 361.831514 -160.500508)
			(xy 361.860951 -160.409855) (xy 361.897408 -160.321791) (xy 361.94066 -160.236857) (xy 361.99044 -160.155578)
			(xy 362.046442 -160.078453) (xy 362.108322 -160.005959) (xy 362.175696 -159.938542) (xy 362.21162 -159.907224)
			(xy 362.219633 -159.899643) (xy 362.228856 -159.879633) (xy 362.2294 -159.868616) (xy 362.2294 -159.7914)
			(xy 362.228862 -159.780381) (xy 362.219642 -159.760365) (xy 362.21162 -159.752792) (xy 362.174006 -159.719957)
			(xy 362.103686 -159.649065) (xy 362.039427 -159.572635) (xy 361.981664 -159.491185) (xy 361.930788 -159.405265)
			(xy 361.887143 -159.315455) (xy 361.851024 -159.222363) (xy 361.822675 -159.126619) (xy 361.802287 -159.028869)
			(xy 361.789999 -158.929775) (xy 361.785893 -158.830006) (xy 359.492747 -158.830006) (xy 359.596877 -158.939217)
			(xy 359.706261 -159.065454) (xy 359.809514 -159.196753) (xy 359.906403 -159.332816) (xy 359.996708 -159.473335)
			(xy 360.080225 -159.617992) (xy 360.156764 -159.766459) (xy 360.226152 -159.9184) (xy 360.288231 -160.07347)
			(xy 360.342862 -160.231318) (xy 360.389921 -160.391587) (xy 360.4293 -160.553913) (xy 360.460911 -160.71793)
			(xy 360.484682 -160.883264) (xy 360.50056 -161.049543) (xy 360.508507 -161.216389) (xy 360.509058 -161.299906)
			(xy 360.509058 -166.649908) (xy 360.509557 -166.745241) (xy 360.51765 -166.935736) (xy 360.53382 -167.125715)
			(xy 360.558038 -167.314837) (xy 360.590261 -167.502761) (xy 360.629411 -167.684417) (xy 365.513608 -167.684417)
			(xy 365.513608 -167.575771) (xy 365.521539 -167.467414) (xy 365.537358 -167.359925) (xy 365.560981 -167.253878)
			(xy 365.592282 -167.149838) (xy 365.631094 -167.04836) (xy 365.677209 -166.949986) (xy 365.730383 -166.855241)
			(xy 365.790331 -166.76463) (xy 365.856733 -166.678636) (xy 365.929235 -166.597719) (xy 366.00745 -166.522311)
			(xy 366.090961 -166.452812) (xy 366.179322 -166.389595) (xy 366.272062 -166.332997) (xy 366.368686 -166.283319)
			(xy 366.468678 -166.240827) (xy 366.571506 -166.205747) (xy 366.67662 -166.178267) (xy 366.783459 -166.158532)
			(xy 366.891454 -166.146649) (xy 367.000028 -166.142682) (xy 367.108602 -166.146649) (xy 367.216597 -166.158532)
			(xy 367.323436 -166.178267) (xy 367.42855 -166.205747) (xy 367.531378 -166.240827) (xy 367.63137 -166.283319)
			(xy 367.727994 -166.332997) (xy 367.820734 -166.389595) (xy 367.909095 -166.452812) (xy 367.992606 -166.522311)
			(xy 368.070821 -166.597719) (xy 368.143323 -166.678636) (xy 368.209725 -166.76463) (xy 368.252971 -166.829996)
			(xy 397.160973 -166.829996) (xy 397.165078 -166.730227) (xy 397.177366 -166.631132) (xy 397.197754 -166.533381)
			(xy 397.226103 -166.437636) (xy 397.262222 -166.344543) (xy 397.305867 -166.254733) (xy 397.356743 -166.168811)
			(xy 397.414505 -166.08736) (xy 397.478764 -166.010929) (xy 397.549084 -165.940036) (xy 397.586708 -165.907212)
			(xy 397.594725 -165.899634) (xy 397.603946 -165.879622) (xy 397.604488 -165.868604) (xy 397.604488 -165.791388)
			(xy 397.60396 -165.780368) (xy 397.594734 -165.760351) (xy 397.586708 -165.75278) (xy 397.549083 -165.719958)
			(xy 397.478763 -165.649065) (xy 397.414504 -165.572634) (xy 397.356742 -165.491183) (xy 397.305867 -165.405261)
			(xy 397.262223 -165.315451) (xy 397.226104 -165.222358) (xy 397.197756 -165.126613) (xy 397.177369 -165.028863)
			(xy 397.165081 -164.929768) (xy 397.160976 -164.829999) (xy 397.165081 -164.730229) (xy 397.177369 -164.631135)
			(xy 397.197756 -164.533384) (xy 397.226105 -164.437639) (xy 397.262224 -164.344547) (xy 397.305869 -164.254736)
			(xy 397.356744 -164.168815) (xy 397.414506 -164.087364) (xy 397.478764 -164.010933) (xy 397.549085 -163.94004)
			(xy 397.586708 -163.907216) (xy 397.594723 -163.899637) (xy 397.603946 -163.879625) (xy 397.604488 -163.868608)
			(xy 397.604488 -163.791392) (xy 397.603958 -163.780372) (xy 397.594733 -163.760355) (xy 397.586708 -163.752784)
			(xy 397.549087 -163.719958) (xy 397.478767 -163.649065) (xy 397.414508 -163.572634) (xy 397.356746 -163.491183)
			(xy 397.305871 -163.405262) (xy 397.262227 -163.315452) (xy 397.226108 -163.22236) (xy 397.197759 -163.126615)
			(xy 397.177372 -163.028865) (xy 397.165084 -162.92977) (xy 397.160979 -162.830001) (xy 397.165084 -162.730232)
			(xy 397.177372 -162.631138) (xy 397.197759 -162.533388) (xy 397.226107 -162.437643) (xy 397.262226 -162.34455)
			(xy 397.30587 -162.25474) (xy 397.356745 -162.168819) (xy 397.414507 -162.087368) (xy 397.478765 -162.010937)
			(xy 397.549085 -161.940044) (xy 397.586708 -161.90722) (xy 397.594721 -161.899639) (xy 397.603945 -161.879629)
			(xy 397.604488 -161.868612) (xy 397.604488 -161.791396) (xy 397.603956 -161.780376) (xy 397.594733 -161.76036)
			(xy 397.586708 -161.752788) (xy 397.549091 -161.719957) (xy 397.478771 -161.649065) (xy 397.414512 -161.572634)
			(xy 397.35675 -161.491184) (xy 397.305875 -161.405263) (xy 397.262231 -161.315453) (xy 397.226112 -161.222361)
			(xy 397.197763 -161.126617) (xy 397.177375 -161.028867) (xy 397.165088 -160.929773) (xy 397.160982 -160.830004)
			(xy 397.165087 -160.730235) (xy 397.177374 -160.631141) (xy 397.197761 -160.533391) (xy 397.226109 -160.437646)
			(xy 397.262227 -160.344554) (xy 397.305871 -160.254744) (xy 397.356746 -160.168823) (xy 397.414508 -160.087372)
			(xy 397.478765 -160.010941) (xy 397.549085 -159.940048) (xy 397.586708 -159.907224) (xy 397.594719 -159.899642)
			(xy 397.603944 -159.879632) (xy 397.604488 -159.868616) (xy 397.604488 -159.7914) (xy 397.603954 -159.780381)
			(xy 397.594732 -159.760364) (xy 397.586708 -159.752792) (xy 397.549095 -159.719957) (xy 397.478775 -159.649064)
			(xy 397.414516 -159.572635) (xy 397.356754 -159.491184) (xy 397.305879 -159.405264) (xy 397.262234 -159.315454)
			(xy 397.226115 -159.222363) (xy 397.197766 -159.126619) (xy 397.177379 -159.028869) (xy 397.165091 -158.929775)
			(xy 397.160985 -158.830006) (xy 397.16509 -158.730238) (xy 397.177377 -158.631144) (xy 397.197763 -158.533394)
			(xy 397.226111 -158.43765) (xy 397.262229 -158.344558) (xy 397.305873 -158.254748) (xy 397.356747 -158.168827)
			(xy 397.414508 -158.087376) (xy 397.478766 -158.010945) (xy 397.549085 -157.940052) (xy 397.586708 -157.907228)
			(xy 397.594718 -157.899644) (xy 397.603943 -157.879636) (xy 397.604488 -157.86862) (xy 397.604488 -157.791404)
			(xy 397.603952 -157.780385) (xy 397.594731 -157.760368) (xy 397.586708 -157.752796) (xy 397.549099 -157.719956)
			(xy 397.478779 -157.649064) (xy 397.41452 -157.572635) (xy 397.356758 -157.491185) (xy 397.305883 -157.405265)
			(xy 397.262238 -157.315455) (xy 397.226119 -157.222364) (xy 397.19777 -157.12662) (xy 397.177382 -157.028871)
			(xy 397.165094 -156.929777) (xy 397.160988 -156.830009) (xy 397.165093 -156.730241) (xy 397.177379 -156.631147)
			(xy 397.197766 -156.533397) (xy 397.226113 -156.437653) (xy 397.262231 -156.344561) (xy 397.305874 -156.254751)
			(xy 397.356748 -156.16883) (xy 397.414509 -156.08738) (xy 397.478766 -156.010949) (xy 397.549085 -155.940056)
			(xy 397.586708 -155.907232) (xy 397.594716 -155.899646) (xy 397.603942 -155.87964) (xy 397.604488 -155.868624)
			(xy 397.604488 -155.791408) (xy 397.603949 -155.780389) (xy 397.594731 -155.760372) (xy 397.586708 -155.7528)
			(xy 397.549103 -155.719956) (xy 397.478783 -155.649064) (xy 397.414524 -155.572635) (xy 397.356762 -155.491185)
			(xy 397.305887 -155.405266) (xy 397.262242 -155.315457) (xy 397.226123 -155.222366) (xy 397.197774 -155.126622)
			(xy 397.177386 -155.028873) (xy 397.165097 -154.92978) (xy 397.160991 -154.830012) (xy 397.165095 -154.730244)
			(xy 397.177382 -154.63115) (xy 397.197768 -154.533401) (xy 397.226115 -154.437656) (xy 397.262233 -154.344565)
			(xy 397.305876 -154.254755) (xy 397.35675 -154.168834) (xy 397.41451 -154.087383) (xy 397.478767 -154.010953)
			(xy 397.549085 -153.94006) (xy 397.586708 -153.907236) (xy 397.594714 -153.899649) (xy 397.603942 -153.879643)
			(xy 397.604488 -153.868628) (xy 397.604488 -153.791412) (xy 397.603947 -153.780393) (xy 397.59473 -153.760377)
			(xy 397.586708 -153.752804) (xy 397.550784 -153.721486) (xy 397.483413 -153.654066) (xy 397.421536 -153.58157)
			(xy 397.365535 -153.504444) (xy 397.315755 -153.423165) (xy 397.272502 -153.338232) (xy 397.236043 -153.250169)
			(xy 397.206602 -153.159517) (xy 397.184361 -153.066836) (xy 397.169456 -152.972697) (xy 397.16198 -152.877678)
			(xy 397.161512 -152.830022) (xy 397.162073 -152.779845) (xy 397.170357 -152.679834) (xy 397.186871 -152.580848)
			(xy 397.211501 -152.483564) (xy 397.24408 -152.388646) (xy 397.284385 -152.296742) (xy 397.332141 -152.208479)
			(xy 397.387021 -152.124461) (xy 397.448651 -152.045262) (xy 397.51661 -151.971421) (xy 397.590434 -151.903444)
			(xy 397.669619 -151.841794) (xy 397.753623 -151.786893) (xy 397.841874 -151.739116) (xy 397.933768 -151.698789)
			(xy 398.028678 -151.666187) (xy 398.125957 -151.641532) (xy 398.224938 -151.624994) (xy 398.324947 -151.616685)
			(xy 398.375124 -151.616156) (xy 398.422787 -151.616598) (xy 398.517818 -151.624087) (xy 398.611969 -151.639007)
			(xy 398.704659 -151.661268) (xy 398.795316 -151.690732) (xy 398.883383 -151.727218) (xy 398.968317 -151.7705)
			(xy 399.049592 -151.820312) (xy 399.12671 -151.876346) (xy 399.199193 -151.938258) (xy 399.266597 -152.005666)
			(xy 399.297906 -152.041606) (xy 399.305477 -152.049631) (xy 399.325495 -152.058848) (xy 399.336514 -152.059386)
			(xy 399.41373 -152.059386) (xy 399.424752 -152.058869) (xy 399.444768 -152.049635) (xy 399.452338 -152.041606)
			(xy 399.483634 -152.005656) (xy 399.551049 -151.938264) (xy 399.623541 -151.876366) (xy 399.700663 -151.820343)
			(xy 399.781942 -151.77054) (xy 399.866876 -151.727265) (xy 399.954941 -151.690783) (xy 400.045597 -151.66132)
			(xy 400.138284 -151.639057) (xy 400.232431 -151.624131) (xy 400.327459 -151.616634) (xy 400.37512 -151.616156)
			(xy 400.425287 -151.616687) (xy 400.525277 -151.624972) (xy 400.624243 -151.641486) (xy 400.721506 -151.666114)
			(xy 400.816405 -151.698689) (xy 400.908289 -151.738988) (xy 400.996533 -151.786735) (xy 401.080533 -151.841606)
			(xy 401.159716 -151.903225) (xy 401.23354 -151.971171) (xy 401.301503 -152.044981) (xy 401.363139 -152.12415)
			(xy 401.418028 -152.208138) (xy 401.465796 -152.296372) (xy 401.506115 -152.388247) (xy 401.53871 -152.483139)
			(xy 401.56336 -152.580397) (xy 401.579895 -152.679359) (xy 401.588202 -152.779347) (xy 401.588732 -152.829514)
			(xy 401.588732 -152.830022) (xy 401.588278 -152.877679) (xy 401.580808 -152.9727) (xy 401.565908 -153.066842)
			(xy 401.543669 -153.159525) (xy 401.514229 -153.250178) (xy 401.477769 -153.338243) (xy 401.434513 -153.423176)
			(xy 401.384729 -153.504455) (xy 401.328723 -153.581579) (xy 401.26684 -153.654072) (xy 401.199462 -153.721487)
			(xy 401.163536 -153.752804) (xy 401.155503 -153.760367) (xy 401.146292 -153.780391) (xy 401.145756 -153.791412)
			(xy 401.145756 -153.868628) (xy 401.146261 -153.879651) (xy 401.155502 -153.899669) (xy 401.163536 -153.907236)
			(xy 401.201179 -153.940039) (xy 401.271502 -154.010932) (xy 401.335763 -154.087363) (xy 401.393527 -154.168815)
			(xy 401.444405 -154.254738) (xy 401.488051 -154.34455) (xy 401.524171 -154.437644) (xy 401.55252 -154.533391)
			(xy 401.572908 -154.631143) (xy 401.585195 -154.73024) (xy 401.5893 -154.830012) (xy 401.585193 -154.929783)
			(xy 401.572904 -155.02888) (xy 401.552515 -155.126632) (xy 401.524163 -155.222378) (xy 401.488042 -155.315472)
			(xy 401.444394 -155.405283) (xy 401.393515 -155.491204) (xy 401.335749 -155.572655) (xy 401.271486 -155.649085)
			(xy 401.201162 -155.719977) (xy 401.163536 -155.7528) (xy 401.155505 -155.760364) (xy 401.146293 -155.780388)
			(xy 401.145756 -155.791408) (xy 401.145756 -155.868624) (xy 401.146263 -155.879647) (xy 401.155502 -155.899664)
			(xy 401.163536 -155.907232) (xy 401.201175 -155.94004) (xy 401.271498 -156.010932) (xy 401.335759 -156.087363)
			(xy 401.393523 -156.168815) (xy 401.444401 -156.254737) (xy 401.488047 -156.344549) (xy 401.524167 -156.437643)
			(xy 401.552517 -156.533389) (xy 401.572904 -156.631141) (xy 401.585192 -156.730238) (xy 401.589297 -156.830009)
			(xy 401.585191 -156.92978) (xy 401.572901 -157.028877) (xy 401.552512 -157.126628) (xy 401.524161 -157.222375)
			(xy 401.48804 -157.315468) (xy 401.444392 -157.405279) (xy 401.393514 -157.4912) (xy 401.335748 -157.572651)
			(xy 401.271486 -157.649081) (xy 401.201161 -157.719973) (xy 401.163536 -157.752796) (xy 401.155507 -157.760362)
			(xy 401.146294 -157.780384) (xy 401.145756 -157.791404) (xy 401.145756 -157.86862) (xy 401.146265 -157.879643)
			(xy 401.155503 -157.89966) (xy 401.163536 -157.907228) (xy 401.201171 -157.94004) (xy 401.271494 -158.010933)
			(xy 401.335755 -158.087363) (xy 401.393519 -158.168814) (xy 401.444397 -158.254736) (xy 401.488043 -158.344548)
			(xy 401.524163 -158.437641) (xy 401.552513 -158.533387) (xy 401.572901 -158.631139) (xy 401.585189 -158.730236)
			(xy 401.589294 -158.830006) (xy 401.585188 -158.929777) (xy 401.572899 -159.028874) (xy 401.55251 -159.126625)
			(xy 401.524159 -159.222371) (xy 401.488038 -159.315464) (xy 401.444391 -159.405275) (xy 401.393512 -159.491197)
			(xy 401.335747 -159.572647) (xy 401.271485 -159.649077) (xy 401.201161 -159.719969) (xy 401.163536 -159.752792)
			(xy 401.155508 -159.760359) (xy 401.146295 -159.78038) (xy 401.145756 -159.7914) (xy 401.145756 -159.868616)
			(xy 401.146267 -159.879639) (xy 401.155504 -159.899656) (xy 401.163536 -159.907224) (xy 401.201167 -159.940041)
			(xy 401.27149 -160.010933) (xy 401.335751 -160.087363) (xy 401.393516 -160.168814) (xy 401.444393 -160.254735)
			(xy 401.488039 -160.344546) (xy 401.52416 -160.43764) (xy 401.55251 -160.533386) (xy 401.572898 -160.631137)
			(xy 401.585186 -160.730233) (xy 401.589291 -160.830004) (xy 401.585185 -160.929774) (xy 401.572896 -161.028871)
			(xy 401.552508 -161.126622) (xy 401.524157 -161.222368) (xy 401.488036 -161.315461) (xy 401.444389 -161.405272)
			(xy 401.393511 -161.491193) (xy 401.335746 -161.572643) (xy 401.271485 -161.649073) (xy 401.201161 -161.719965)
			(xy 401.163536 -161.752788) (xy 401.15551 -161.760357) (xy 401.146296 -161.780377) (xy 401.145756 -161.791396)
			(xy 401.145756 -161.868612) (xy 401.146269 -161.879634) (xy 401.155504 -161.899652) (xy 401.163536 -161.90722)
			(xy 401.201163 -161.940041) (xy 401.271486 -162.010933) (xy 401.335747 -162.087363) (xy 401.393512 -162.168813)
			(xy 401.444389 -162.254734) (xy 401.488036 -162.344545) (xy 401.524156 -162.437638) (xy 401.552506 -162.533384)
			(xy 401.572894 -162.631135) (xy 401.585182 -162.730231) (xy 401.589288 -162.830001) (xy 401.585182 -162.929772)
			(xy 401.572894 -163.028867) (xy 401.552505 -163.126619) (xy 401.524155 -163.222364) (xy 401.488035 -163.315457)
			(xy 401.444388 -163.405268) (xy 401.39351 -163.491189) (xy 401.335745 -163.57264) (xy 401.271484 -163.649069)
			(xy 401.201161 -163.719961) (xy 401.163536 -163.752784) (xy 401.155512 -163.760355) (xy 401.146296 -163.780373)
			(xy 401.145756 -163.791392) (xy 401.145756 -163.868608) (xy 401.146272 -163.87963) (xy 401.155505 -163.899648)
			(xy 401.163536 -163.907216) (xy 401.201159 -163.940041) (xy 401.271482 -164.010933) (xy 401.335743 -164.087362)
			(xy 401.393508 -164.168813) (xy 401.444385 -164.254734) (xy 401.488032 -164.344544) (xy 401.524152 -164.437637)
			(xy 401.552503 -164.533382) (xy 401.572891 -164.631133) (xy 401.585179 -164.730229) (xy 401.589285 -164.829999)
			(xy 401.585179 -164.929769) (xy 401.572891 -165.028864) (xy 401.552503 -165.126615) (xy 401.524153 -165.222361)
			(xy 401.488033 -165.315454) (xy 401.444386 -165.405264) (xy 401.393509 -165.491185) (xy 401.335745 -165.572636)
			(xy 401.271484 -165.649065) (xy 401.201161 -165.719957) (xy 401.163536 -165.75278) (xy 401.155514 -165.760352)
			(xy 401.146297 -165.78037) (xy 401.145756 -165.791388) (xy 401.145756 -165.868604) (xy 401.146274 -165.879626)
			(xy 401.155505 -165.899643) (xy 401.163536 -165.907212) (xy 401.201155 -165.940042) (xy 401.271478 -166.010933)
			(xy 401.335739 -166.087362) (xy 401.393504 -166.168812) (xy 401.444381 -166.254733) (xy 401.488028 -166.344543)
			(xy 401.524149 -166.437635) (xy 401.552499 -166.53338) (xy 401.572887 -166.631131) (xy 401.585176 -166.730226)
			(xy 401.589282 -166.829996) (xy 401.585177 -166.929766) (xy 401.572889 -167.028861) (xy 401.552501 -167.126612)
			(xy 401.524151 -167.222357) (xy 401.488031 -167.31545) (xy 401.444385 -167.40526) (xy 401.393508 -167.491181)
			(xy 401.335744 -167.572632) (xy 401.271483 -167.649061) (xy 401.201161 -167.719953) (xy 401.163536 -167.752776)
			(xy 401.155516 -167.76035) (xy 401.146298 -167.780366) (xy 401.145756 -167.791384) (xy 401.145756 -167.8686)
			(xy 401.146276 -167.879622) (xy 401.155506 -167.899639) (xy 401.163536 -167.907208) (xy 401.199475 -167.938508)
			(xy 401.266845 -168.005932) (xy 401.32872 -168.07843) (xy 401.384719 -168.155558) (xy 401.434498 -168.236839)
			(xy 401.477749 -168.321774) (xy 401.514207 -168.409839) (xy 401.543646 -168.500491) (xy 401.565886 -168.593173)
			(xy 401.58079 -168.687314) (xy 401.588265 -168.782333) (xy 401.588732 -168.82999) (xy 401.588238 -168.880168)
			(xy 401.579953 -168.980183) (xy 401.563437 -169.079172) (xy 401.538804 -169.176459) (xy 401.506223 -169.271379)
			(xy 401.465915 -169.363286) (xy 401.418156 -169.45155) (xy 401.363272 -169.53557) (xy 401.301637 -169.61477)
			(xy 401.233674 -169.688611) (xy 401.159846 -169.756589) (xy 401.080657 -169.818238) (xy 400.996648 -169.873138)
			(xy 400.908392 -169.920914) (xy 400.816494 -169.961239) (xy 400.721579 -169.993839) (xy 400.624297 -170.01849)
			(xy 400.525311 -170.035024) (xy 400.425298 -170.043329) (xy 400.37512 -170.043856) (xy 400.327458 -170.043378)
			(xy 400.232428 -170.035893) (xy 400.138278 -170.020976) (xy 400.045589 -169.998719) (xy 399.954931 -169.969258)
			(xy 399.866864 -169.932776) (xy 399.781931 -169.889498) (xy 399.700655 -169.839689) (xy 399.623537 -169.783658)
			(xy 399.551052 -169.721749) (xy 399.483648 -169.654345) (xy 399.452338 -169.618406) (xy 399.444748 -169.610403)
			(xy 399.424745 -169.601173) (xy 399.41373 -169.600626) (xy 399.336514 -169.600626) (xy 399.325495 -169.601163)
			(xy 399.305478 -169.610382) (xy 399.297906 -169.618406) (xy 399.266589 -169.654337) (xy 399.199176 -169.721729)
			(xy 399.126687 -169.783628) (xy 399.049566 -169.839652) (xy 398.96829 -169.889456) (xy 398.883358 -169.932733)
			(xy 398.795295 -169.969216) (xy 398.704641 -169.998681) (xy 398.611956 -170.020947) (xy 398.517811 -170.035876)
			(xy 398.422785 -170.043376) (xy 398.375124 -170.043856) (xy 398.324958 -170.043271) (xy 398.224969 -170.034989)
			(xy 398.126005 -170.018479) (xy 398.028743 -169.993855) (xy 397.933845 -169.961284) (xy 397.841961 -169.920988)
			(xy 397.753718 -169.873244) (xy 397.669718 -169.818376) (xy 397.590535 -169.756761) (xy 397.516711 -169.688817)
			(xy 397.448748 -169.61501) (xy 397.387111 -169.535844) (xy 397.332221 -169.451859) (xy 397.284453 -169.363628)
			(xy 397.244133 -169.271755) (xy 397.211537 -169.176866) (xy 397.186887 -169.07961) (xy 397.170351 -168.98065)
			(xy 397.162042 -168.880664) (xy 397.161512 -168.830498) (xy 397.161512 -168.82999) (xy 397.161994 -168.782334)
			(xy 397.169463 -168.687314) (xy 397.184361 -168.593173) (xy 397.206598 -168.500491) (xy 397.236036 -168.409839)
			(xy 397.272493 -168.321774) (xy 397.315746 -168.236841) (xy 397.365527 -168.155562) (xy 397.42153 -168.078437)
			(xy 397.483409 -168.005943) (xy 397.550784 -167.938526) (xy 397.586708 -167.907208) (xy 397.594727 -167.899632)
			(xy 397.603947 -167.879618) (xy 397.604488 -167.8686) (xy 397.604488 -167.791384) (xy 397.603963 -167.780363)
			(xy 397.594735 -167.760347) (xy 397.586708 -167.752776) (xy 397.549079 -167.719959) (xy 397.478759 -167.649065)
			(xy 397.4145 -167.572634) (xy 397.356739 -167.491182) (xy 397.305863 -167.40526) (xy 397.262219 -167.31545)
			(xy 397.226101 -167.222357) (xy 397.197752 -167.126611) (xy 397.177365 -167.028861) (xy 397.165078 -166.929766)
			(xy 397.160973 -166.829996) (xy 368.252971 -166.829996) (xy 368.269673 -166.855241) (xy 368.322847 -166.949986)
			(xy 368.368962 -167.04836) (xy 368.407774 -167.149838) (xy 368.439075 -167.253878) (xy 368.462698 -167.359925)
			(xy 368.478517 -167.467414) (xy 368.486448 -167.575771) (xy 368.486944 -167.630094) (xy 368.486448 -167.684417)
			(xy 368.478517 -167.792774) (xy 368.462698 -167.900263) (xy 368.439075 -168.00631) (xy 368.407774 -168.11035)
			(xy 368.368962 -168.211828) (xy 368.322847 -168.310202) (xy 368.269673 -168.404947) (xy 368.209725 -168.495558)
			(xy 368.143323 -168.581552) (xy 368.070821 -168.662469) (xy 367.992606 -168.737877) (xy 367.909095 -168.807376)
			(xy 367.820734 -168.870593) (xy 367.727994 -168.927191) (xy 367.63137 -168.976869) (xy 367.531378 -169.019361)
			(xy 367.42855 -169.054441) (xy 367.323436 -169.081921) (xy 367.216597 -169.101656) (xy 367.108602 -169.113539)
			(xy 367.000028 -169.117507) (xy 366.891454 -169.113539) (xy 366.783459 -169.101656) (xy 366.67662 -169.081921)
			(xy 366.571506 -169.054441) (xy 366.468678 -169.019361) (xy 366.368686 -168.976869) (xy 366.272062 -168.927191)
			(xy 366.179322 -168.870593) (xy 366.090961 -168.807376) (xy 366.00745 -168.737877) (xy 365.929235 -168.662469)
			(xy 365.856733 -168.581552) (xy 365.790331 -168.495558) (xy 365.730383 -168.404947) (xy 365.677209 -168.310202)
			(xy 365.631094 -168.211828) (xy 365.592282 -168.11035) (xy 365.560981 -168.00631) (xy 365.537358 -167.900263)
			(xy 365.521539 -167.792774) (xy 365.513608 -167.684417) (xy 360.629411 -167.684417) (xy 360.630431 -167.689148)
			(xy 360.678475 -167.873662) (xy 360.734307 -168.05597) (xy 360.797826 -168.235745) (xy 360.868918 -168.412662)
			(xy 360.947454 -168.586403) (xy 361.033294 -168.756653) (xy 361.126281 -168.923107) (xy 361.22625 -169.085465)
			(xy 361.333019 -169.243433) (xy 361.446396 -169.396728) (xy 361.566177 -169.545073) (xy 361.692146 -169.6882)
			(xy 361.824076 -169.825852) (xy 361.961729 -169.957781) (xy 362.104858 -170.083749) (xy 362.253204 -170.203529)
			(xy 362.406499 -170.316905) (xy 362.564469 -170.423672) (xy 362.726827 -170.523639) (xy 362.893282 -170.616625)
			(xy 363.063534 -170.702463) (xy 363.237275 -170.780998) (xy 363.414192 -170.852088) (xy 363.593968 -170.915605)
			(xy 363.776277 -170.971436) (xy 363.960791 -171.019478) (xy 364.147178 -171.059646) (xy 364.335102 -171.091868)
			(xy 364.524225 -171.116085) (xy 364.714204 -171.132253) (xy 364.904699 -171.140344) (xy 365.000032 -171.140882)
			(xy 403.999954 -171.140882) (xy 404.095288 -171.140384) (xy 404.285785 -171.132294) (xy 404.475767 -171.116126)
			(xy 404.664891 -171.091909) (xy 404.852817 -171.059688) (xy 405.039206 -171.01952) (xy 405.223723 -170.971477)
			(xy 405.406034 -170.915647) (xy 405.585812 -170.852129) (xy 405.762731 -170.781038) (xy 405.936475 -170.702503)
			(xy 406.106728 -170.616665) (xy 406.273185 -170.523678) (xy 406.435545 -170.423711) (xy 406.593517 -170.316942)
			(xy 406.746814 -170.203565) (xy 406.895162 -170.083785) (xy 407.038292 -169.957816) (xy 407.175947 -169.825886)
			(xy 407.307879 -169.688232) (xy 407.43385 -169.545103) (xy 407.553632 -169.396757) (xy 407.667011 -169.243461)
			(xy 407.773781 -169.085491) (xy 407.873751 -168.923132) (xy 407.96674 -168.756676) (xy 408.05258 -168.586423)
			(xy 408.131117 -168.412681) (xy 408.20221 -168.235762) (xy 408.26573 -168.055986) (xy 408.321562 -167.873675)
			(xy 408.369607 -167.689159) (xy 408.409778 -167.50277) (xy 408.442001 -167.314844) (xy 408.46622 -167.12572)
			(xy 408.48239 -166.935739) (xy 408.490483 -166.745242) (xy 408.490928 -166.649908) (xy 408.490928 -163.299902)
			(xy 408.491427 -163.194368) (xy 408.499512 -162.983455) (xy 408.515669 -162.773006) (xy 408.539875 -162.563331)
			(xy 408.572094 -162.354737) (xy 408.61228 -162.14753) (xy 408.660372 -161.942014) (xy 408.716302 -161.738491)
			(xy 408.779985 -161.53726) (xy 408.85133 -161.338616) (xy 408.930231 -161.14285) (xy 409.016573 -160.95025)
			(xy 409.110228 -160.761098) (xy 409.21106 -160.575672) (xy 409.31892 -160.394245) (xy 409.43365 -160.217082)
			(xy 409.555081 -160.044444) (xy 409.683036 -159.876583) (xy 409.817327 -159.713747) (xy 409.957756 -159.556174)
			(xy 410.104118 -159.404096) (xy 410.256198 -159.257735) (xy 410.413771 -159.117306) (xy 410.576608 -158.983016)
			(xy 410.74447 -158.855062) (xy 410.917109 -158.733632) (xy 411.094272 -158.618903) (xy 411.2757 -158.511044)
			(xy 411.461126 -158.410213) (xy 411.650279 -158.316559) (xy 411.842879 -158.230219) (xy 412.038645 -158.151319)
			(xy 412.23729 -158.079975) (xy 412.438522 -158.016293) (xy 412.642045 -157.960365) (xy 412.847561 -157.912273)
			(xy 413.054769 -157.872089) (xy 413.263363 -157.839871) (xy 413.473038 -157.815666) (xy 413.683487 -157.79951)
			(xy 413.8944 -157.791427) (xy 413.999934 -157.790896) (xy 434.999892 -157.790896) (xy 435.095226 -157.79039)
			(xy 435.285721 -157.782299) (xy 435.475702 -157.766129) (xy 435.664825 -157.741911) (xy 435.85275 -157.709689)
			(xy 436.039137 -157.66952) (xy 436.223653 -157.621476) (xy 436.405963 -157.565645) (xy 436.585739 -157.502126)
			(xy 436.762657 -157.431035) (xy 436.936399 -157.3525) (xy 437.106651 -157.266661) (xy 437.273106 -157.173674)
			(xy 437.435465 -157.073706) (xy 437.593435 -156.966938) (xy 437.746732 -156.853561) (xy 437.895078 -156.73378)
			(xy 438.038207 -156.607812) (xy 438.175861 -156.475882) (xy 438.307792 -156.338229) (xy 438.433761 -156.195101)
			(xy 438.553543 -156.046755) (xy 438.66692 -155.89346) (xy 438.77369 -155.73549) (xy 438.873659 -155.573132)
			(xy 438.966647 -155.406677) (xy 439.052487 -155.236426) (xy 439.131023 -155.062685) (xy 439.202116 -154.885767)
			(xy 439.265635 -154.705991) (xy 439.321468 -154.523682) (xy 439.369513 -154.339167) (xy 439.409683 -154.152779)
			(xy 439.441907 -153.964854) (xy 439.466126 -153.775732) (xy 439.482297 -153.585751) (xy 439.49039 -153.395256)
			(xy 439.490866 -153.299922) (xy 439.490866 -136.77011) (xy 439.491377 -136.664578) (xy 439.499472 -136.453669)
			(xy 439.515639 -136.243225) (xy 439.539854 -136.033554) (xy 439.572082 -135.824965) (xy 439.612275 -135.617763)
			(xy 439.660375 -135.412253) (xy 439.71631 -135.208736) (xy 439.78 -135.00751) (xy 439.851349 -134.808871)
			(xy 439.930254 -134.613111) (xy 440.016599 -134.420517) (xy 440.110257 -134.231371) (xy 440.211091 -134.045951)
			(xy 440.318953 -133.864528) (xy 440.433684 -133.687371) (xy 440.555116 -133.514737) (xy 440.68307 -133.346881)
			(xy 440.81736 -133.184049) (xy 440.957788 -133.026479) (xy 441.104148 -132.874404) (xy 441.256225 -132.728046)
			(xy 441.413796 -132.58762) (xy 441.576629 -132.453332) (xy 441.744487 -132.325379) (xy 441.917122 -132.203949)
			(xy 442.094281 -132.08922) (xy 442.275704 -131.981361) (xy 442.461126 -131.880529) (xy 442.650273 -131.786873)
			(xy 442.842868 -131.70053) (xy 443.038629 -131.621627) (xy 443.237269 -131.55028) (xy 443.438495 -131.486593)
			(xy 443.642013 -131.430659) (xy 443.847524 -131.382562) (xy 444.054726 -131.342371) (xy 444.263316 -131.310146)
			(xy 444.472987 -131.285933) (xy 444.683431 -131.269768) (xy 444.89434 -131.261676) (xy 444.999872 -131.261104)
			(xy 471.000074 -131.261104) (xy 471.095408 -131.260599) (xy 471.285904 -131.252508) (xy 471.475885 -131.236339)
			(xy 471.665009 -131.212122) (xy 471.852935 -131.1799) (xy 472.039323 -131.139731) (xy 472.223839 -131.091688)
			(xy 472.40615 -131.035857) (xy 472.585927 -130.972339) (xy 472.762846 -130.901249) (xy 472.936588 -130.822713)
			(xy 473.106841 -130.736875) (xy 473.273298 -130.643888) (xy 473.435658 -130.543921) (xy 473.593628 -130.437152)
			(xy 473.746926 -130.323776) (xy 473.895273 -130.203995) (xy 474.038403 -130.078027) (xy 474.176057 -129.946097)
			(xy 474.307989 -129.808444) (xy 474.433959 -129.665316) (xy 474.553742 -129.51697) (xy 474.66712 -129.363674)
			(xy 474.77389 -129.205705) (xy 474.87386 -129.043346) (xy 474.966849 -128.876891) (xy 475.052689 -128.706639)
			(xy 475.131227 -128.532897) (xy 475.20232 -128.355979) (xy 475.26584 -128.176203) (xy 475.321673 -127.993893)
			(xy 475.369718 -127.809378) (xy 475.409889 -127.62299) (xy 475.442114 -127.435064) (xy 475.466333 -127.245941)
			(xy 475.482504 -127.05596) (xy 475.490597 -126.865464) (xy 475.491048 -126.77013) (xy 475.491048 -21.770086)
			(xy 475.490549 -21.674753) (xy 475.482456 -21.484258) (xy 475.466286 -21.294279) (xy 475.442067 -21.105157)
			(xy 475.409844 -20.917234) (xy 475.369674 -20.730847) (xy 475.321629 -20.546333) (xy 475.265797 -20.364024)
			(xy 475.202278 -20.18425) (xy 475.131186 -20.007333) (xy 475.05265 -19.833593) (xy 474.966811 -19.663342)
			(xy 474.873823 -19.496888) (xy 474.773855 -19.334531) (xy 474.667086 -19.176562) (xy 474.553708 -19.023267)
			(xy 474.433927 -18.874923) (xy 474.307958 -18.731795) (xy 474.176028 -18.594143) (xy 474.038375 -18.462215)
			(xy 473.895247 -18.336247) (xy 473.746901 -18.216467) (xy 473.593605 -18.103091) (xy 473.435636 -17.996324)
			(xy 473.273277 -17.896357) (xy 473.106823 -17.803371) (xy 472.936571 -17.717533) (xy 472.76283 -17.638998)
			(xy 472.585913 -17.567908) (xy 472.406138 -17.50439) (xy 472.223829 -17.44856) (xy 472.039314 -17.400517)
			(xy 471.852927 -17.360349) (xy 471.665003 -17.328127) (xy 471.475881 -17.30391) (xy 471.285902 -17.287741)
			(xy 471.095407 -17.27965) (xy 471.000074 -17.279112) (xy 444.999872 -17.279112) (xy 444.894339 -17.278602)
			(xy 444.683429 -17.27051) (xy 444.472984 -17.254345) (xy 444.263312 -17.230132) (xy 444.054721 -17.197906)
			(xy 443.847518 -17.157714) (xy 443.642006 -17.109616) (xy 443.438487 -17.053682) (xy 443.237259 -16.989994)
			(xy 443.038619 -16.918645) (xy 442.842857 -16.839741) (xy 442.650261 -16.753397) (xy 442.461113 -16.65974)
			(xy 442.275691 -16.558907) (xy 442.094267 -16.451046) (xy 441.917108 -16.336315) (xy 441.744473 -16.214883)
			(xy 441.576615 -16.086929) (xy 441.413781 -15.952639) (xy 441.25621 -15.812211) (xy 441.104134 -15.665851)
			(xy 440.957774 -15.513774) (xy 440.817347 -15.356202) (xy 440.683058 -15.193368) (xy 440.555104 -15.02551)
			(xy 440.433673 -14.852874) (xy 440.318943 -14.675714) (xy 440.211083 -14.49429) (xy 440.11025 -14.308867)
			(xy 440.016594 -14.119719) (xy 439.93025 -13.927123) (xy 439.851347 -13.73136) (xy 439.779999 -13.53272)
			(xy 439.716312 -13.331492) (xy 439.660379 -13.127973) (xy 439.612281 -12.922461) (xy 439.572091 -12.715257)
			(xy 439.539865 -12.506666) (xy 439.515653 -12.296994) (xy 439.499489 -12.086549) (xy 439.491397 -11.875639)
			(xy 439.490866 -11.770106) (xy 439.490866 -4.99999) (xy 439.49036 -4.904657) (xy 439.482267 -4.714162)
			(xy 439.466097 -4.524183) (xy 439.441879 -4.335061) (xy 439.409656 -4.147137) (xy 439.369486 -3.96075)
			(xy 439.321442 -3.776236) (xy 439.26561 -3.593927) (xy 439.202091 -3.414153) (xy 439.130999 -3.237235)
			(xy 439.052463 -3.063495) (xy 438.966624 -2.893244) (xy 438.873637 -2.72679) (xy 438.773669 -2.564432)
			(xy 438.6669 -2.406464) (xy 438.553523 -2.253169) (xy 438.433742 -2.104824) (xy 438.307774 -1.961696)
			(xy 438.175844 -1.824043) (xy 438.038191 -1.692114) (xy 437.895063 -1.566146) (xy 437.746717 -1.446366)
			(xy 437.593422 -1.33299) (xy 437.435453 -1.226222) (xy 437.273094 -1.126254) (xy 437.10664 -1.033267)
			(xy 436.936389 -0.947429) (xy 436.762648 -0.868894) (xy 436.585731 -0.797803) (xy 436.405955 -0.734284)
			(xy 436.223646 -0.678453) (xy 436.039132 -0.63041) (xy 435.852745 -0.590241) (xy 435.664821 -0.558018)
			(xy 435.475699 -0.533801) (xy 435.28572 -0.517631) (xy 435.095225 -0.50954) (xy 434.999892 -0.509016)
			(xy 4.99999 -0.509016) (xy 4.904657 -0.509522) (xy 4.714162 -0.517614) (xy 4.524182 -0.533784) (xy 4.335059 -0.558002)
			(xy 4.147135 -0.590225) (xy 3.960748 -0.630394) (xy 3.776233 -0.678438) (xy 3.593924 -0.73427) (xy 3.414149 -0.797788)
			(xy 3.237231 -0.86888) (xy 3.06349 -0.947415) (xy 2.893239 -1.033254) (xy 2.726784 -1.126242) (xy 2.564426 -1.22621)
			(xy 2.406456 -1.332978) (xy 2.253161 -1.446355) (xy 2.104815 -1.566136) (xy 1.961687 -1.692104) (xy 1.824034 -1.824034)
			(xy 1.692104 -1.961687) (xy 1.566136 -2.104815) (xy 1.446355 -2.253161) (xy 1.332978 -2.406456) (xy 1.22621 -2.564426)
			(xy 1.126242 -2.726784) (xy 1.033254 -2.893239) (xy 0.947415 -3.06349) (xy 0.86888 -3.237231) (xy 0.797788 -3.414149)
			(xy 0.73427 -3.593924) (xy 0.678438 -3.776233) (xy 0.646137 -3.900286) (xy 59.465106 -3.900286) (xy 59.471831 -3.783378)
			(xy 59.486516 -3.667201) (xy 59.509092 -3.552297) (xy 59.539454 -3.4392) (xy 59.577461 -3.328438)
			(xy 59.622935 -3.220527) (xy 59.675664 -3.115969) (xy 59.735404 -3.015253) (xy 59.801875 -2.918846)
			(xy 59.874768 -2.827198) (xy 59.953743 -2.740736) (xy 60.038433 -2.659864) (xy 60.128442 -2.584957)
			(xy 60.223352 -2.516365) (xy 60.32272 -2.454408) (xy 60.426083 -2.399373) (xy 60.532959 -2.351518)
			(xy 60.642851 -2.311065) (xy 60.755247 -2.278204) (xy 60.869623 -2.253086) (xy 60.985446 -2.23583)
			(xy 61.102176 -2.226514) (xy 61.219269 -2.225184) (xy 61.336181 -2.231845) (xy 61.452366 -2.246466)
			(xy 61.567283 -2.268978) (xy 61.680396 -2.299278) (xy 61.791179 -2.337224) (xy 61.899115 -2.382638)
			(xy 62.003702 -2.43531) (xy 62.104452 -2.494994) (xy 62.200895 -2.561413) (xy 62.292583 -2.634255)
			(xy 62.336172 -2.67335) (xy 62.343731 -2.679658) (xy 62.362196 -2.686443) (xy 62.381859 -2.68581)
			(xy 62.391036 -2.68224) (xy 62.476126 -2.644394) (xy 62.484905 -2.639997) (xy 62.498544 -2.625901)
			(xy 62.505902 -2.607719) (xy 62.506352 -2.597912) (xy 62.506352 -2.590038) (xy 62.506852 -2.540721)
			(xy 62.514857 -2.442413) (xy 62.530814 -2.345078) (xy 62.554617 -2.24936) (xy 62.58611 -2.155889)
			(xy 62.625084 -2.065282) (xy 62.671283 -1.978137) (xy 62.724402 -1.895029) (xy 62.784091 -1.816506)
			(xy 62.849955 -1.743086) (xy 62.92156 -1.675253) (xy 62.998434 -1.613455) (xy 63.08007 -1.5581) (xy 63.165929 -1.509552)
			(xy 63.255444 -1.468132) (xy 63.348026 -1.434114) (xy 63.443063 -1.407721) (xy 63.539928 -1.389129)
			(xy 63.637983 -1.378458) (xy 63.73658 -1.375781) (xy 63.83507 -1.381114) (xy 63.932801 -1.394422)
			(xy 64.029131 -1.415618) (xy 64.123422 -1.444561) (xy 64.215054 -1.481062) (xy 64.303421 -1.524878)
			(xy 64.38794 -1.575721) (xy 64.468055 -1.633256) (xy 64.543236 -1.697102) (xy 64.612988 -1.76684)
			(xy 64.67685 -1.842008) (xy 64.734401 -1.922111) (xy 64.785262 -2.00662) (xy 64.829096 -2.094978)
			(xy 64.865616 -2.186602) (xy 64.894579 -2.280887) (xy 64.915794 -2.377212) (xy 64.929123 -2.474941)
			(xy 64.934476 -2.57343) (xy 64.934028 -2.590038) (xy 65.045593 -2.590038) (xy 65.049633 -2.491055)
			(xy 65.061728 -2.392732) (xy 65.081798 -2.295721) (xy 65.109708 -2.200669) (xy 65.145272 -2.108208)
			(xy 65.188255 -2.018953) (xy 65.23837 -1.933499) (xy 65.295283 -1.852414) (xy 65.358616 -1.776238)
			(xy 65.427947 -1.705478) (xy 65.502816 -1.640604) (xy 65.582723 -1.582049) (xy 65.667137 -1.530201)
			(xy 65.755496 -1.485407) (xy 65.847212 -1.447964) (xy 65.941675 -1.418121) (xy 66.038256 -1.396077)
			(xy 66.136313 -1.381978) (xy 66.235193 -1.375919) (xy 66.334237 -1.37794) (xy 66.432787 -1.388027)
			(xy 66.530187 -1.406113) (xy 66.625789 -1.432078) (xy 66.718956 -1.46575) (xy 66.809069 -1.506903)
			(xy 66.895527 -1.555264) (xy 66.977756 -1.610511) (xy 67.055208 -1.672277) (xy 67.127368 -1.740151)
			(xy 67.193756 -1.81368) (xy 67.253929 -1.892376) (xy 67.307487 -1.975715) (xy 67.354075 -2.063142)
			(xy 67.393381 -2.154075) (xy 67.425145 -2.24791) (xy 67.449154 -2.344021) (xy 67.46525 -2.44177)
			(xy 67.473325 -2.540506) (xy 67.47383 -2.590038) (xy 67.473325 -2.63957) (xy 67.472584 -2.648633)
			(xy 74.704694 -2.648633) (xy 74.704694 -2.531443) (xy 74.712691 -2.414525) (xy 74.728649 -2.298426)
			(xy 74.752492 -2.183686) (xy 74.78411 -2.070841) (xy 74.823355 -1.960417) (xy 74.870043 -1.852928)
			(xy 74.923959 -1.748876) (xy 74.984849 -1.648746) (xy 75.052431 -1.553005) (xy 75.126389 -1.462099)
			(xy 75.206377 -1.376451) (xy 75.292025 -1.296463) (xy 75.382931 -1.222505) (xy 75.478672 -1.154923)
			(xy 75.578802 -1.094033) (xy 75.682854 -1.040117) (xy 75.790343 -0.993429) (xy 75.900767 -0.954184)
			(xy 76.013612 -0.922566) (xy 76.128352 -0.898723) (xy 76.244451 -0.882765) (xy 76.361369 -0.874768)
			(xy 76.478559 -0.874768) (xy 76.595477 -0.882765) (xy 76.711576 -0.898723) (xy 76.826316 -0.922566)
			(xy 76.939161 -0.954184) (xy 77.049585 -0.993429) (xy 77.157074 -1.040117) (xy 77.261126 -1.094033)
			(xy 77.361256 -1.154923) (xy 77.456997 -1.222505) (xy 77.547903 -1.296463) (xy 77.633551 -1.376451)
			(xy 77.713539 -1.462099) (xy 77.787497 -1.553005) (xy 77.855079 -1.648746) (xy 77.915969 -1.748876)
			(xy 77.969885 -1.852928) (xy 78.016573 -1.960417) (xy 78.055818 -2.070841) (xy 78.087436 -2.183686)
			(xy 78.111279 -2.298426) (xy 78.127237 -2.414525) (xy 78.135234 -2.531443) (xy 78.135734 -2.590038)
			(xy 78.135234 -2.648633) (xy 78.127237 -2.765551) (xy 78.111279 -2.88165) (xy 78.087436 -2.99639)
			(xy 78.055818 -3.109235) (xy 78.016573 -3.219659) (xy 77.969885 -3.327148) (xy 77.915969 -3.4312)
			(xy 77.855079 -3.53133) (xy 77.787497 -3.627071) (xy 77.713539 -3.717977) (xy 77.633551 -3.803625)
			(xy 77.547903 -3.883613) (xy 77.456997 -3.957571) (xy 77.361256 -4.025153) (xy 77.261126 -4.086043)
			(xy 77.157074 -4.139959) (xy 77.049585 -4.186647) (xy 76.939161 -4.225892) (xy 76.826316 -4.25751)
			(xy 76.711576 -4.281353) (xy 76.595477 -4.297311) (xy 76.478559 -4.305308) (xy 76.361369 -4.305308)
			(xy 76.244451 -4.297311) (xy 76.128352 -4.281353) (xy 76.013612 -4.25751) (xy 75.900767 -4.225892)
			(xy 75.790343 -4.186647) (xy 75.682854 -4.139959) (xy 75.578802 -4.086043) (xy 75.478672 -4.025153)
			(xy 75.382931 -3.957571) (xy 75.292025 -3.883613) (xy 75.206377 -3.803625) (xy 75.126389 -3.717977)
			(xy 75.052431 -3.627071) (xy 74.984849 -3.53133) (xy 74.923959 -3.4312) (xy 74.870043 -3.327148)
			(xy 74.823355 -3.219659) (xy 74.78411 -3.109235) (xy 74.752492 -2.99639) (xy 74.728649 -2.88165)
			(xy 74.712691 -2.765551) (xy 74.704694 -2.648633) (xy 67.472584 -2.648633) (xy 67.46525 -2.738306)
			(xy 67.449154 -2.836055) (xy 67.425145 -2.932166) (xy 67.393381 -3.026001) (xy 67.354075 -3.116934)
			(xy 67.307487 -3.204361) (xy 67.253929 -3.2877) (xy 67.193756 -3.366396) (xy 67.127368 -3.439925)
			(xy 67.055208 -3.507799) (xy 66.977756 -3.569565) (xy 66.895527 -3.624812) (xy 66.809069 -3.673173)
			(xy 66.718956 -3.714326) (xy 66.625789 -3.747998) (xy 66.530187 -3.773963) (xy 66.432787 -3.792049)
			(xy 66.334237 -3.802136) (xy 66.235193 -3.804157) (xy 66.136313 -3.798098) (xy 66.038256 -3.783999)
			(xy 65.941675 -3.761955) (xy 65.847212 -3.732112) (xy 65.755496 -3.694669) (xy 65.667137 -3.649875)
			(xy 65.582723 -3.598027) (xy 65.502816 -3.539472) (xy 65.427947 -3.474598) (xy 65.358616 -3.403838)
			(xy 65.295283 -3.327662) (xy 65.23837 -3.246577) (xy 65.188255 -3.161123) (xy 65.145272 -3.071868)
			(xy 65.109708 -2.979407) (xy 65.081798 -2.884355) (xy 65.061728 -2.787344) (xy 65.049633 -2.689021)
			(xy 65.045593 -2.590038) (xy 64.934028 -2.590038) (xy 64.931819 -2.672028) (xy 64.921169 -2.770085)
			(xy 64.902596 -2.866954) (xy 64.876223 -2.961996) (xy 64.842223 -3.054585) (xy 64.800822 -3.144109)
			(xy 64.752292 -3.229978) (xy 64.696954 -3.311625) (xy 64.635172 -3.388512) (xy 64.567354 -3.460131)
			(xy 64.493947 -3.52601) (xy 64.415436 -3.585715) (xy 64.332339 -3.638851) (xy 64.245203 -3.685068)
			(xy 64.154604 -3.724061) (xy 64.06114 -3.755573) (xy 63.965427 -3.779396) (xy 63.868095 -3.795372)
			(xy 63.769789 -3.803397) (xy 63.720472 -3.803904) (xy 63.719964 -3.803904) (xy 63.667939 -3.803349)
			(xy 63.564271 -3.794428) (xy 63.461748 -3.776665) (xy 63.361123 -3.750189) (xy 63.263133 -3.715195)
			(xy 63.1685 -3.67194) (xy 63.077917 -3.620741) (xy 63.034672 -3.591814) (xy 63.022226 -3.583178)
			(xy 62.992 -3.58267) (xy 62.887352 -3.647948) (xy 62.874652 -3.67538) (xy 62.876938 -3.690366) (xy 62.88499 -3.748362)
			(xy 62.894112 -3.865108) (xy 62.895249 -3.982203) (xy 62.888395 -4.099104) (xy 62.873582 -4.215265)
			(xy 62.85088 -4.330144) (xy 62.820393 -4.443207) (xy 62.782264 -4.553927) (xy 62.736672 -4.661788)
			(xy 62.683827 -4.766287) (xy 62.623976 -4.866938) (xy 62.557399 -4.963272) (xy 62.484405 -5.054839)
			(xy 62.405335 -5.141214) (xy 62.320556 -5.221993) (xy 62.230464 -5.296801) (xy 62.178873 -5.334)
			(xy 81.787492 -5.334) (xy 81.787492 -5.333492) (xy 81.788098 -5.28716) (xy 81.797769 -5.195002) (xy 81.816965 -5.104348)
			(xy 81.845477 -5.016179) (xy 81.863692 -4.973574) (xy 81.867498 -4.963632) (xy 81.867498 -4.942368)
			(xy 81.863692 -4.932426) (xy 81.845447 -4.889764) (xy 81.816903 -4.801471) (xy 81.79771 -4.710686)
			(xy 81.788077 -4.618396) (xy 81.787492 -4.572) (xy 81.788075 -4.525604) (xy 81.79772 -4.433316) (xy 81.816916 -4.342532)
			(xy 81.845454 -4.254239) (xy 81.863692 -4.211574) (xy 81.867498 -4.201632) (xy 81.867498 -4.180368)
			(xy 81.863692 -4.170426) (xy 81.84547 -4.127823) (xy 81.816952 -4.039656) (xy 81.79776 -3.949) (xy 81.7881 -3.85684)
			(xy 81.787492 -3.810508) (xy 81.787492 -3.81) (xy 81.787967 -3.768898) (xy 81.795552 -3.687043) (xy 81.810657 -3.606238)
			(xy 81.833153 -3.527171) (xy 81.862849 -3.450517) (xy 81.899491 -3.37693) (xy 81.942766 -3.307038)
			(xy 81.992306 -3.241437) (xy 82.047687 -3.180687) (xy 82.108437 -3.125306) (xy 82.174038 -3.075766)
			(xy 82.24393 -3.032491) (xy 82.317517 -2.995849) (xy 82.394171 -2.966153) (xy 82.473238 -2.943657)
			(xy 82.554043 -2.928552) (xy 82.635898 -2.920967) (xy 82.677 -2.920492) (xy 82.677508 -2.920492)
			(xy 82.72384 -2.921098) (xy 82.815998 -2.930769) (xy 82.906652 -2.949965) (xy 82.994821 -2.978477)
			(xy 83.037426 -2.996692) (xy 83.047368 -3.000498) (xy 83.068632 -3.000498) (xy 83.078574 -2.996692)
			(xy 83.121236 -2.978447) (xy 83.209529 -2.949903) (xy 83.300314 -2.93071) (xy 83.392604 -2.921077)
			(xy 83.439 -2.920492) (xy 83.485396 -2.921075) (xy 83.577684 -2.93072) (xy 83.668468 -2.949916) (xy 83.756761 -2.978454)
			(xy 83.799426 -2.996692) (xy 83.809368 -3.000498) (xy 83.830632 -3.000498) (xy 83.840574 -2.996692)
			(xy 83.883236 -2.978447) (xy 83.971529 -2.949903) (xy 84.062314 -2.93071) (xy 84.154604 -2.921077)
			(xy 84.201 -2.920492) (xy 84.247396 -2.921075) (xy 84.339684 -2.93072) (xy 84.430468 -2.949916) (xy 84.518761 -2.978454)
			(xy 84.561426 -2.996692) (xy 84.571368 -3.000498) (xy 84.592632 -3.000498) (xy 84.602574 -2.996692)
			(xy 84.645236 -2.978447) (xy 84.733529 -2.949903) (xy 84.824314 -2.93071) (xy 84.916604 -2.921077)
			(xy 84.963 -2.920492) (xy 85.009396 -2.921075) (xy 85.101684 -2.93072) (xy 85.192468 -2.949916) (xy 85.280761 -2.978454)
			(xy 85.323426 -2.996692) (xy 85.333368 -3.000498) (xy 85.354632 -3.000498) (xy 85.364574 -2.996692)
			(xy 85.407236 -2.978447) (xy 85.495529 -2.949903) (xy 85.586314 -2.93071) (xy 85.678604 -2.921077)
			(xy 85.725 -2.920492) (xy 85.771396 -2.921075) (xy 85.863684 -2.93072) (xy 85.954468 -2.949916) (xy 86.042761 -2.978454)
			(xy 86.085426 -2.996692) (xy 86.095368 -3.000498) (xy 86.116632 -3.000498) (xy 86.126574 -2.996692)
			(xy 86.169177 -2.97847) (xy 86.257344 -2.949952) (xy 86.348 -2.93076) (xy 86.44016 -2.9211) (xy 86.486492 -2.920492)
			(xy 86.487 -2.920492) (xy 86.528102 -2.920967) (xy 86.609957 -2.928552) (xy 86.690762 -2.943657)
			(xy 86.769829 -2.966153) (xy 86.846483 -2.995849) (xy 86.92007 -3.032491) (xy 86.989962 -3.075766)
			(xy 87.055563 -3.125306) (xy 87.116313 -3.180687) (xy 87.171694 -3.241437) (xy 87.221234 -3.307038)
			(xy 87.264509 -3.37693) (xy 87.301151 -3.450517) (xy 87.330847 -3.527171) (xy 87.353343 -3.606238)
			(xy 87.368448 -3.687043) (xy 87.376033 -3.768898) (xy 87.376508 -3.81) (xy 87.376508 -3.810508) (xy 87.375902 -3.85684)
			(xy 87.366231 -3.948998) (xy 87.347035 -4.039652) (xy 87.318523 -4.127821) (xy 87.300308 -4.170426)
			(xy 87.296502 -4.180368) (xy 87.296502 -4.201632) (xy 87.300308 -4.211574) (xy 87.318553 -4.254236)
			(xy 87.347097 -4.342529) (xy 87.36629 -4.433314) (xy 87.375923 -4.525604) (xy 87.376508 -4.572) (xy 87.375925 -4.618396)
			(xy 87.36628 -4.710684) (xy 87.347084 -4.801468) (xy 87.318546 -4.889761) (xy 87.300308 -4.932426)
			(xy 87.296502 -4.942368) (xy 87.296502 -4.963632) (xy 87.300308 -4.973574) (xy 87.31853 -5.016177)
			(xy 87.347048 -5.104344) (xy 87.36624 -5.195) (xy 87.3759 -5.28716) (xy 87.376508 -5.333492) (xy 87.376508 -5.334)
			(xy 87.376285 -5.353304) (xy 354.006912 -5.353304) (xy 354.006912 -5.352796) (xy 354.007518 -5.306464)
			(xy 354.017189 -5.214306) (xy 354.036385 -5.123652) (xy 354.064897 -5.035483) (xy 354.083112 -4.992878)
			(xy 354.086914 -4.982935) (xy 354.086915 -4.961672) (xy 354.083112 -4.95173) (xy 354.06487 -4.909067)
			(xy 354.036325 -4.820775) (xy 354.017131 -4.72999) (xy 354.007497 -4.6377) (xy 354.006912 -4.591304)
			(xy 354.007495 -4.544908) (xy 354.017139 -4.45262) (xy 354.036335 -4.361836) (xy 354.064874 -4.273543)
			(xy 354.083112 -4.230878) (xy 354.086914 -4.220935) (xy 354.086915 -4.199672) (xy 354.083112 -4.18973)
			(xy 354.064892 -4.147126) (xy 354.036374 -4.058959) (xy 354.01718 -3.968304) (xy 354.00752 -3.876144)
			(xy 354.006912 -3.829812) (xy 354.006912 -3.829304) (xy 354.007356 -3.7882) (xy 354.014941 -3.706344)
			(xy 354.030046 -3.625536) (xy 354.052543 -3.546467) (xy 354.08224 -3.469811) (xy 354.118884 -3.396222)
			(xy 354.162161 -3.326328) (xy 354.211702 -3.260725) (xy 354.267085 -3.199974) (xy 354.327838 -3.144592)
			(xy 354.393441 -3.095051) (xy 354.463336 -3.051776) (xy 354.536925 -3.015134) (xy 354.613582 -2.985438)
			(xy 354.692652 -2.962943) (xy 354.773459 -2.947839) (xy 354.855316 -2.940255) (xy 354.89642 -2.939796)
			(xy 354.896928 -2.939796) (xy 354.94326 -2.940395) (xy 355.035418 -2.950068) (xy 355.126072 -2.969266)
			(xy 355.214241 -2.99778) (xy 355.256846 -3.015996) (xy 355.266788 -3.019802) (xy 355.288052 -3.019802)
			(xy 355.297994 -3.015996) (xy 355.340654 -2.997745) (xy 355.428947 -2.969202) (xy 355.519733 -2.950011)
			(xy 355.612024 -2.94038) (xy 355.65842 -2.939796) (xy 355.704815 -2.940407) (xy 355.797102 -2.950044)
			(xy 355.887886 -2.969231) (xy 355.97618 -2.997762) (xy 356.018846 -3.015996) (xy 356.028788 -3.019802)
			(xy 356.050052 -3.019802) (xy 356.059994 -3.015996) (xy 356.102654 -2.997745) (xy 356.190947 -2.969202)
			(xy 356.281733 -2.950011) (xy 356.374024 -2.94038) (xy 356.42042 -2.939796) (xy 356.466815 -2.940407)
			(xy 356.559102 -2.950044) (xy 356.649886 -2.969231) (xy 356.73818 -2.997762) (xy 356.780846 -3.015996)
			(xy 356.790788 -3.019802) (xy 356.812052 -3.019802) (xy 356.821994 -3.015996) (xy 356.864654 -2.997745)
			(xy 356.952947 -2.969202) (xy 357.043733 -2.950011) (xy 357.136024 -2.94038) (xy 357.18242 -2.939796)
			(xy 357.228815 -2.940407) (xy 357.321102 -2.950044) (xy 357.411886 -2.969231) (xy 357.50018 -2.997762)
			(xy 357.542846 -3.015996) (xy 357.552788 -3.019802) (xy 357.574052 -3.019802) (xy 357.583994 -3.015996)
			(xy 357.626654 -2.997745) (xy 357.714947 -2.969202) (xy 357.805733 -2.950011) (xy 357.898024 -2.94038)
			(xy 357.94442 -2.939796) (xy 357.990815 -2.940407) (xy 358.083102 -2.950044) (xy 358.173886 -2.969231)
			(xy 358.26218 -2.997762) (xy 358.304846 -3.015996) (xy 358.314788 -3.019802) (xy 358.336052 -3.019802)
			(xy 358.345994 -3.015996) (xy 358.388594 -2.997768) (xy 358.476763 -2.969252) (xy 358.567419 -2.950061)
			(xy 358.65958 -2.940403) (xy 358.705912 -2.939796) (xy 358.70642 -2.939796) (xy 358.747523 -2.940248)
			(xy 358.829378 -2.947834) (xy 358.910184 -2.962941) (xy 358.989251 -2.985439) (xy 359.065905 -3.015137)
			(xy 359.139492 -3.051781) (xy 359.209385 -3.095058) (xy 359.274986 -3.144599) (xy 359.335736 -3.199981)
			(xy 359.391117 -3.260733) (xy 359.440656 -3.326335) (xy 359.483931 -3.396229) (xy 359.520573 -3.469817)
			(xy 359.550268 -3.546472) (xy 359.572764 -3.62554) (xy 359.587869 -3.706346) (xy 359.595454 -3.788201)
			(xy 359.595928 -3.829304) (xy 359.595928 -3.829812) (xy 359.595322 -3.876144) (xy 359.592786 -3.900309)
			(xy 361.865136 -3.900309) (xy 361.87186 -3.783404) (xy 361.886543 -3.667229) (xy 361.909117 -3.552327)
			(xy 361.939477 -3.439232) (xy 361.977481 -3.328472) (xy 362.022952 -3.220563) (xy 362.075679 -3.116006)
			(xy 362.135416 -3.015291) (xy 362.201884 -2.918885) (xy 362.274775 -2.827238) (xy 362.353747 -2.740777)
			(xy 362.438434 -2.659905) (xy 362.52844 -2.584998) (xy 362.623346 -2.516406) (xy 362.722711 -2.454448)
			(xy 362.826071 -2.399413) (xy 362.932945 -2.351557) (xy 363.042834 -2.311104) (xy 363.155227 -2.278241)
			(xy 363.269599 -2.253122) (xy 363.38542 -2.235864) (xy 363.502147 -2.226547) (xy 363.619238 -2.225214)
			(xy 363.736148 -2.231873) (xy 363.85233 -2.246491) (xy 363.967245 -2.269002) (xy 364.080357 -2.299299)
			(xy 364.191138 -2.337241) (xy 364.299073 -2.382653) (xy 364.403658 -2.435322) (xy 364.504407 -2.495003)
			(xy 364.60085 -2.561418) (xy 364.692537 -2.634257) (xy 364.736126 -2.67335) (xy 364.74371 -2.679623)
			(xy 364.762161 -2.686419) (xy 364.781815 -2.685801) (xy 364.79099 -2.68224) (xy 364.87608 -2.644394)
			(xy 364.88487 -2.640018) (xy 364.898503 -2.62591) (xy 364.905858 -2.607721) (xy 364.906306 -2.597912)
			(xy 364.906306 -2.597658) (xy 364.906052 -2.5908) (xy 364.906052 -2.589276) (xy 364.90662 -2.539112)
			(xy 364.914961 -2.439131) (xy 364.931528 -2.340179) (xy 364.956206 -2.242933) (xy 364.988828 -2.148056)
			(xy 365.02917 -2.056196) (xy 365.076958 -1.967979) (xy 365.131864 -1.884009) (xy 365.193515 -1.804857)
			(xy 365.261489 -1.731065) (xy 365.335323 -1.663135) (xy 365.414513 -1.601533) (xy 365.498517 -1.546678)
			(xy 365.586763 -1.498944) (xy 365.678648 -1.458658) (xy 365.773545 -1.426094) (xy 365.870806 -1.401475)
			(xy 365.969767 -1.384969) (xy 366.069754 -1.376689) (xy 366.119918 -1.376172) (xy 366.168816 -1.376589)
			(xy 366.266296 -1.38446) (xy 366.362826 -1.400149) (xy 366.457781 -1.423554) (xy 366.550544 -1.454524)
			(xy 366.640514 -1.492858) (xy 366.727109 -1.538308) (xy 366.809765 -1.590578) (xy 366.887947 -1.649329)
			(xy 366.961149 -1.714181) (xy 367.028894 -1.784712) (xy 367.090745 -1.860467) (xy 367.146299 -1.940952)
			(xy 367.195197 -2.025647) (xy 367.237122 -2.114001) (xy 367.271801 -2.205443) (xy 367.299009 -2.299379)
			(xy 367.318571 -2.395199) (xy 367.330359 -2.492283) (xy 367.334297 -2.59) (xy 367.334295 -2.590038)
			(xy 367.445547 -2.590038) (xy 367.449587 -2.491055) (xy 367.461682 -2.392732) (xy 367.481752 -2.295721)
			(xy 367.509662 -2.200669) (xy 367.545226 -2.108208) (xy 367.588209 -2.018953) (xy 367.638324 -1.933499)
			(xy 367.695237 -1.852414) (xy 367.75857 -1.776238) (xy 367.827901 -1.705478) (xy 367.90277 -1.640604)
			(xy 367.982677 -1.582049) (xy 368.067091 -1.530201) (xy 368.15545 -1.485407) (xy 368.247166 -1.447964)
			(xy 368.341629 -1.418121) (xy 368.43821 -1.396077) (xy 368.536267 -1.381978) (xy 368.635147 -1.375919)
			(xy 368.734191 -1.37794) (xy 368.832741 -1.388027) (xy 368.930141 -1.406113) (xy 369.025743 -1.432078)
			(xy 369.11891 -1.46575) (xy 369.209023 -1.506903) (xy 369.295481 -1.555264) (xy 369.37771 -1.610511)
			(xy 369.455162 -1.672277) (xy 369.527322 -1.740151) (xy 369.59371 -1.81368) (xy 369.653883 -1.892376)
			(xy 369.707441 -1.975715) (xy 369.754029 -2.063142) (xy 369.793335 -2.154075) (xy 369.825099 -2.24791)
			(xy 369.849108 -2.344021) (xy 369.865204 -2.44177) (xy 369.873279 -2.540506) (xy 369.873784 -2.590038)
			(xy 369.873279 -2.63957) (xy 369.872538 -2.648633) (xy 377.104648 -2.648633) (xy 377.104648 -2.531443)
			(xy 377.112645 -2.414525) (xy 377.128603 -2.298426) (xy 377.152446 -2.183686) (xy 377.184064 -2.070841)
			(xy 377.223309 -1.960417) (xy 377.269997 -1.852928) (xy 377.323913 -1.748876) (xy 377.384803 -1.648746)
			(xy 377.452385 -1.553005) (xy 377.526343 -1.462099) (xy 377.606331 -1.376451) (xy 377.691979 -1.296463)
			(xy 377.782885 -1.222505) (xy 377.878626 -1.154923) (xy 377.978756 -1.094033) (xy 378.082808 -1.040117)
			(xy 378.190297 -0.993429) (xy 378.300721 -0.954184) (xy 378.413566 -0.922566) (xy 378.528306 -0.898723)
			(xy 378.644405 -0.882765) (xy 378.761323 -0.874768) (xy 378.878513 -0.874768) (xy 378.995431 -0.882765)
			(xy 379.11153 -0.898723) (xy 379.22627 -0.922566) (xy 379.339115 -0.954184) (xy 379.449539 -0.993429)
			(xy 379.557028 -1.040117) (xy 379.66108 -1.094033) (xy 379.76121 -1.154923) (xy 379.856951 -1.222505)
			(xy 379.947857 -1.296463) (xy 380.033505 -1.376451) (xy 380.113493 -1.462099) (xy 380.187451 -1.553005)
			(xy 380.255033 -1.648746) (xy 380.315923 -1.748876) (xy 380.369839 -1.852928) (xy 380.416527 -1.960417)
			(xy 380.455772 -2.070841) (xy 380.48739 -2.183686) (xy 380.511233 -2.298426) (xy 380.527191 -2.414525)
			(xy 380.535188 -2.531443) (xy 380.535688 -2.590038) (xy 380.535188 -2.648633) (xy 380.527191 -2.765551)
			(xy 380.511233 -2.88165) (xy 380.48739 -2.99639) (xy 380.455772 -3.109235) (xy 380.416527 -3.219659)
			(xy 380.369839 -3.327148) (xy 380.315923 -3.4312) (xy 380.255033 -3.53133) (xy 380.187451 -3.627071)
			(xy 380.113493 -3.717977) (xy 380.033505 -3.803625) (xy 379.947857 -3.883613) (xy 379.856951 -3.957571)
			(xy 379.76121 -4.025153) (xy 379.66108 -4.086043) (xy 379.557028 -4.139959) (xy 379.449539 -4.186647)
			(xy 379.339115 -4.225892) (xy 379.22627 -4.25751) (xy 379.11153 -4.281353) (xy 378.995431 -4.297311)
			(xy 378.878513 -4.305308) (xy 378.761323 -4.305308) (xy 378.644405 -4.297311) (xy 378.528306 -4.281353)
			(xy 378.413566 -4.25751) (xy 378.300721 -4.225892) (xy 378.190297 -4.186647) (xy 378.082808 -4.139959)
			(xy 377.978756 -4.086043) (xy 377.878626 -4.025153) (xy 377.782885 -3.957571) (xy 377.691979 -3.883613)
			(xy 377.606331 -3.803625) (xy 377.526343 -3.717977) (xy 377.452385 -3.627071) (xy 377.384803 -3.53133)
			(xy 377.323913 -3.4312) (xy 377.269997 -3.327148) (xy 377.223309 -3.219659) (xy 377.184064 -3.109235)
			(xy 377.152446 -2.99639) (xy 377.128603 -2.88165) (xy 377.112645 -2.765551) (xy 377.104648 -2.648633)
			(xy 369.872538 -2.648633) (xy 369.865204 -2.738306) (xy 369.849108 -2.836055) (xy 369.825099 -2.932166)
			(xy 369.793335 -3.026001) (xy 369.754029 -3.116934) (xy 369.707441 -3.204361) (xy 369.653883 -3.2877)
			(xy 369.59371 -3.366396) (xy 369.527322 -3.439925) (xy 369.455162 -3.507799) (xy 369.37771 -3.569565)
			(xy 369.295481 -3.624812) (xy 369.209023 -3.673173) (xy 369.11891 -3.714326) (xy 369.025743 -3.747998)
			(xy 368.930141 -3.773963) (xy 368.832741 -3.792049) (xy 368.734191 -3.802136) (xy 368.635147 -3.804157)
			(xy 368.536267 -3.798098) (xy 368.43821 -3.783999) (xy 368.341629 -3.761955) (xy 368.247166 -3.732112)
			(xy 368.15545 -3.694669) (xy 368.067091 -3.649875) (xy 367.982677 -3.598027) (xy 367.90277 -3.539472)
			(xy 367.827901 -3.474598) (xy 367.75857 -3.403838) (xy 367.695237 -3.327662) (xy 367.638324 -3.246577)
			(xy 367.588209 -3.161123) (xy 367.545226 -3.071868) (xy 367.509662 -2.979407) (xy 367.481752 -2.884355)
			(xy 367.461682 -2.787344) (xy 367.449587 -2.689021) (xy 367.445547 -2.590038) (xy 367.334295 -2.590038)
			(xy 367.330359 -2.687717) (xy 367.318571 -2.784801) (xy 367.299009 -2.880621) (xy 367.271801 -2.974557)
			(xy 367.237122 -3.065999) (xy 367.195197 -3.154353) (xy 367.146299 -3.239048) (xy 367.090745 -3.319533)
			(xy 367.028894 -3.395288) (xy 366.961149 -3.465819) (xy 366.887947 -3.530671) (xy 366.809765 -3.589422)
			(xy 366.727109 -3.641692) (xy 366.640514 -3.687142) (xy 366.550544 -3.725476) (xy 366.457781 -3.756446)
			(xy 366.362826 -3.779851) (xy 366.266296 -3.79554) (xy 366.168816 -3.803411) (xy 366.119918 -3.803904)
			(xy 366.067892 -3.803373) (xy 365.964224 -3.794448) (xy 365.861701 -3.776681) (xy 365.761075 -3.750202)
			(xy 365.663086 -3.715204) (xy 365.568453 -3.671945) (xy 365.477871 -3.620743) (xy 365.434626 -3.591814)
			(xy 365.42218 -3.583178) (xy 365.391954 -3.58267) (xy 365.287306 -3.647948) (xy 365.274606 -3.67538)
			(xy 365.276892 -3.690366) (xy 365.284958 -3.748359) (xy 365.294081 -3.865102) (xy 365.295218 -3.982195)
			(xy 365.288365 -4.099093) (xy 365.273553 -4.215251) (xy 365.250851 -4.330129) (xy 365.220366 -4.44319)
			(xy 365.182239 -4.553907) (xy 365.136647 -4.661766) (xy 365.083804 -4.766264) (xy 365.023956 -4.866913)
			(xy 364.95738 -4.963245) (xy 364.884389 -5.054811) (xy 364.80532 -5.141184) (xy 364.720544 -5.221962)
			(xy 364.630454 -5.296769) (xy 364.535472 -5.365256) (xy 364.436038 -5.427103) (xy 364.332617 -5.482023)
			(xy 364.225691 -5.52976) (xy 364.115757 -5.570092) (xy 364.003327 -5.60283) (xy 363.888927 -5.627822)
			(xy 363.773088 -5.644952) (xy 363.65635 -5.654139) (xy 363.539257 -5.655341) (xy 363.422355 -5.648553)
			(xy 363.306189 -5.633805) (xy 363.191299 -5.611168) (xy 363.078221 -5.580745) (xy 362.967482 -5.542679)
			(xy 362.859598 -5.497148) (xy 362.755071 -5.444363) (xy 362.654389 -5.38457) (xy 362.55802 -5.318048)
			(xy 362.466413 -5.245107) (xy 362.379996 -5.166087) (xy 362.299171 -5.081355) (xy 362.224314 -4.991308)
			(xy 362.155775 -4.896363) (xy 362.093872 -4.796964) (xy 362.038895 -4.693573) (xy 361.991098 -4.586673)
			(xy 361.950706 -4.476762) (xy 361.917905 -4.36435) (xy 361.89285 -4.249964) (xy 361.875656 -4.134134)
			(xy 361.866404 -4.017401) (xy 361.865136 -3.900309) (xy 359.592786 -3.900309) (xy 359.58565 -3.968302)
			(xy 359.566455 -4.058956) (xy 359.537943 -4.147125) (xy 359.519728 -4.18973) (xy 359.515919 -4.199671)
			(xy 359.515921 -4.220936) (xy 359.519728 -4.230878) (xy 359.537975 -4.273539) (xy 359.566518 -4.361832)
			(xy 359.585711 -4.452617) (xy 359.595343 -4.544908) (xy 359.595928 -4.591304) (xy 359.595345 -4.6377)
			(xy 359.5857 -4.729988) (xy 359.566504 -4.820772) (xy 359.537966 -4.909065) (xy 359.519728 -4.95173)
			(xy 359.515919 -4.961671) (xy 359.515921 -4.982936) (xy 359.519728 -4.992878) (xy 359.537953 -5.03548)
			(xy 359.566469 -5.123648) (xy 359.585661 -5.214303) (xy 359.59532 -5.306464) (xy 359.595928 -5.352796)
			(xy 359.595928 -5.353304) (xy 359.595437 -5.394406) (xy 359.587852 -5.476259) (xy 359.572747 -5.557063)
			(xy 359.550251 -5.636129) (xy 359.520556 -5.712782) (xy 359.483914 -5.786368) (xy 359.44064 -5.85626)
			(xy 359.391101 -5.92186) (xy 359.335722 -5.98261) (xy 359.274973 -6.037991) (xy 359.209373 -6.087531)
			(xy 359.139482 -6.130807) (xy 359.065897 -6.167449) (xy 358.989245 -6.197146) (xy 358.910179 -6.219643)
			(xy 358.829375 -6.23475) (xy 358.747522 -6.242336) (xy 358.70642 -6.242812) (xy 358.705912 -6.242812)
			(xy 358.65958 -6.242199) (xy 358.567423 -6.232529) (xy 358.476769 -6.213336) (xy 358.3886 -6.184826)
			(xy 358.345994 -6.166612) (xy 358.336052 -6.162806) (xy 358.314788 -6.162806) (xy 358.304846 -6.166612)
			(xy 358.262181 -6.18485) (xy 358.17389 -6.213396) (xy 358.083106 -6.232591) (xy 357.990816 -6.242226)
			(xy 357.94442 -6.242812) (xy 357.898025 -6.242222) (xy 357.805736 -6.232579) (xy 357.714953 -6.213385)
			(xy 357.626659 -6.184849) (xy 357.583994 -6.166612) (xy 357.574052 -6.162806) (xy 357.552788 -6.162806)
			(xy 357.542846 -6.166612) (xy 357.500181 -6.18485) (xy 357.41189 -6.213396) (xy 357.321106 -6.232591)
			(xy 357.228816 -6.242226) (xy 357.18242 -6.242812) (xy 357.136025 -6.242222) (xy 357.043736 -6.232579)
			(xy 356.952953 -6.213385) (xy 356.864659 -6.184849) (xy 356.821994 -6.166612) (xy 356.812052 -6.162806)
			(xy 356.790788 -6.162806) (xy 356.780846 -6.166612) (xy 356.738181 -6.18485) (xy 356.64989 -6.213396)
			(xy 356.559106 -6.232591) (xy 356.466816 -6.242226) (xy 356.42042 -6.242812) (xy 356.374025 -6.242222)
			(xy 356.281736 -6.232579) (xy 356.190953 -6.213385) (xy 356.102659 -6.184849) (xy 356.059994 -6.166612)
			(xy 356.050052 -6.162806) (xy 356.028788 -6.162806) (xy 356.018846 -6.166612) (xy 355.976181 -6.18485)
			(xy 355.88789 -6.213396) (xy 355.797106 -6.232591) (xy 355.704816 -6.242226) (xy 355.65842 -6.242812)
			(xy 355.612025 -6.242222) (xy 355.519736 -6.232579) (xy 355.428953 -6.213385) (xy 355.340659 -6.184849)
			(xy 355.297994 -6.166612) (xy 355.288052 -6.162806) (xy 355.266788 -6.162806) (xy 355.256846 -6.166612)
			(xy 355.214241 -6.184828) (xy 355.126074 -6.213347) (xy 355.035419 -6.232541) (xy 354.94326 -6.242203)
			(xy 354.896928 -6.242812) (xy 354.89642 -6.242812) (xy 354.855317 -6.242329) (xy 354.773462 -6.234746)
			(xy 354.692656 -6.219642) (xy 354.613589 -6.197147) (xy 354.536934 -6.167452) (xy 354.463346 -6.130811)
			(xy 354.393453 -6.087537) (xy 354.327851 -6.037998) (xy 354.267099 -5.982618) (xy 354.211717 -5.921868)
			(xy 354.162177 -5.856267) (xy 354.1189 -5.786375) (xy 354.082257 -5.712788) (xy 354.052561 -5.636134)
			(xy 354.030063 -5.557067) (xy 354.014958 -5.476261) (xy 354.007372 -5.394407) (xy 354.006912 -5.353304)
			(xy 87.376285 -5.353304) (xy 87.376033 -5.375102) (xy 87.368448 -5.456957) (xy 87.353343 -5.537762)
			(xy 87.330847 -5.616829) (xy 87.301151 -5.693483) (xy 87.264509 -5.76707) (xy 87.221234 -5.836962)
			(xy 87.171694 -5.902563) (xy 87.116313 -5.963313) (xy 87.055563 -6.018694) (xy 86.989962 -6.068234)
			(xy 86.92007 -6.111509) (xy 86.846483 -6.148151) (xy 86.769829 -6.177847) (xy 86.690762 -6.200343)
			(xy 86.609957 -6.215448) (xy 86.528102 -6.223033) (xy 86.487 -6.223508) (xy 86.486492 -6.223508)
			(xy 86.44016 -6.222902) (xy 86.348002 -6.213231) (xy 86.257348 -6.194035) (xy 86.169179 -6.165523)
			(xy 86.126574 -6.147308) (xy 86.116632 -6.143502) (xy 86.095368 -6.143502) (xy 86.085426 -6.147308)
			(xy 86.042764 -6.165553) (xy 85.954471 -6.194097) (xy 85.863686 -6.21329) (xy 85.771396 -6.222923)
			(xy 85.725 -6.223508) (xy 85.678604 -6.222925) (xy 85.586316 -6.21328) (xy 85.495532 -6.194084) (xy 85.407239 -6.165546)
			(xy 85.364574 -6.147308) (xy 85.354632 -6.143502) (xy 85.333368 -6.143502) (xy 85.323426 -6.147308)
			(xy 85.280764 -6.165553) (xy 85.192471 -6.194097) (xy 85.101686 -6.21329) (xy 85.009396 -6.222923)
			(xy 84.963 -6.223508) (xy 84.916604 -6.222925) (xy 84.824316 -6.21328) (xy 84.733532 -6.194084) (xy 84.645239 -6.165546)
			(xy 84.602574 -6.147308) (xy 84.592632 -6.143502) (xy 84.571368 -6.143502) (xy 84.561426 -6.147308)
			(xy 84.518764 -6.165553) (xy 84.430471 -6.194097) (xy 84.339686 -6.21329) (xy 84.247396 -6.222923)
			(xy 84.201 -6.223508) (xy 84.154604 -6.222925) (xy 84.062316 -6.21328) (xy 83.971532 -6.194084) (xy 83.883239 -6.165546)
			(xy 83.840574 -6.147308) (xy 83.830632 -6.143502) (xy 83.809368 -6.143502) (xy 83.799426 -6.147308)
			(xy 83.756764 -6.165553) (xy 83.668471 -6.194097) (xy 83.577686 -6.21329) (xy 83.485396 -6.222923)
			(xy 83.439 -6.223508) (xy 83.392604 -6.222925) (xy 83.300316 -6.21328) (xy 83.209532 -6.194084) (xy 83.121239 -6.165546)
			(xy 83.078574 -6.147308) (xy 83.068632 -6.143502) (xy 83.047368 -6.143502) (xy 83.037426 -6.147308)
			(xy 82.994823 -6.16553) (xy 82.906656 -6.194048) (xy 82.816 -6.21324) (xy 82.72384 -6.2229) (xy 82.677508 -6.223508)
			(xy 82.677 -6.223508) (xy 82.635898 -6.223033) (xy 82.554043 -6.215448) (xy 82.473238 -6.200343)
			(xy 82.394171 -6.177847) (xy 82.317517 -6.148151) (xy 82.24393 -6.111509) (xy 82.174038 -6.068234)
			(xy 82.108437 -6.018694) (xy 82.047687 -5.963313) (xy 81.992306 -5.902563) (xy 81.942766 -5.836962)
			(xy 81.899491 -5.76707) (xy 81.862849 -5.693483) (xy 81.833153 -5.616829) (xy 81.810657 -5.537762)
			(xy 81.795552 -5.456957) (xy 81.787967 -5.375102) (xy 81.787492 -5.334) (xy 62.178873 -5.334) (xy 62.135479 -5.365288)
			(xy 62.036043 -5.427136) (xy 61.932619 -5.482057) (xy 61.82569 -5.529794) (xy 61.715754 -5.570126)
			(xy 61.603322 -5.602863) (xy 61.488918 -5.627855) (xy 61.373077 -5.644984) (xy 61.256336 -5.654171)
			(xy 61.139241 -5.655372) (xy 61.022337 -5.648582) (xy 60.906168 -5.633833) (xy 60.791276 -5.611194)
			(xy 60.678196 -5.58077) (xy 60.567455 -5.542702) (xy 60.459569 -5.497169) (xy 60.355041 -5.444382)
			(xy 60.254357 -5.384586) (xy 60.157987 -5.318062) (xy 60.066379 -5.245119) (xy 59.979961 -5.166096)
			(xy 59.899135 -5.081362) (xy 59.824278 -4.991311) (xy 59.755738 -4.896364) (xy 59.693835 -4.796962)
			(xy 59.638858 -4.693568) (xy 59.591062 -4.586666) (xy 59.55067 -4.476751) (xy 59.51787 -4.364337)
			(xy 59.492815 -4.249948) (xy 59.475623 -4.134116) (xy 59.466372 -4.01738) (xy 59.465106 -3.900286)
			(xy 0.646137 -3.900286) (xy 0.630394 -3.960748) (xy 0.590225 -4.147135) (xy 0.558002 -4.335059) (xy 0.533784 -4.524182)
			(xy 0.517614 -4.714162) (xy 0.509522 -4.904657) (xy 0.509016 -4.99999) (xy 0.509016 -17.272) (xy 111.565944 -17.272)
			(xy 111.565944 -17.271492) (xy 111.566546 -17.22516) (xy 111.576218 -17.133002) (xy 111.595414 -17.042348)
			(xy 111.623928 -16.954179) (xy 111.642144 -16.911574) (xy 111.645952 -16.901632) (xy 111.645952 -16.880368)
			(xy 111.642144 -16.870426) (xy 111.623902 -16.827762) (xy 111.595357 -16.739471) (xy 111.576163 -16.648686)
			(xy 111.566529 -16.556396) (xy 111.565944 -16.51) (xy 111.566522 -16.463604) (xy 111.576168 -16.371316)
			(xy 111.595365 -16.280532) (xy 111.623905 -16.192239) (xy 111.642144 -16.149574) (xy 111.645952 -16.139632)
			(xy 111.645952 -16.118368) (xy 111.642144 -16.108426) (xy 111.623902 -16.065762) (xy 111.595357 -15.977471)
			(xy 111.576163 -15.886686) (xy 111.566529 -15.794396) (xy 111.565944 -15.748) (xy 111.566522 -15.701604)
			(xy 111.576168 -15.609316) (xy 111.595365 -15.518532) (xy 111.623905 -15.430239) (xy 111.642144 -15.387574)
			(xy 111.645952 -15.377632) (xy 111.645952 -15.356368) (xy 111.642144 -15.346426) (xy 111.623902 -15.303762)
			(xy 111.595357 -15.215471) (xy 111.576163 -15.124686) (xy 111.566529 -15.032396) (xy 111.565944 -14.986)
			(xy 111.566522 -14.939604) (xy 111.576168 -14.847316) (xy 111.595365 -14.756532) (xy 111.623905 -14.668239)
			(xy 111.642144 -14.625574) (xy 111.645952 -14.615632) (xy 111.645952 -14.594368) (xy 111.642144 -14.584426)
			(xy 111.623919 -14.541824) (xy 111.595403 -14.453656) (xy 111.576211 -14.363) (xy 111.566552 -14.27084)
			(xy 111.565944 -14.224508) (xy 111.565944 -14.224) (xy 111.566467 -14.182899) (xy 111.574051 -14.101047)
			(xy 111.589155 -14.020245) (xy 111.61165 -13.94118) (xy 111.641344 -13.864529) (xy 111.677983 -13.790944)
			(xy 111.721256 -13.721053) (xy 111.770792 -13.655454) (xy 111.82617 -13.594704) (xy 111.886917 -13.539323)
			(xy 111.952514 -13.489783) (xy 112.022402 -13.446507) (xy 112.095985 -13.409863) (xy 112.172635 -13.380165)
			(xy 112.251698 -13.357666) (xy 112.3325 -13.342558) (xy 112.414351 -13.334969) (xy 112.455452 -13.334492)
			(xy 112.45596 -13.334492) (xy 112.502291 -13.335115) (xy 112.594449 -13.344781) (xy 112.685103 -13.363972)
			(xy 112.773272 -13.392479) (xy 112.815878 -13.410692) (xy 112.82582 -13.414498) (xy 112.847084 -13.414498)
			(xy 112.857026 -13.410692) (xy 112.899695 -13.392463) (xy 112.987985 -13.363915) (xy 113.078768 -13.344717)
			(xy 113.171056 -13.335079) (xy 113.217452 -13.334492) (xy 113.263847 -13.335092) (xy 113.356135 -13.344732)
			(xy 113.446919 -13.363923) (xy 113.535213 -13.392456) (xy 113.577878 -13.410692) (xy 113.58782 -13.414498)
			(xy 113.609084 -13.414498) (xy 113.619026 -13.410692) (xy 113.661695 -13.392463) (xy 113.749985 -13.363915)
			(xy 113.840768 -13.344717) (xy 113.933056 -13.335079) (xy 113.979452 -13.334492) (xy 114.025847 -13.335092)
			(xy 114.118135 -13.344732) (xy 114.208919 -13.363923) (xy 114.297213 -13.392456) (xy 114.339878 -13.410692)
			(xy 114.34982 -13.414498) (xy 114.371084 -13.414498) (xy 114.381026 -13.410692) (xy 114.423695 -13.392463)
			(xy 114.511985 -13.363915) (xy 114.602768 -13.344717) (xy 114.695056 -13.335079) (xy 114.741452 -13.334492)
			(xy 114.787847 -13.335092) (xy 114.880135 -13.344732) (xy 114.970919 -13.363923) (xy 115.059213 -13.392456)
			(xy 115.101878 -13.410692) (xy 115.11182 -13.414498) (xy 115.133084 -13.414498) (xy 115.143026 -13.410692)
			(xy 115.185635 -13.392486) (xy 115.2738 -13.363964) (xy 115.364454 -13.344767) (xy 115.456612 -13.335103)
			(xy 115.502944 -13.334492) (xy 115.503452 -13.334492) (xy 115.544554 -13.334998) (xy 115.626409 -13.342579)
			(xy 115.707215 -13.35768) (xy 115.786282 -13.380173) (xy 115.862937 -13.409865) (xy 115.936525 -13.446504)
			(xy 116.006418 -13.489777) (xy 116.072021 -13.539314) (xy 116.132772 -13.594694) (xy 116.188155 -13.655442)
			(xy 116.237696 -13.721042) (xy 116.280972 -13.790933) (xy 116.317615 -13.864519) (xy 116.347312 -13.941172)
			(xy 116.369809 -14.020239) (xy 116.384915 -14.101044) (xy 116.3925 -14.182898) (xy 116.39296 -14.224)
			(xy 116.39296 -14.224508) (xy 116.392358 -14.27084) (xy 116.382686 -14.362998) (xy 116.363489 -14.453652)
			(xy 116.334976 -14.541821) (xy 116.31676 -14.584426) (xy 116.312952 -14.594368) (xy 116.312952 -14.615632)
			(xy 116.31676 -14.625574) (xy 116.335002 -14.668237) (xy 116.363547 -14.756529) (xy 116.382741 -14.847314)
			(xy 116.392375 -14.939604) (xy 116.39296 -14.986) (xy 116.392381 -15.032396) (xy 116.382736 -15.124684)
			(xy 116.363539 -15.215468) (xy 116.334999 -15.303761) (xy 116.31676 -15.346426) (xy 116.312952 -15.356368)
			(xy 116.312952 -15.377632) (xy 116.31676 -15.387574) (xy 116.335002 -15.430237) (xy 116.363547 -15.518529)
			(xy 116.382741 -15.609314) (xy 116.392375 -15.701604) (xy 116.39296 -15.748) (xy 116.392381 -15.794396)
			(xy 116.382736 -15.886684) (xy 116.363539 -15.977468) (xy 116.334999 -16.065761) (xy 116.31676 -16.108426)
			(xy 116.312952 -16.118368) (xy 116.312952 -16.139632) (xy 116.31676 -16.149574) (xy 116.335002 -16.192237)
			(xy 116.363547 -16.280529) (xy 116.382741 -16.371314) (xy 116.392375 -16.463604) (xy 116.39296 -16.51)
			(xy 116.392381 -16.556396) (xy 116.382736 -16.648684) (xy 116.363539 -16.739468) (xy 116.334999 -16.827761)
			(xy 116.31676 -16.870426) (xy 116.312952 -16.880368) (xy 116.312952 -16.901632) (xy 116.31676 -16.911574)
			(xy 116.334985 -16.954176) (xy 116.363501 -17.042344) (xy 116.382693 -17.132999) (xy 116.392352 -17.22516)
			(xy 116.39296 -17.271492) (xy 116.39296 -17.272) (xy 116.392548 -17.313105) (xy 116.384962 -17.394963)
			(xy 116.369856 -17.475772) (xy 116.347357 -17.554843) (xy 116.317659 -17.6315) (xy 116.281014 -17.70509)
			(xy 116.237735 -17.774985) (xy 116.188192 -17.840588) (xy 116.132806 -17.90134) (xy 116.072051 -17.956722)
			(xy 116.006446 -18.006262) (xy 115.936548 -18.049538) (xy 115.862956 -18.086179) (xy 115.786297 -18.115873)
			(xy 115.707226 -18.138367) (xy 115.626415 -18.153469) (xy 115.544557 -18.16105) (xy 115.503452 -18.161508)
			(xy 115.502944 -18.161508) (xy 115.456613 -18.160884) (xy 115.364455 -18.151218) (xy 115.273801 -18.132027)
			(xy 115.185632 -18.103521) (xy 115.143026 -18.085308) (xy 115.133084 -18.081502) (xy 115.11182 -18.081502)
			(xy 115.101878 -18.085308) (xy 115.059209 -18.103536) (xy 114.970919 -18.132084) (xy 114.880136 -18.151282)
			(xy 114.787847 -18.16092) (xy 114.741452 -18.161508) (xy 114.695057 -18.160907) (xy 114.602769 -18.151267)
			(xy 114.511985 -18.132076) (xy 114.423691 -18.103543) (xy 114.381026 -18.085308) (xy 114.371084 -18.081502)
			(xy 114.34982 -18.081502) (xy 114.339878 -18.085308) (xy 114.297209 -18.103536) (xy 114.208919 -18.132084)
			(xy 114.118136 -18.151282) (xy 114.025847 -18.16092) (xy 113.979452 -18.161508) (xy 113.933057 -18.160907)
			(xy 113.840769 -18.151267) (xy 113.749985 -18.132076) (xy 113.661691 -18.103543) (xy 113.619026 -18.085308)
			(xy 113.609084 -18.081502) (xy 113.58782 -18.081502) (xy 113.577878 -18.085308) (xy 113.535209 -18.103536)
			(xy 113.446919 -18.132084) (xy 113.356136 -18.151282) (xy 113.263847 -18.16092) (xy 113.217452 -18.161508)
			(xy 113.171057 -18.160907) (xy 113.078769 -18.151267) (xy 112.987985 -18.132076) (xy 112.899691 -18.103543)
			(xy 112.857026 -18.085308) (xy 112.847084 -18.081502) (xy 112.82582 -18.081502) (xy 112.815878 -18.085308)
			(xy 112.773268 -18.103513) (xy 112.685103 -18.132035) (xy 112.59445 -18.151233) (xy 112.502292 -18.160897)
			(xy 112.45596 -18.161508) (xy 112.455452 -18.161508) (xy 112.414349 -18.161079) (xy 112.332493 -18.15349)
			(xy 112.251687 -18.138381) (xy 112.17262 -18.11588) (xy 112.095965 -18.086181) (xy 112.022379 -18.049535)
			(xy 111.952487 -18.006257) (xy 111.886886 -17.956714) (xy 111.826136 -17.90133) (xy 111.770755 -17.840577)
			(xy 111.721216 -17.774974) (xy 111.677941 -17.705079) (xy 111.6413 -17.631491) (xy 111.611604 -17.554835)
			(xy 111.589108 -17.475766) (xy 111.574003 -17.394959) (xy 111.566419 -17.313103) (xy 111.565944 -17.272)
			(xy 0.509016 -17.272) (xy 0.509016 -20.63857) (xy 56.730635 -20.63857) (xy 56.730635 -20.50943) (xy 56.738585 -20.380535)
			(xy 56.754455 -20.252375) (xy 56.778184 -20.125434) (xy 56.809683 -20.000195) (xy 56.848832 -19.877132)
			(xy 56.895483 -19.756713) (xy 56.949458 -19.639394) (xy 57.010553 -19.52562) (xy 57.078536 -19.415823)
			(xy 57.15315 -19.31042) (xy 57.234111 -19.20981) (xy 57.321111 -19.114375) (xy 57.413822 -19.024476)
			(xy 57.511892 -18.940455) (xy 57.614947 -18.862631) (xy 57.722598 -18.791299) (xy 57.834437 -18.726729)
			(xy 57.950038 -18.669167) (xy 58.068963 -18.61883) (xy 58.190762 -18.57591) (xy 58.314972 -18.540569)
			(xy 58.441121 -18.512942) (xy 58.568733 -18.493133) (xy 58.697322 -18.481217) (xy 58.8264 -18.477241)
			(xy 58.955478 -18.481217) (xy 59.084067 -18.493133) (xy 59.211679 -18.512942) (xy 59.337828 -18.540569)
			(xy 59.462038 -18.57591) (xy 59.583837 -18.61883) (xy 59.702762 -18.669167) (xy 59.818363 -18.726729)
			(xy 59.930202 -18.791299) (xy 60.037853 -18.862631) (xy 60.140908 -18.940455) (xy 60.238978 -19.024476)
			(xy 60.331689 -19.114375) (xy 60.418689 -19.20981) (xy 60.49965 -19.31042) (xy 60.574264 -19.415823)
			(xy 60.642247 -19.52562) (xy 60.703342 -19.639394) (xy 60.757317 -19.756713) (xy 60.803968 -19.877132)
			(xy 60.843117 -20.000195) (xy 60.874616 -20.125434) (xy 60.898345 -20.252375) (xy 60.914215 -20.380535)
			(xy 60.922165 -20.50943) (xy 60.922662 -20.574) (xy 60.922165 -20.63857) (xy 60.914215 -20.767465)
			(xy 60.898345 -20.895625) (xy 60.874616 -21.022566) (xy 60.843117 -21.147805) (xy 60.803968 -21.270868)
			(xy 60.757317 -21.391287) (xy 60.703342 -21.508606) (xy 60.642247 -21.62238) (xy 60.574264 -21.732177)
			(xy 60.49965 -21.83758) (xy 60.418689 -21.93819) (xy 60.331689 -22.033625) (xy 60.238978 -22.123524)
			(xy 60.140908 -22.207545) (xy 60.037853 -22.285369) (xy 59.988365 -22.318161) (xy 111.362994 -22.318161)
			(xy 111.362994 -22.233439) (xy 111.371047 -22.149102) (xy 111.387081 -22.065912) (xy 111.410949 -21.984622)
			(xy 111.442437 -21.90597) (xy 111.481259 -21.830667) (xy 111.527062 -21.759395) (xy 111.579433 -21.692799)
			(xy 111.637898 -21.631484) (xy 111.701926 -21.576003) (xy 111.770938 -21.52686) (xy 111.844308 -21.4845)
			(xy 111.921373 -21.449305) (xy 112.001435 -21.421596) (xy 112.083768 -21.401622) (xy 112.167627 -21.389565)
			(xy 112.252252 -21.385534) (xy 112.336877 -21.389565) (xy 112.420736 -21.401622) (xy 112.503069 -21.421596)
			(xy 112.583131 -21.449305) (xy 112.660196 -21.4845) (xy 112.733566 -21.52686) (xy 112.802578 -21.576003)
			(xy 112.866606 -21.631484) (xy 112.925071 -21.692799) (xy 112.977442 -21.759395) (xy 113.023245 -21.830667)
			(xy 113.062067 -21.90597) (xy 113.093555 -21.984622) (xy 113.117423 -22.065912) (xy 113.133457 -22.149102)
			(xy 113.14151 -22.233439) (xy 113.142014 -22.2758) (xy 113.14151 -22.318161) (xy 113.133457 -22.402498)
			(xy 113.117423 -22.485688) (xy 113.093555 -22.566978) (xy 113.062067 -22.64563) (xy 113.023245 -22.720933)
			(xy 112.977442 -22.792205) (xy 112.925071 -22.858801) (xy 112.866606 -22.920116) (xy 112.802578 -22.975597)
			(xy 112.733566 -23.02474) (xy 112.660196 -23.0671) (xy 112.583131 -23.102295) (xy 112.503069 -23.130004)
			(xy 112.420736 -23.149978) (xy 112.336877 -23.162035) (xy 112.252252 -23.166067) (xy 112.167627 -23.162035)
			(xy 112.083768 -23.149978) (xy 112.001435 -23.130004) (xy 111.921373 -23.102295) (xy 111.844308 -23.0671)
			(xy 111.770938 -23.02474) (xy 111.701926 -22.975597) (xy 111.637898 -22.920116) (xy 111.579433 -22.858801)
			(xy 111.527062 -22.792205) (xy 111.481259 -22.720933) (xy 111.442437 -22.64563) (xy 111.410949 -22.566978)
			(xy 111.387081 -22.485688) (xy 111.371047 -22.402498) (xy 111.362994 -22.318161) (xy 59.988365 -22.318161)
			(xy 59.930202 -22.356701) (xy 59.818363 -22.421271) (xy 59.702762 -22.478833) (xy 59.583837 -22.52917)
			(xy 59.462038 -22.57209) (xy 59.337828 -22.607431) (xy 59.211679 -22.635058) (xy 59.084067 -22.654867)
			(xy 58.955478 -22.666783) (xy 58.8264 -22.67076) (xy 58.697322 -22.666783) (xy 58.568733 -22.654867)
			(xy 58.441121 -22.635058) (xy 58.314972 -22.607431) (xy 58.190762 -22.57209) (xy 58.068963 -22.52917)
			(xy 57.950038 -22.478833) (xy 57.834437 -22.421271) (xy 57.722598 -22.356701) (xy 57.614947 -22.285369)
			(xy 57.511892 -22.207545) (xy 57.413822 -22.123524) (xy 57.321111 -22.033625) (xy 57.234111 -21.93819)
			(xy 57.15315 -21.83758) (xy 57.078536 -21.732177) (xy 57.010553 -21.62238) (xy 56.949458 -21.508606)
			(xy 56.895483 -21.391287) (xy 56.848832 -21.270868) (xy 56.809683 -21.147805) (xy 56.778184 -21.022566)
			(xy 56.754455 -20.895625) (xy 56.738585 -20.767465) (xy 56.730635 -20.63857) (xy 0.509016 -20.63857)
			(xy 0.509016 -28.5496) (xy 111.565944 -28.5496) (xy 111.565944 -28.549092) (xy 111.566546 -28.50276)
			(xy 111.576218 -28.410602) (xy 111.595414 -28.319948) (xy 111.623928 -28.231779) (xy 111.642144 -28.189174)
			(xy 111.645952 -28.179232) (xy 111.645952 -28.157968) (xy 111.642144 -28.148026) (xy 111.623902 -28.105362)
			(xy 111.595357 -28.017071) (xy 111.576163 -27.926286) (xy 111.566529 -27.833996) (xy 111.565944 -27.7876)
			(xy 111.566522 -27.741204) (xy 111.576168 -27.648916) (xy 111.595365 -27.558132) (xy 111.623905 -27.469839)
			(xy 111.642144 -27.427174) (xy 111.645952 -27.417232) (xy 111.645952 -27.395968) (xy 111.642144 -27.386026)
			(xy 111.623902 -27.343362) (xy 111.595357 -27.255071) (xy 111.576163 -27.164286) (xy 111.566529 -27.071996)
			(xy 111.565944 -27.0256) (xy 111.566522 -26.979204) (xy 111.576168 -26.886916) (xy 111.595365 -26.796132)
			(xy 111.623905 -26.707839) (xy 111.642144 -26.665174) (xy 111.645952 -26.655232) (xy 111.645952 -26.633968)
			(xy 111.642144 -26.624026) (xy 111.623902 -26.581362) (xy 111.595357 -26.493071) (xy 111.576163 -26.402286)
			(xy 111.566529 -26.309996) (xy 111.565944 -26.2636) (xy 111.566522 -26.217204) (xy 111.576168 -26.124916)
			(xy 111.595365 -26.034132) (xy 111.623905 -25.945839) (xy 111.642144 -25.903174) (xy 111.645952 -25.893232)
			(xy 111.645952 -25.871968) (xy 111.642144 -25.862026) (xy 111.623919 -25.819424) (xy 111.595403 -25.731256)
			(xy 111.576211 -25.6406) (xy 111.566552 -25.54844) (xy 111.565944 -25.502108) (xy 111.565944 -25.5016)
			(xy 111.566467 -25.460499) (xy 111.574051 -25.378647) (xy 111.589155 -25.297845) (xy 111.61165 -25.21878)
			(xy 111.641344 -25.142129) (xy 111.677983 -25.068544) (xy 111.721256 -24.998653) (xy 111.770792 -24.933054)
			(xy 111.82617 -24.872304) (xy 111.886917 -24.816923) (xy 111.952514 -24.767383) (xy 112.022402 -24.724107)
			(xy 112.095985 -24.687463) (xy 112.172635 -24.657765) (xy 112.251698 -24.635266) (xy 112.3325 -24.620158)
			(xy 112.414351 -24.612569) (xy 112.455452 -24.612092) (xy 112.45596 -24.612092) (xy 112.502291 -24.612715)
			(xy 112.594449 -24.622381) (xy 112.685103 -24.641572) (xy 112.773272 -24.670079) (xy 112.815878 -24.688292)
			(xy 112.82582 -24.692098) (xy 112.847084 -24.692098) (xy 112.857026 -24.688292) (xy 112.899695 -24.670063)
			(xy 112.987985 -24.641515) (xy 113.078768 -24.622317) (xy 113.171056 -24.612679) (xy 113.217452 -24.612092)
			(xy 113.263847 -24.612692) (xy 113.356135 -24.622332) (xy 113.446919 -24.641523) (xy 113.535213 -24.670056)
			(xy 113.577878 -24.688292) (xy 113.58782 -24.692098) (xy 113.609084 -24.692098) (xy 113.619026 -24.688292)
			(xy 113.661695 -24.670063) (xy 113.749985 -24.641515) (xy 113.840768 -24.622317) (xy 113.933056 -24.612679)
			(xy 113.979452 -24.612092) (xy 114.025847 -24.612692) (xy 114.118135 -24.622332) (xy 114.208919 -24.641523)
			(xy 114.297213 -24.670056) (xy 114.339878 -24.688292) (xy 114.34982 -24.692098) (xy 114.371084 -24.692098)
			(xy 114.381026 -24.688292) (xy 114.423695 -24.670063) (xy 114.511985 -24.641515) (xy 114.602768 -24.622317)
			(xy 114.695056 -24.612679) (xy 114.741452 -24.612092) (xy 114.787847 -24.612692) (xy 114.880135 -24.622332)
			(xy 114.970919 -24.641523) (xy 115.059213 -24.670056) (xy 115.101878 -24.688292) (xy 115.11182 -24.692098)
			(xy 115.133084 -24.692098) (xy 115.143026 -24.688292) (xy 115.185635 -24.670086) (xy 115.2738 -24.641564)
			(xy 115.364454 -24.622367) (xy 115.456612 -24.612703) (xy 115.502944 -24.612092) (xy 115.503452 -24.612092)
			(xy 115.544554 -24.612598) (xy 115.626409 -24.620179) (xy 115.707215 -24.63528) (xy 115.786282 -24.657773)
			(xy 115.862937 -24.687465) (xy 115.936525 -24.724104) (xy 116.006418 -24.767377) (xy 116.072021 -24.816914)
			(xy 116.132772 -24.872294) (xy 116.188155 -24.933042) (xy 116.237696 -24.998642) (xy 116.280972 -25.068533)
			(xy 116.317615 -25.142119) (xy 116.347312 -25.218772) (xy 116.369809 -25.297839) (xy 116.384915 -25.378644)
			(xy 116.3925 -25.460498) (xy 116.39296 -25.5016) (xy 116.39296 -25.502108) (xy 116.392358 -25.54844)
			(xy 116.382686 -25.640598) (xy 116.363489 -25.731252) (xy 116.334976 -25.819421) (xy 116.31676 -25.862026)
			(xy 116.312952 -25.871968) (xy 116.312952 -25.893232) (xy 116.31676 -25.903174) (xy 116.335002 -25.945837)
			(xy 116.363547 -26.034129) (xy 116.382741 -26.124914) (xy 116.392375 -26.217204) (xy 116.39296 -26.2636)
			(xy 116.392381 -26.309996) (xy 116.382736 -26.402284) (xy 116.363539 -26.493068) (xy 116.334999 -26.581361)
			(xy 116.31676 -26.624026) (xy 116.312952 -26.633968) (xy 116.312952 -26.655232) (xy 116.31676 -26.665174)
			(xy 116.335002 -26.707837) (xy 116.363547 -26.796129) (xy 116.382741 -26.886914) (xy 116.392375 -26.979204)
			(xy 116.39296 -27.0256) (xy 116.392381 -27.071996) (xy 116.382736 -27.164284) (xy 116.363539 -27.255068)
			(xy 116.334999 -27.343361) (xy 116.31676 -27.386026) (xy 116.312952 -27.395968) (xy 116.312952 -27.417232)
			(xy 116.31676 -27.427174) (xy 116.335002 -27.469837) (xy 116.363547 -27.558129) (xy 116.382741 -27.648914)
			(xy 116.392375 -27.741204) (xy 116.39296 -27.7876) (xy 116.392381 -27.833996) (xy 116.382736 -27.926284)
			(xy 116.363539 -28.017068) (xy 116.334999 -28.105361) (xy 116.31676 -28.148026) (xy 116.312952 -28.157968)
			(xy 116.312952 -28.179232) (xy 116.31676 -28.189174) (xy 116.334985 -28.231776) (xy 116.363501 -28.319944)
			(xy 116.382693 -28.410599) (xy 116.392352 -28.50276) (xy 116.39296 -28.549092) (xy 116.39296 -28.5496)
			(xy 116.392548 -28.590705) (xy 116.384962 -28.672563) (xy 116.369856 -28.753372) (xy 116.347357 -28.832443)
			(xy 116.317659 -28.9091) (xy 116.281014 -28.98269) (xy 116.237735 -29.052585) (xy 116.188192 -29.118188)
			(xy 116.132806 -29.17894) (xy 116.072051 -29.234322) (xy 116.006446 -29.283862) (xy 115.936548 -29.327138)
			(xy 115.862956 -29.363779) (xy 115.786297 -29.393473) (xy 115.707226 -29.415967) (xy 115.626415 -29.431069)
			(xy 115.544557 -29.43865) (xy 115.503452 -29.439108) (xy 115.502944 -29.439108) (xy 115.456613 -29.438484)
			(xy 115.364455 -29.428818) (xy 115.273801 -29.409627) (xy 115.185632 -29.381121) (xy 115.143026 -29.362908)
			(xy 115.133084 -29.359102) (xy 115.11182 -29.359102) (xy 115.101878 -29.362908) (xy 115.059209 -29.381136)
			(xy 114.970919 -29.409684) (xy 114.880136 -29.428882) (xy 114.787847 -29.43852) (xy 114.741452 -29.439108)
			(xy 114.695057 -29.438507) (xy 114.602769 -29.428867) (xy 114.511985 -29.409676) (xy 114.423691 -29.381143)
			(xy 114.381026 -29.362908) (xy 114.371084 -29.359102) (xy 114.34982 -29.359102) (xy 114.339878 -29.362908)
			(xy 114.297209 -29.381136) (xy 114.208919 -29.409684) (xy 114.118136 -29.428882) (xy 114.025847 -29.43852)
			(xy 113.979452 -29.439108) (xy 113.933057 -29.438507) (xy 113.840769 -29.428867) (xy 113.749985 -29.409676)
			(xy 113.661691 -29.381143) (xy 113.619026 -29.362908) (xy 113.609084 -29.359102) (xy 113.58782 -29.359102)
			(xy 113.577878 -29.362908) (xy 113.535209 -29.381136) (xy 113.446919 -29.409684) (xy 113.356136 -29.428882)
			(xy 113.263847 -29.43852) (xy 113.217452 -29.439108) (xy 113.171057 -29.438507) (xy 113.078769 -29.428867)
			(xy 112.987985 -29.409676) (xy 112.899691 -29.381143) (xy 112.857026 -29.362908) (xy 112.847084 -29.359102)
			(xy 112.82582 -29.359102) (xy 112.815878 -29.362908) (xy 112.773268 -29.381113) (xy 112.685103 -29.409635)
			(xy 112.59445 -29.428833) (xy 112.502292 -29.438497) (xy 112.45596 -29.439108) (xy 112.455452 -29.439108)
			(xy 112.414349 -29.438679) (xy 112.332493 -29.43109) (xy 112.251687 -29.415981) (xy 112.17262 -29.39348)
			(xy 112.095965 -29.363781) (xy 112.022379 -29.327135) (xy 111.952487 -29.283857) (xy 111.886886 -29.234314)
			(xy 111.826136 -29.17893) (xy 111.770755 -29.118177) (xy 111.721216 -29.052574) (xy 111.677941 -28.982679)
			(xy 111.6413 -28.909091) (xy 111.611604 -28.832435) (xy 111.589108 -28.753366) (xy 111.574003 -28.672559)
			(xy 111.566419 -28.590703) (xy 111.565944 -28.5496) (xy 0.509016 -28.5496) (xy 0.509016 -33.595761)
			(xy 111.362994 -33.595761) (xy 111.362994 -33.511039) (xy 111.371047 -33.426702) (xy 111.387081 -33.343512)
			(xy 111.410949 -33.262222) (xy 111.442437 -33.18357) (xy 111.481259 -33.108267) (xy 111.527062 -33.036995)
			(xy 111.579433 -32.970399) (xy 111.637898 -32.909084) (xy 111.701926 -32.853603) (xy 111.770938 -32.80446)
			(xy 111.844308 -32.7621) (xy 111.921373 -32.726905) (xy 112.001435 -32.699196) (xy 112.083768 -32.679222)
			(xy 112.167627 -32.667165) (xy 112.252252 -32.663134) (xy 112.336877 -32.667165) (xy 112.420736 -32.679222)
			(xy 112.503069 -32.699196) (xy 112.583131 -32.726905) (xy 112.660196 -32.7621) (xy 112.733566 -32.80446)
			(xy 112.802578 -32.853603) (xy 112.866606 -32.909084) (xy 112.925071 -32.970399) (xy 112.977442 -33.036995)
			(xy 113.023245 -33.108267) (xy 113.062067 -33.18357) (xy 113.093555 -33.262222) (xy 113.117423 -33.343512)
			(xy 113.133457 -33.426702) (xy 113.14151 -33.511039) (xy 113.142014 -33.5534) (xy 113.14151 -33.595761)
			(xy 113.133457 -33.680098) (xy 113.117423 -33.763288) (xy 113.093555 -33.844578) (xy 113.062067 -33.92323)
			(xy 113.023245 -33.998533) (xy 112.977442 -34.069805) (xy 112.925071 -34.136401) (xy 112.866606 -34.197716)
			(xy 112.802578 -34.253197) (xy 112.733566 -34.30234) (xy 112.660196 -34.3447) (xy 112.583131 -34.379895)
			(xy 112.503069 -34.407604) (xy 112.420736 -34.427578) (xy 112.336877 -34.439635) (xy 112.252252 -34.443667)
			(xy 112.167627 -34.439635) (xy 112.083768 -34.427578) (xy 112.001435 -34.407604) (xy 111.921373 -34.379895)
			(xy 111.844308 -34.3447) (xy 111.770938 -34.30234) (xy 111.701926 -34.253197) (xy 111.637898 -34.197716)
			(xy 111.579433 -34.136401) (xy 111.527062 -34.069805) (xy 111.481259 -33.998533) (xy 111.442437 -33.92323)
			(xy 111.410949 -33.844578) (xy 111.387081 -33.763288) (xy 111.371047 -33.680098) (xy 111.362994 -33.595761)
			(xy 0.509016 -33.595761) (xy 0.509016 -39.8272) (xy 111.565944 -39.8272) (xy 111.565944 -39.826692)
			(xy 111.566546 -39.78036) (xy 111.576218 -39.688202) (xy 111.595414 -39.597548) (xy 111.623928 -39.509379)
			(xy 111.642144 -39.466774) (xy 111.645952 -39.456832) (xy 111.645952 -39.435568) (xy 111.642144 -39.425626)
			(xy 111.623902 -39.382962) (xy 111.595357 -39.294671) (xy 111.576163 -39.203886) (xy 111.566529 -39.111596)
			(xy 111.565944 -39.0652) (xy 111.566522 -39.018804) (xy 111.576168 -38.926516) (xy 111.595365 -38.835732)
			(xy 111.623905 -38.747439) (xy 111.642144 -38.704774) (xy 111.645952 -38.694832) (xy 111.645952 -38.673568)
			(xy 111.642144 -38.663626) (xy 111.623902 -38.620962) (xy 111.595357 -38.532671) (xy 111.576163 -38.441886)
			(xy 111.566529 -38.349596) (xy 111.565944 -38.3032) (xy 111.566522 -38.256804) (xy 111.576168 -38.164516)
			(xy 111.595365 -38.073732) (xy 111.623905 -37.985439) (xy 111.642144 -37.942774) (xy 111.645952 -37.932832)
			(xy 111.645952 -37.911568) (xy 111.642144 -37.901626) (xy 111.623902 -37.858962) (xy 111.595357 -37.770671)
			(xy 111.576163 -37.679886) (xy 111.566529 -37.587596) (xy 111.565944 -37.5412) (xy 111.566522 -37.494804)
			(xy 111.576168 -37.402516) (xy 111.595365 -37.311732) (xy 111.623905 -37.223439) (xy 111.642144 -37.180774)
			(xy 111.645952 -37.170832) (xy 111.645952 -37.149568) (xy 111.642144 -37.139626) (xy 111.623919 -37.097024)
			(xy 111.595403 -37.008856) (xy 111.576211 -36.9182) (xy 111.566552 -36.82604) (xy 111.565944 -36.779708)
			(xy 111.565944 -36.7792) (xy 111.566467 -36.738099) (xy 111.574051 -36.656247) (xy 111.589155 -36.575445)
			(xy 111.61165 -36.49638) (xy 111.641344 -36.419729) (xy 111.677983 -36.346144) (xy 111.721256 -36.276253)
			(xy 111.770792 -36.210654) (xy 111.82617 -36.149904) (xy 111.886917 -36.094523) (xy 111.952514 -36.044983)
			(xy 112.022402 -36.001707) (xy 112.095985 -35.965063) (xy 112.172635 -35.935365) (xy 112.251698 -35.912866)
			(xy 112.3325 -35.897758) (xy 112.414351 -35.890169) (xy 112.455452 -35.889692) (xy 112.45596 -35.889692)
			(xy 112.502291 -35.890315) (xy 112.594449 -35.899981) (xy 112.685103 -35.919172) (xy 112.773272 -35.947679)
			(xy 112.815878 -35.965892) (xy 112.82582 -35.969698) (xy 112.847084 -35.969698) (xy 112.857026 -35.965892)
			(xy 112.899695 -35.947663) (xy 112.987985 -35.919115) (xy 113.078768 -35.899917) (xy 113.171056 -35.890279)
			(xy 113.217452 -35.889692) (xy 113.263847 -35.890292) (xy 113.356135 -35.899932) (xy 113.446919 -35.919123)
			(xy 113.535213 -35.947656) (xy 113.577878 -35.965892) (xy 113.58782 -35.969698) (xy 113.609084 -35.969698)
			(xy 113.619026 -35.965892) (xy 113.661695 -35.947663) (xy 113.749985 -35.919115) (xy 113.840768 -35.899917)
			(xy 113.933056 -35.890279) (xy 113.979452 -35.889692) (xy 114.025847 -35.890292) (xy 114.118135 -35.899932)
			(xy 114.208919 -35.919123) (xy 114.297213 -35.947656) (xy 114.339878 -35.965892) (xy 114.34982 -35.969698)
			(xy 114.371084 -35.969698) (xy 114.381026 -35.965892) (xy 114.423695 -35.947663) (xy 114.511985 -35.919115)
			(xy 114.602768 -35.899917) (xy 114.695056 -35.890279) (xy 114.741452 -35.889692) (xy 114.787847 -35.890292)
			(xy 114.880135 -35.899932) (xy 114.970919 -35.919123) (xy 115.059213 -35.947656) (xy 115.101878 -35.965892)
			(xy 115.11182 -35.969698) (xy 115.133084 -35.969698) (xy 115.143026 -35.965892) (xy 115.185635 -35.947686)
			(xy 115.2738 -35.919164) (xy 115.364454 -35.899967) (xy 115.456612 -35.890303) (xy 115.502944 -35.889692)
			(xy 115.503452 -35.889692) (xy 115.544554 -35.890198) (xy 115.626409 -35.897779) (xy 115.707215 -35.91288)
			(xy 115.786282 -35.935373) (xy 115.862937 -35.965065) (xy 115.936525 -36.001704) (xy 116.006418 -36.044977)
			(xy 116.072021 -36.094514) (xy 116.132772 -36.149894) (xy 116.188155 -36.210642) (xy 116.237696 -36.276242)
			(xy 116.280972 -36.346133) (xy 116.317615 -36.419719) (xy 116.347312 -36.496372) (xy 116.369809 -36.575439)
			(xy 116.384915 -36.656244) (xy 116.3925 -36.738098) (xy 116.39296 -36.7792) (xy 116.39296 -36.779708)
			(xy 116.392358 -36.82604) (xy 116.382686 -36.918198) (xy 116.363489 -37.008852) (xy 116.334976 -37.097021)
			(xy 116.31676 -37.139626) (xy 116.312952 -37.149568) (xy 116.312952 -37.170832) (xy 116.31676 -37.180774)
			(xy 116.335002 -37.223437) (xy 116.363547 -37.311729) (xy 116.382741 -37.402514) (xy 116.392375 -37.494804)
			(xy 116.39296 -37.5412) (xy 116.392381 -37.587596) (xy 116.382736 -37.679884) (xy 116.363539 -37.770668)
			(xy 116.334999 -37.858961) (xy 116.31676 -37.901626) (xy 116.312952 -37.911568) (xy 116.312952 -37.932832)
			(xy 116.31676 -37.942774) (xy 116.335002 -37.985437) (xy 116.363547 -38.073729) (xy 116.382741 -38.164514)
			(xy 116.392375 -38.256804) (xy 116.39296 -38.3032) (xy 116.392381 -38.349596) (xy 116.382736 -38.441884)
			(xy 116.363539 -38.532668) (xy 116.334999 -38.620961) (xy 116.31676 -38.663626) (xy 116.312952 -38.673568)
			(xy 116.312952 -38.694832) (xy 116.31676 -38.704774) (xy 116.335002 -38.747437) (xy 116.363547 -38.835729)
			(xy 116.382741 -38.926514) (xy 116.392375 -39.018804) (xy 116.39296 -39.0652) (xy 116.392381 -39.111596)
			(xy 116.382736 -39.203884) (xy 116.363539 -39.294668) (xy 116.334999 -39.382961) (xy 116.31676 -39.425626)
			(xy 116.312952 -39.435568) (xy 116.312952 -39.456832) (xy 116.31676 -39.466774) (xy 116.334985 -39.509376)
			(xy 116.363501 -39.597544) (xy 116.382693 -39.688199) (xy 116.392352 -39.78036) (xy 116.39296 -39.826692)
			(xy 116.39296 -39.8272) (xy 116.392548 -39.868305) (xy 116.384962 -39.950163) (xy 116.369856 -40.030972)
			(xy 116.347357 -40.110043) (xy 116.317659 -40.1867) (xy 116.281014 -40.26029) (xy 116.237735 -40.330185)
			(xy 116.188192 -40.395788) (xy 116.132806 -40.45654) (xy 116.072051 -40.511922) (xy 116.006446 -40.561462)
			(xy 115.936548 -40.604738) (xy 115.862956 -40.641379) (xy 115.786297 -40.671073) (xy 115.707226 -40.693567)
			(xy 115.626415 -40.708669) (xy 115.544557 -40.71625) (xy 115.503452 -40.716708) (xy 115.502944 -40.716708)
			(xy 115.456613 -40.716084) (xy 115.364455 -40.706418) (xy 115.273801 -40.687227) (xy 115.185632 -40.658721)
			(xy 115.143026 -40.640508) (xy 115.133084 -40.636702) (xy 115.11182 -40.636702) (xy 115.101878 -40.640508)
			(xy 115.059209 -40.658736) (xy 114.970919 -40.687284) (xy 114.880136 -40.706482) (xy 114.787847 -40.71612)
			(xy 114.741452 -40.716708) (xy 114.695057 -40.716107) (xy 114.602769 -40.706467) (xy 114.511985 -40.687276)
			(xy 114.423691 -40.658743) (xy 114.381026 -40.640508) (xy 114.371084 -40.636702) (xy 114.34982 -40.636702)
			(xy 114.339878 -40.640508) (xy 114.297209 -40.658736) (xy 114.208919 -40.687284) (xy 114.118136 -40.706482)
			(xy 114.025847 -40.71612) (xy 113.979452 -40.716708) (xy 113.933057 -40.716107) (xy 113.840769 -40.706467)
			(xy 113.749985 -40.687276) (xy 113.661691 -40.658743) (xy 113.619026 -40.640508) (xy 113.609084 -40.636702)
			(xy 113.58782 -40.636702) (xy 113.577878 -40.640508) (xy 113.535209 -40.658736) (xy 113.446919 -40.687284)
			(xy 113.356136 -40.706482) (xy 113.263847 -40.71612) (xy 113.217452 -40.716708) (xy 113.171057 -40.716107)
			(xy 113.078769 -40.706467) (xy 112.987985 -40.687276) (xy 112.899691 -40.658743) (xy 112.857026 -40.640508)
			(xy 112.847084 -40.636702) (xy 112.82582 -40.636702) (xy 112.815878 -40.640508) (xy 112.773268 -40.658713)
			(xy 112.685103 -40.687235) (xy 112.59445 -40.706433) (xy 112.502292 -40.716097) (xy 112.45596 -40.716708)
			(xy 112.455452 -40.716708) (xy 112.414349 -40.716279) (xy 112.332493 -40.70869) (xy 112.251687 -40.693581)
			(xy 112.17262 -40.67108) (xy 112.095965 -40.641381) (xy 112.022379 -40.604735) (xy 111.952487 -40.561457)
			(xy 111.886886 -40.511914) (xy 111.826136 -40.45653) (xy 111.770755 -40.395777) (xy 111.721216 -40.330174)
			(xy 111.677941 -40.260279) (xy 111.6413 -40.186691) (xy 111.611604 -40.110035) (xy 111.589108 -40.030966)
			(xy 111.574003 -39.950159) (xy 111.566419 -39.868303) (xy 111.565944 -39.8272) (xy 0.509016 -39.8272)
			(xy 0.509016 -42.474585) (xy 107.8931 -42.474585) (xy 107.8931 -42.389863) (xy 107.901153 -42.305526)
			(xy 107.917187 -42.222336) (xy 107.941055 -42.141046) (xy 107.972543 -42.062394) (xy 108.011365 -41.987091)
			(xy 108.057168 -41.915819) (xy 108.109539 -41.849223) (xy 108.168004 -41.787908) (xy 108.232032 -41.732427)
			(xy 108.301044 -41.683284) (xy 108.374414 -41.640924) (xy 108.451479 -41.605729) (xy 108.531541 -41.57802)
			(xy 108.613874 -41.558046) (xy 108.697733 -41.545989) (xy 108.782358 -41.541958) (xy 108.866983 -41.545989)
			(xy 108.950842 -41.558046) (xy 109.033175 -41.57802) (xy 109.113237 -41.605729) (xy 109.190302 -41.640924)
			(xy 109.263672 -41.683284) (xy 109.332684 -41.732427) (xy 109.396712 -41.787908) (xy 109.455177 -41.849223)
			(xy 109.507548 -41.915819) (xy 109.553351 -41.987091) (xy 109.592173 -42.062394) (xy 109.623661 -42.141046)
			(xy 109.647529 -42.222336) (xy 109.663563 -42.305526) (xy 109.671616 -42.389863) (xy 109.67212 -42.432224)
			(xy 109.671616 -42.474585) (xy 109.663563 -42.558922) (xy 109.647529 -42.642112) (xy 109.623661 -42.723402)
			(xy 109.592173 -42.802054) (xy 109.553351 -42.877357) (xy 109.507548 -42.948629) (xy 109.455177 -43.015225)
			(xy 109.396712 -43.07654) (xy 109.332684 -43.132021) (xy 109.263672 -43.181164) (xy 109.192316 -43.222361)
			(xy 110.388142 -43.222361) (xy 110.388142 -43.137639) (xy 110.396195 -43.053302) (xy 110.412229 -42.970112)
			(xy 110.436097 -42.888822) (xy 110.467585 -42.81017) (xy 110.506407 -42.734867) (xy 110.55221 -42.663595)
			(xy 110.604581 -42.596999) (xy 110.663046 -42.535684) (xy 110.727074 -42.480203) (xy 110.796086 -42.43106)
			(xy 110.869456 -42.3887) (xy 110.946521 -42.353505) (xy 111.026583 -42.325796) (xy 111.108916 -42.305822)
			(xy 111.192775 -42.293765) (xy 111.2774 -42.289734) (xy 111.362025 -42.293765) (xy 111.445884 -42.305822)
			(xy 111.528217 -42.325796) (xy 111.608279 -42.353505) (xy 111.685344 -42.3887) (xy 111.758714 -42.43106)
			(xy 111.827726 -42.480203) (xy 111.891754 -42.535684) (xy 111.950219 -42.596999) (xy 112.00259 -42.663595)
			(xy 112.048393 -42.734867) (xy 112.087215 -42.81017) (xy 112.118703 -42.888822) (xy 112.142571 -42.970112)
			(xy 112.158605 -43.053302) (xy 112.166658 -43.137639) (xy 112.167162 -43.18) (xy 112.166658 -43.222361)
			(xy 112.158605 -43.306698) (xy 112.142571 -43.389888) (xy 112.118703 -43.471178) (xy 112.087215 -43.54983)
			(xy 112.048393 -43.625133) (xy 112.00259 -43.696405) (xy 111.950219 -43.763001) (xy 111.891754 -43.824316)
			(xy 111.827726 -43.879797) (xy 111.758714 -43.92894) (xy 111.685344 -43.9713) (xy 111.608279 -44.006495)
			(xy 111.528217 -44.034204) (xy 111.445884 -44.054178) (xy 111.362025 -44.066235) (xy 111.2774 -44.070267)
			(xy 111.192775 -44.066235) (xy 111.108916 -44.054178) (xy 111.026583 -44.034204) (xy 110.946521 -44.006495)
			(xy 110.869456 -43.9713) (xy 110.796086 -43.92894) (xy 110.727074 -43.879797) (xy 110.663046 -43.824316)
			(xy 110.604581 -43.763001) (xy 110.55221 -43.696405) (xy 110.506407 -43.625133) (xy 110.467585 -43.54983)
			(xy 110.436097 -43.471178) (xy 110.412229 -43.389888) (xy 110.396195 -43.306698) (xy 110.388142 -43.222361)
			(xy 109.192316 -43.222361) (xy 109.190302 -43.223524) (xy 109.113237 -43.258719) (xy 109.033175 -43.286428)
			(xy 108.950842 -43.306402) (xy 108.866983 -43.318459) (xy 108.782358 -43.322491) (xy 108.697733 -43.318459)
			(xy 108.613874 -43.306402) (xy 108.531541 -43.286428) (xy 108.451479 -43.258719) (xy 108.374414 -43.223524)
			(xy 108.301044 -43.181164) (xy 108.232032 -43.132021) (xy 108.168004 -43.07654) (xy 108.109539 -43.015225)
			(xy 108.057168 -42.948629) (xy 108.011365 -42.877357) (xy 107.972543 -42.802054) (xy 107.941055 -42.723402)
			(xy 107.917187 -42.642112) (xy 107.901153 -42.558922) (xy 107.8931 -42.474585) (xy 0.509016 -42.474585)
			(xy 0.509016 -44.873361) (xy 111.362994 -44.873361) (xy 111.362994 -44.788639) (xy 111.371047 -44.704302)
			(xy 111.387081 -44.621112) (xy 111.410949 -44.539822) (xy 111.442437 -44.46117) (xy 111.481259 -44.385867)
			(xy 111.527062 -44.314595) (xy 111.579433 -44.247999) (xy 111.637898 -44.186684) (xy 111.701926 -44.131203)
			(xy 111.770938 -44.08206) (xy 111.844308 -44.0397) (xy 111.921373 -44.004505) (xy 112.001435 -43.976796)
			(xy 112.083768 -43.956822) (xy 112.167627 -43.944765) (xy 112.252252 -43.940734) (xy 112.336877 -43.944765)
			(xy 112.420736 -43.956822) (xy 112.503069 -43.976796) (xy 112.583131 -44.004505) (xy 112.660196 -44.0397)
			(xy 112.733566 -44.08206) (xy 112.802578 -44.131203) (xy 112.866606 -44.186684) (xy 112.925071 -44.247999)
			(xy 112.977442 -44.314595) (xy 113.023245 -44.385867) (xy 113.062067 -44.46117) (xy 113.093555 -44.539822)
			(xy 113.117423 -44.621112) (xy 113.133457 -44.704302) (xy 113.14151 -44.788639) (xy 113.142014 -44.831)
			(xy 113.14151 -44.873361) (xy 113.133457 -44.957698) (xy 113.117423 -45.040888) (xy 113.093555 -45.122178)
			(xy 113.062067 -45.20083) (xy 113.023245 -45.276133) (xy 112.977442 -45.347405) (xy 112.925071 -45.414001)
			(xy 112.866606 -45.475316) (xy 112.802578 -45.530797) (xy 112.733566 -45.57994) (xy 112.660196 -45.6223)
			(xy 112.583131 -45.657495) (xy 112.503069 -45.685204) (xy 112.420736 -45.705178) (xy 112.336877 -45.717235)
			(xy 112.252252 -45.721267) (xy 112.167627 -45.717235) (xy 112.083768 -45.705178) (xy 112.001435 -45.685204)
			(xy 111.921373 -45.657495) (xy 111.844308 -45.6223) (xy 111.770938 -45.57994) (xy 111.701926 -45.530797)
			(xy 111.637898 -45.475316) (xy 111.579433 -45.414001) (xy 111.527062 -45.347405) (xy 111.481259 -45.276133)
			(xy 111.442437 -45.20083) (xy 111.410949 -45.122178) (xy 111.387081 -45.040888) (xy 111.371047 -44.957698)
			(xy 111.362994 -44.873361) (xy 0.509016 -44.873361) (xy 0.509016 -50.919888) (xy 41.345622 -50.919888)
			(xy 41.349604 -50.829938) (xy 41.361521 -50.740691) (xy 41.381279 -50.652847) (xy 41.408723 -50.567093)
			(xy 41.443639 -50.4841) (xy 41.485753 -50.404518) (xy 41.534736 -50.328969) (xy 41.590204 -50.258045)
			(xy 41.651724 -50.1923) (xy 41.718813 -50.13225) (xy 41.790947 -50.078365) (xy 41.867561 -50.031065)
			(xy 41.948055 -49.990722) (xy 42.0318 -49.95765) (xy 42.118141 -49.93211) (xy 42.2064 -49.9143) (xy 42.295889 -49.90436)
			(xy 42.385905 -49.902369) (xy 42.475746 -49.90834) (xy 42.564707 -49.922229) (xy 42.652092 -49.943925)
			(xy 42.737218 -49.97326) (xy 42.819418 -50.010003) (xy 42.898049 -50.053867) (xy 42.972496 -50.104509)
			(xy 43.042176 -50.161533) (xy 43.106543 -50.224492) (xy 43.165094 -50.292893) (xy 43.217371 -50.366201)
			(xy 43.262964 -50.443843) (xy 43.301517 -50.52521) (xy 43.332728 -50.609666) (xy 43.356352 -50.69655)
			(xy 43.372205 -50.785182) (xy 43.380162 -50.874869) (xy 43.38066 -50.919888) (xy 60.903622 -50.919888)
			(xy 60.907604 -50.829938) (xy 60.919521 -50.740691) (xy 60.939279 -50.652847) (xy 60.966723 -50.567093)
			(xy 61.001639 -50.4841) (xy 61.043753 -50.404518) (xy 61.092736 -50.328969) (xy 61.148204 -50.258045)
			(xy 61.209724 -50.1923) (xy 61.276813 -50.13225) (xy 61.348947 -50.078365) (xy 61.425561 -50.031065)
			(xy 61.506055 -49.990722) (xy 61.5898 -49.95765) (xy 61.676141 -49.93211) (xy 61.7644 -49.9143) (xy 61.853889 -49.90436)
			(xy 61.943905 -49.902369) (xy 62.033746 -49.90834) (xy 62.122707 -49.922229) (xy 62.210092 -49.943925)
			(xy 62.295218 -49.97326) (xy 62.377418 -50.010003) (xy 62.456049 -50.053867) (xy 62.530496 -50.104509)
			(xy 62.600176 -50.161533) (xy 62.664543 -50.224492) (xy 62.723094 -50.292893) (xy 62.775371 -50.366201)
			(xy 62.820964 -50.443843) (xy 62.859517 -50.52521) (xy 62.890728 -50.609666) (xy 62.914352 -50.69655)
			(xy 62.930205 -50.785182) (xy 62.938162 -50.874869) (xy 62.93866 -50.919888) (xy 62.938162 -50.964907)
			(xy 62.930205 -51.054594) (xy 62.921225 -51.1048) (xy 111.565944 -51.1048) (xy 111.565944 -51.104292)
			(xy 111.566546 -51.05796) (xy 111.576218 -50.965802) (xy 111.595414 -50.875148) (xy 111.623928 -50.786979)
			(xy 111.642144 -50.744374) (xy 111.645952 -50.734432) (xy 111.645952 -50.713168) (xy 111.642144 -50.703226)
			(xy 111.623902 -50.660562) (xy 111.595357 -50.572271) (xy 111.576163 -50.481486) (xy 111.566529 -50.389196)
			(xy 111.565944 -50.3428) (xy 111.566522 -50.296404) (xy 111.576168 -50.204116) (xy 111.595365 -50.113332)
			(xy 111.623905 -50.025039) (xy 111.642144 -49.982374) (xy 111.645952 -49.972432) (xy 111.645952 -49.951168)
			(xy 111.642144 -49.941226) (xy 111.623902 -49.898562) (xy 111.595357 -49.810271) (xy 111.576163 -49.719486)
			(xy 111.566529 -49.627196) (xy 111.565944 -49.5808) (xy 111.566522 -49.534404) (xy 111.576168 -49.442116)
			(xy 111.595365 -49.351332) (xy 111.623905 -49.263039) (xy 111.642144 -49.220374) (xy 111.645952 -49.210432)
			(xy 111.645952 -49.189168) (xy 111.642144 -49.179226) (xy 111.623902 -49.136562) (xy 111.595357 -49.048271)
			(xy 111.576163 -48.957486) (xy 111.566529 -48.865196) (xy 111.565944 -48.8188) (xy 111.566522 -48.772404)
			(xy 111.576168 -48.680116) (xy 111.595365 -48.589332) (xy 111.623905 -48.501039) (xy 111.642144 -48.458374)
			(xy 111.645952 -48.448432) (xy 111.645952 -48.427168) (xy 111.642144 -48.417226) (xy 111.623919 -48.374624)
			(xy 111.595403 -48.286456) (xy 111.576211 -48.1958) (xy 111.566552 -48.10364) (xy 111.565944 -48.057308)
			(xy 111.565944 -48.0568) (xy 111.566467 -48.015699) (xy 111.574051 -47.933847) (xy 111.589155 -47.853045)
			(xy 111.61165 -47.77398) (xy 111.641344 -47.697329) (xy 111.677983 -47.623744) (xy 111.721256 -47.553853)
			(xy 111.770792 -47.488254) (xy 111.82617 -47.427504) (xy 111.886917 -47.372123) (xy 111.952514 -47.322583)
			(xy 112.022402 -47.279307) (xy 112.095985 -47.242663) (xy 112.172635 -47.212965) (xy 112.251698 -47.190466)
			(xy 112.3325 -47.175358) (xy 112.414351 -47.167769) (xy 112.455452 -47.167292) (xy 112.45596 -47.167292)
			(xy 112.502291 -47.167915) (xy 112.594449 -47.177581) (xy 112.685103 -47.196772) (xy 112.773272 -47.225279)
			(xy 112.815878 -47.243492) (xy 112.82582 -47.247298) (xy 112.847084 -47.247298) (xy 112.857026 -47.243492)
			(xy 112.899695 -47.225263) (xy 112.987985 -47.196715) (xy 113.078768 -47.177517) (xy 113.171056 -47.167879)
			(xy 113.217452 -47.167292) (xy 113.263847 -47.167892) (xy 113.356135 -47.177532) (xy 113.446919 -47.196723)
			(xy 113.535213 -47.225256) (xy 113.577878 -47.243492) (xy 113.58782 -47.247298) (xy 113.609084 -47.247298)
			(xy 113.619026 -47.243492) (xy 113.661695 -47.225263) (xy 113.749985 -47.196715) (xy 113.840768 -47.177517)
			(xy 113.933056 -47.167879) (xy 113.979452 -47.167292) (xy 114.025847 -47.167892) (xy 114.118135 -47.177532)
			(xy 114.208919 -47.196723) (xy 114.297213 -47.225256) (xy 114.339878 -47.243492) (xy 114.34982 -47.247298)
			(xy 114.371084 -47.247298) (xy 114.381026 -47.243492) (xy 114.423695 -47.225263) (xy 114.511985 -47.196715)
			(xy 114.602768 -47.177517) (xy 114.695056 -47.167879) (xy 114.741452 -47.167292) (xy 114.787847 -47.167892)
			(xy 114.880135 -47.177532) (xy 114.970919 -47.196723) (xy 115.059213 -47.225256) (xy 115.101878 -47.243492)
			(xy 115.11182 -47.247298) (xy 115.133084 -47.247298) (xy 115.143026 -47.243492) (xy 115.185635 -47.225286)
			(xy 115.2738 -47.196764) (xy 115.364454 -47.177567) (xy 115.456612 -47.167903) (xy 115.502944 -47.167292)
			(xy 115.503452 -47.167292) (xy 115.544554 -47.167798) (xy 115.626409 -47.175379) (xy 115.707215 -47.19048)
			(xy 115.786282 -47.212973) (xy 115.862937 -47.242665) (xy 115.936525 -47.279304) (xy 116.006418 -47.322577)
			(xy 116.072021 -47.372114) (xy 116.132772 -47.427494) (xy 116.188155 -47.488242) (xy 116.237696 -47.553842)
			(xy 116.280972 -47.623733) (xy 116.317615 -47.697319) (xy 116.347312 -47.773972) (xy 116.369809 -47.853039)
			(xy 116.384915 -47.933844) (xy 116.3925 -48.015698) (xy 116.39296 -48.0568) (xy 116.39296 -48.057308)
			(xy 116.392358 -48.10364) (xy 116.382686 -48.195798) (xy 116.363489 -48.286452) (xy 116.334976 -48.374621)
			(xy 116.31676 -48.417226) (xy 116.312952 -48.427168) (xy 116.312952 -48.448432) (xy 116.31676 -48.458374)
			(xy 116.335002 -48.501037) (xy 116.363547 -48.589329) (xy 116.382741 -48.680114) (xy 116.392375 -48.772404)
			(xy 116.39296 -48.8188) (xy 116.392381 -48.865196) (xy 116.382736 -48.957484) (xy 116.363539 -49.048268)
			(xy 116.334999 -49.136561) (xy 116.31676 -49.179226) (xy 116.312952 -49.189168) (xy 116.312952 -49.210432)
			(xy 116.31676 -49.220374) (xy 116.335002 -49.263037) (xy 116.363547 -49.351329) (xy 116.382741 -49.442114)
			(xy 116.392375 -49.534404) (xy 116.39296 -49.5808) (xy 116.392381 -49.627196) (xy 116.382736 -49.719484)
			(xy 116.363539 -49.810268) (xy 116.334999 -49.898561) (xy 116.31676 -49.941226) (xy 116.312952 -49.951168)
			(xy 116.312952 -49.972432) (xy 116.31676 -49.982374) (xy 116.335002 -50.025037) (xy 116.363547 -50.113329)
			(xy 116.382741 -50.204114) (xy 116.392375 -50.296404) (xy 116.39296 -50.3428) (xy 116.392381 -50.389196)
			(xy 116.382736 -50.481484) (xy 116.363539 -50.572268) (xy 116.334999 -50.660561) (xy 116.31676 -50.703226)
			(xy 116.312952 -50.713168) (xy 116.312952 -50.734432) (xy 116.31676 -50.744374) (xy 116.334985 -50.786976)
			(xy 116.363501 -50.875144) (xy 116.382693 -50.965799) (xy 116.392352 -51.05796) (xy 116.39296 -51.104292)
			(xy 116.39296 -51.1048) (xy 116.392548 -51.145905) (xy 116.384962 -51.227763) (xy 116.369856 -51.308572)
			(xy 116.347357 -51.387643) (xy 116.317659 -51.4643) (xy 116.281014 -51.53789) (xy 116.237735 -51.607785)
			(xy 116.188192 -51.673388) (xy 116.132806 -51.73414) (xy 116.072051 -51.789522) (xy 116.006446 -51.839062)
			(xy 115.936548 -51.882338) (xy 115.862956 -51.918979) (xy 115.786297 -51.948673) (xy 115.707226 -51.971167)
			(xy 115.626415 -51.986269) (xy 115.544557 -51.99385) (xy 115.503452 -51.994308) (xy 115.502944 -51.994308)
			(xy 115.456613 -51.993684) (xy 115.364455 -51.984018) (xy 115.273801 -51.964827) (xy 115.185632 -51.936321)
			(xy 115.143026 -51.918108) (xy 115.133084 -51.914302) (xy 115.11182 -51.914302) (xy 115.101878 -51.918108)
			(xy 115.059209 -51.936336) (xy 114.970919 -51.964884) (xy 114.880136 -51.984082) (xy 114.787847 -51.99372)
			(xy 114.741452 -51.994308) (xy 114.695057 -51.993707) (xy 114.602769 -51.984067) (xy 114.511985 -51.964876)
			(xy 114.423691 -51.936343) (xy 114.381026 -51.918108) (xy 114.371084 -51.914302) (xy 114.34982 -51.914302)
			(xy 114.339878 -51.918108) (xy 114.297209 -51.936336) (xy 114.208919 -51.964884) (xy 114.118136 -51.984082)
			(xy 114.025847 -51.99372) (xy 113.979452 -51.994308) (xy 113.933057 -51.993707) (xy 113.840769 -51.984067)
			(xy 113.749985 -51.964876) (xy 113.661691 -51.936343) (xy 113.619026 -51.918108) (xy 113.609084 -51.914302)
			(xy 113.58782 -51.914302) (xy 113.577878 -51.918108) (xy 113.535209 -51.936336) (xy 113.446919 -51.964884)
			(xy 113.356136 -51.984082) (xy 113.263847 -51.99372) (xy 113.217452 -51.994308) (xy 113.171057 -51.993707)
			(xy 113.078769 -51.984067) (xy 112.987985 -51.964876) (xy 112.899691 -51.936343) (xy 112.857026 -51.918108)
			(xy 112.847084 -51.914302) (xy 112.82582 -51.914302) (xy 112.815878 -51.918108) (xy 112.773268 -51.936313)
			(xy 112.685103 -51.964835) (xy 112.59445 -51.984033) (xy 112.502292 -51.993697) (xy 112.45596 -51.994308)
			(xy 112.455452 -51.994308) (xy 112.414349 -51.993879) (xy 112.332493 -51.98629) (xy 112.251687 -51.971181)
			(xy 112.17262 -51.94868) (xy 112.095965 -51.918981) (xy 112.022379 -51.882335) (xy 111.952487 -51.839057)
			(xy 111.886886 -51.789514) (xy 111.826136 -51.73413) (xy 111.770755 -51.673377) (xy 111.721216 -51.607774)
			(xy 111.677941 -51.537879) (xy 111.6413 -51.464291) (xy 111.611604 -51.387635) (xy 111.589108 -51.308566)
			(xy 111.574003 -51.227759) (xy 111.566419 -51.145903) (xy 111.565944 -51.1048) (xy 62.921225 -51.1048)
			(xy 62.914352 -51.143226) (xy 62.890728 -51.23011) (xy 62.859517 -51.314566) (xy 62.820964 -51.395933)
			(xy 62.775371 -51.473575) (xy 62.723094 -51.546883) (xy 62.664543 -51.615284) (xy 62.600176 -51.678243)
			(xy 62.530496 -51.735267) (xy 62.456049 -51.785909) (xy 62.377418 -51.829773) (xy 62.295218 -51.866516)
			(xy 62.210092 -51.895851) (xy 62.122707 -51.917547) (xy 62.033746 -51.931436) (xy 61.943905 -51.937407)
			(xy 61.853889 -51.935416) (xy 61.7644 -51.925476) (xy 61.676141 -51.907666) (xy 61.5898 -51.882126)
			(xy 61.506055 -51.849054) (xy 61.425561 -51.808711) (xy 61.348947 -51.761411) (xy 61.276813 -51.707526)
			(xy 61.209724 -51.647476) (xy 61.148204 -51.581731) (xy 61.092736 -51.510807) (xy 61.043753 -51.435258)
			(xy 61.001639 -51.355676) (xy 60.966723 -51.272683) (xy 60.939279 -51.186929) (xy 60.919521 -51.099085)
			(xy 60.907604 -51.009838) (xy 60.903622 -50.919888) (xy 43.38066 -50.919888) (xy 43.380162 -50.964907)
			(xy 43.372205 -51.054594) (xy 43.356352 -51.143226) (xy 43.332728 -51.23011) (xy 43.301517 -51.314566)
			(xy 43.262964 -51.395933) (xy 43.217371 -51.473575) (xy 43.165094 -51.546883) (xy 43.106543 -51.615284)
			(xy 43.042176 -51.678243) (xy 42.972496 -51.735267) (xy 42.898049 -51.785909) (xy 42.819418 -51.829773)
			(xy 42.737218 -51.866516) (xy 42.652092 -51.895851) (xy 42.564707 -51.917547) (xy 42.475746 -51.931436)
			(xy 42.385905 -51.937407) (xy 42.295889 -51.935416) (xy 42.2064 -51.925476) (xy 42.118141 -51.907666)
			(xy 42.0318 -51.882126) (xy 41.948055 -51.849054) (xy 41.867561 -51.808711) (xy 41.790947 -51.761411)
			(xy 41.718813 -51.707526) (xy 41.651724 -51.647476) (xy 41.590204 -51.581731) (xy 41.534736 -51.510807)
			(xy 41.485753 -51.435258) (xy 41.443639 -51.355676) (xy 41.408723 -51.272683) (xy 41.381279 -51.186929)
			(xy 41.361521 -51.099085) (xy 41.349604 -51.009838) (xy 41.345622 -50.919888) (xy 0.509016 -50.919888)
			(xy 0.509016 -53.735167) (xy 108.485174 -53.735167) (xy 108.485174 -53.650445) (xy 108.493227 -53.566108)
			(xy 108.509261 -53.482918) (xy 108.533129 -53.401628) (xy 108.564617 -53.322976) (xy 108.603439 -53.247673)
			(xy 108.649242 -53.176401) (xy 108.701613 -53.109805) (xy 108.760078 -53.04849) (xy 108.824106 -52.993009)
			(xy 108.893118 -52.943866) (xy 108.966488 -52.901506) (xy 109.043553 -52.866311) (xy 109.123615 -52.838602)
			(xy 109.205948 -52.818628) (xy 109.289807 -52.806571) (xy 109.374432 -52.80254) (xy 109.459057 -52.806571)
			(xy 109.542916 -52.818628) (xy 109.625249 -52.838602) (xy 109.705311 -52.866311) (xy 109.782376 -52.901506)
			(xy 109.855746 -52.943866) (xy 109.924758 -52.993009) (xy 109.988786 -53.04849) (xy 110.047251 -53.109805)
			(xy 110.099622 -53.176401) (xy 110.145425 -53.247673) (xy 110.184247 -53.322976) (xy 110.215735 -53.401628)
			(xy 110.239603 -53.482918) (xy 110.255637 -53.566108) (xy 110.26369 -53.650445) (xy 110.264194 -53.692806)
			(xy 110.26369 -53.735167) (xy 110.255637 -53.819504) (xy 110.239603 -53.902694) (xy 110.215735 -53.983984)
			(xy 110.184247 -54.062636) (xy 110.145425 -54.137939) (xy 110.099622 -54.209211) (xy 110.047251 -54.275807)
			(xy 109.988786 -54.337122) (xy 109.924758 -54.392603) (xy 109.855746 -54.441746) (xy 109.782376 -54.484106)
			(xy 109.705311 -54.519301) (xy 109.687801 -54.525361) (xy 110.388142 -54.525361) (xy 110.388142 -54.440639)
			(xy 110.396195 -54.356302) (xy 110.412229 -54.273112) (xy 110.436097 -54.191822) (xy 110.467585 -54.11317)
			(xy 110.506407 -54.037867) (xy 110.55221 -53.966595) (xy 110.604581 -53.899999) (xy 110.663046 -53.838684)
			(xy 110.727074 -53.783203) (xy 110.796086 -53.73406) (xy 110.869456 -53.6917) (xy 110.946521 -53.656505)
			(xy 111.026583 -53.628796) (xy 111.108916 -53.608822) (xy 111.192775 -53.596765) (xy 111.2774 -53.592734)
			(xy 111.362025 -53.596765) (xy 111.445884 -53.608822) (xy 111.528217 -53.628796) (xy 111.608279 -53.656505)
			(xy 111.685344 -53.6917) (xy 111.758714 -53.73406) (xy 111.827726 -53.783203) (xy 111.891754 -53.838684)
			(xy 111.950219 -53.899999) (xy 112.00259 -53.966595) (xy 112.048393 -54.037867) (xy 112.087215 -54.11317)
			(xy 112.118703 -54.191822) (xy 112.142571 -54.273112) (xy 112.158605 -54.356302) (xy 112.166658 -54.440639)
			(xy 112.167162 -54.483) (xy 112.166658 -54.525361) (xy 112.158605 -54.609698) (xy 112.142571 -54.692888)
			(xy 112.118703 -54.774178) (xy 112.087215 -54.85283) (xy 112.048393 -54.928133) (xy 112.00259 -54.999405)
			(xy 111.950219 -55.066001) (xy 111.891754 -55.127316) (xy 111.827726 -55.182797) (xy 111.758714 -55.23194)
			(xy 111.685344 -55.2743) (xy 111.608279 -55.309495) (xy 111.528217 -55.337204) (xy 111.445884 -55.357178)
			(xy 111.362025 -55.369235) (xy 111.2774 -55.373267) (xy 111.192775 -55.369235) (xy 111.108916 -55.357178)
			(xy 111.026583 -55.337204) (xy 110.946521 -55.309495) (xy 110.869456 -55.2743) (xy 110.796086 -55.23194)
			(xy 110.727074 -55.182797) (xy 110.663046 -55.127316) (xy 110.604581 -55.066001) (xy 110.55221 -54.999405)
			(xy 110.506407 -54.928133) (xy 110.467585 -54.85283) (xy 110.436097 -54.774178) (xy 110.412229 -54.692888)
			(xy 110.396195 -54.609698) (xy 110.388142 -54.525361) (xy 109.687801 -54.525361) (xy 109.625249 -54.54701)
			(xy 109.542916 -54.566984) (xy 109.459057 -54.579041) (xy 109.374432 -54.583073) (xy 109.289807 -54.579041)
			(xy 109.205948 -54.566984) (xy 109.123615 -54.54701) (xy 109.043553 -54.519301) (xy 108.966488 -54.484106)
			(xy 108.893118 -54.441746) (xy 108.824106 -54.392603) (xy 108.760078 -54.337122) (xy 108.701613 -54.275807)
			(xy 108.649242 -54.209211) (xy 108.603439 -54.137939) (xy 108.564617 -54.062636) (xy 108.533129 -53.983984)
			(xy 108.509261 -53.902694) (xy 108.493227 -53.819504) (xy 108.485174 -53.735167) (xy 0.509016 -53.735167)
			(xy 0.509016 -56.150961) (xy 111.362994 -56.150961) (xy 111.362994 -56.066239) (xy 111.371047 -55.981902)
			(xy 111.387081 -55.898712) (xy 111.410949 -55.817422) (xy 111.442437 -55.73877) (xy 111.481259 -55.663467)
			(xy 111.527062 -55.592195) (xy 111.579433 -55.525599) (xy 111.637898 -55.464284) (xy 111.701926 -55.408803)
			(xy 111.770938 -55.35966) (xy 111.844308 -55.3173) (xy 111.921373 -55.282105) (xy 112.001435 -55.254396)
			(xy 112.083768 -55.234422) (xy 112.167627 -55.222365) (xy 112.252252 -55.218334) (xy 112.336877 -55.222365)
			(xy 112.420736 -55.234422) (xy 112.503069 -55.254396) (xy 112.583131 -55.282105) (xy 112.660196 -55.3173)
			(xy 112.733566 -55.35966) (xy 112.802578 -55.408803) (xy 112.866606 -55.464284) (xy 112.925071 -55.525599)
			(xy 112.977442 -55.592195) (xy 113.023245 -55.663467) (xy 113.062067 -55.73877) (xy 113.093555 -55.817422)
			(xy 113.117423 -55.898712) (xy 113.133457 -55.981902) (xy 113.14151 -56.066239) (xy 113.142014 -56.1086)
			(xy 113.14151 -56.150961) (xy 113.133457 -56.235298) (xy 113.117423 -56.318488) (xy 113.093555 -56.399778)
			(xy 113.062067 -56.47843) (xy 113.023245 -56.553733) (xy 112.977442 -56.625005) (xy 112.925071 -56.691601)
			(xy 112.866606 -56.752916) (xy 112.802578 -56.808397) (xy 112.733566 -56.85754) (xy 112.660196 -56.8999)
			(xy 112.583131 -56.935095) (xy 112.503069 -56.962804) (xy 112.420736 -56.982778) (xy 112.336877 -56.994835)
			(xy 112.252252 -56.998867) (xy 112.167627 -56.994835) (xy 112.083768 -56.982778) (xy 112.001435 -56.962804)
			(xy 111.921373 -56.935095) (xy 111.844308 -56.8999) (xy 111.770938 -56.85754) (xy 111.701926 -56.808397)
			(xy 111.637898 -56.752916) (xy 111.579433 -56.691601) (xy 111.527062 -56.625005) (xy 111.481259 -56.553733)
			(xy 111.442437 -56.47843) (xy 111.410949 -56.399778) (xy 111.387081 -56.318488) (xy 111.371047 -56.235298)
			(xy 111.362994 -56.150961) (xy 0.509016 -56.150961) (xy 0.509016 -60.099956) (xy 12.484104 -60.099956)
			(xy 12.488134 -59.957621) (xy 12.500209 -59.815741) (xy 12.520292 -59.674773) (xy 12.548319 -59.535166)
			(xy 12.584199 -59.397368) (xy 12.627817 -59.261821) (xy 12.679034 -59.128959) (xy 12.737685 -58.999207)
			(xy 12.803583 -58.872981) (xy 12.876517 -58.750685) (xy 12.956254 -58.632712) (xy 13.042536 -58.519439)
			(xy 13.135089 -58.411228) (xy 13.233616 -58.308427) (xy 13.337801 -58.211365) (xy 13.44731 -58.120353)
			(xy 13.561793 -58.035681) (xy 13.680883 -57.957623) (xy 13.804198 -57.886427) (xy 13.931344 -57.822321)
			(xy 14.061913 -57.765512) (xy 14.195487 -57.71618) (xy 14.331638 -57.674484) (xy 14.469929 -57.640558)
			(xy 14.609919 -57.61451) (xy 14.751158 -57.596424) (xy 14.893194 -57.586357) (xy 15.035572 -57.584342)
			(xy 15.177836 -57.590385) (xy 15.31953 -57.604467) (xy 15.4602 -57.626543) (xy 15.599397 -57.656543)
			(xy 15.736673 -57.694369) (xy 15.871589 -57.739901) (xy 16.003713 -57.792992) (xy 16.132622 -57.853474)
			(xy 16.257903 -57.921152) (xy 16.379154 -57.995809) (xy 16.495987 -58.077207) (xy 16.608028 -58.165084)
			(xy 16.714918 -58.259159) (xy 16.816315 -58.359131) (xy 16.871434 -58.42) (xy 40.838131 -58.42) (xy 40.842106 -58.309941)
			(xy 40.854014 -58.200455) (xy 40.87379 -58.092114) (xy 40.901333 -57.985483) (xy 40.936498 -57.881117)
			(xy 40.979102 -57.77956) (xy 41.028923 -57.681343) (xy 41.085702 -57.586976) (xy 41.149141 -57.496952)
			(xy 41.218912 -57.411741) (xy 41.294649 -57.331786) (xy 41.375958 -57.257505) (xy 41.462415 -57.189285)
			(xy 41.553569 -57.12748) (xy 41.648946 -57.072415) (xy 41.748047 -57.024375) (xy 41.850356 -56.983611)
			(xy 41.95534 -56.950336) (xy 42.062451 -56.924723) (xy 42.171131 -56.906906) (xy 42.280814 -56.896977)
			(xy 42.390927 -56.894989) (xy 42.500897 -56.900951) (xy 42.61015 -56.914833) (xy 42.718116 -56.936563)
			(xy 42.824233 -56.966026) (xy 42.927947 -57.003069) (xy 43.028718 -57.0475) (xy 43.12602 -57.099087)
			(xy 43.219346 -57.157559) (xy 43.308209 -57.222614) (xy 43.392147 -57.293912) (xy 43.470722 -57.37108)
			(xy 43.543523 -57.453717) (xy 43.610171 -57.541391) (xy 43.67032 -57.633647) (xy 43.723654 -57.730002)
			(xy 43.769897 -57.829954) (xy 43.808807 -57.932982) (xy 43.840181 -58.03855) (xy 43.863856 -58.146106)
			(xy 43.879708 -58.25509) (xy 43.887655 -58.364934) (xy 43.888152 -58.42) (xy 60.396131 -58.42) (xy 60.400106 -58.309941)
			(xy 60.412014 -58.200455) (xy 60.43179 -58.092114) (xy 60.459333 -57.985483) (xy 60.494498 -57.881117)
			(xy 60.537102 -57.77956) (xy 60.586923 -57.681343) (xy 60.643702 -57.586976) (xy 60.707141 -57.496952)
			(xy 60.776912 -57.411741) (xy 60.852649 -57.331786) (xy 60.933958 -57.257505) (xy 61.020415 -57.189285)
			(xy 61.111569 -57.12748) (xy 61.206946 -57.072415) (xy 61.306047 -57.024375) (xy 61.408356 -56.983611)
			(xy 61.51334 -56.950336) (xy 61.620451 -56.924723) (xy 61.729131 -56.906906) (xy 61.838814 -56.896977)
			(xy 61.948927 -56.894989) (xy 62.058897 -56.900951) (xy 62.16815 -56.914833) (xy 62.276116 -56.936563)
			(xy 62.382233 -56.966026) (xy 62.485947 -57.003069) (xy 62.586718 -57.0475) (xy 62.68402 -57.099087)
			(xy 62.777346 -57.157559) (xy 62.866209 -57.222614) (xy 62.950147 -57.293912) (xy 63.028722 -57.37108)
			(xy 63.101523 -57.453717) (xy 63.168171 -57.541391) (xy 63.22832 -57.633647) (xy 63.281654 -57.730002)
			(xy 63.327897 -57.829954) (xy 63.366807 -57.932982) (xy 63.398181 -58.03855) (xy 63.421856 -58.146106)
			(xy 63.437708 -58.25509) (xy 63.445655 -58.364934) (xy 63.446152 -58.42) (xy 63.445655 -58.475066)
			(xy 63.437708 -58.58491) (xy 63.421856 -58.693894) (xy 63.398181 -58.80145) (xy 63.366807 -58.907018)
			(xy 63.327897 -59.010046) (xy 63.281654 -59.109998) (xy 63.22832 -59.206353) (xy 63.168171 -59.298609)
			(xy 63.101523 -59.386283) (xy 63.028722 -59.46892) (xy 62.950147 -59.546088) (xy 62.866209 -59.617386)
			(xy 62.777346 -59.682441) (xy 62.68402 -59.740913) (xy 62.586718 -59.7925) (xy 62.485947 -59.836931)
			(xy 62.382233 -59.873974) (xy 62.276116 -59.903437) (xy 62.16815 -59.925167) (xy 62.058897 -59.939049)
			(xy 61.948927 -59.945011) (xy 61.838814 -59.943023) (xy 61.729131 -59.933094) (xy 61.620451 -59.915277)
			(xy 61.51334 -59.889664) (xy 61.408356 -59.856389) (xy 61.306047 -59.815625) (xy 61.206946 -59.767585)
			(xy 61.111569 -59.71252) (xy 61.020415 -59.650715) (xy 60.933958 -59.582495) (xy 60.852649 -59.508214)
			(xy 60.776912 -59.428259) (xy 60.707141 -59.343048) (xy 60.643702 -59.253024) (xy 60.586923 -59.158657)
			(xy 60.537102 -59.06044) (xy 60.494498 -58.958883) (xy 60.459333 -58.854517) (xy 60.43179 -58.747886)
			(xy 60.412014 -58.639545) (xy 60.400106 -58.530059) (xy 60.396131 -58.42) (xy 43.888152 -58.42) (xy 43.887655 -58.475066)
			(xy 43.879708 -58.58491) (xy 43.863856 -58.693894) (xy 43.840181 -58.80145) (xy 43.808807 -58.907018)
			(xy 43.769897 -59.010046) (xy 43.723654 -59.109998) (xy 43.67032 -59.206353) (xy 43.610171 -59.298609)
			(xy 43.543523 -59.386283) (xy 43.470722 -59.46892) (xy 43.392147 -59.546088) (xy 43.308209 -59.617386)
			(xy 43.219346 -59.682441) (xy 43.12602 -59.740913) (xy 43.028718 -59.7925) (xy 42.927947 -59.836931)
			(xy 42.824233 -59.873974) (xy 42.718116 -59.903437) (xy 42.61015 -59.925167) (xy 42.500897 -59.939049)
			(xy 42.390927 -59.945011) (xy 42.280814 -59.943023) (xy 42.171131 -59.933094) (xy 42.062451 -59.915277)
			(xy 41.95534 -59.889664) (xy 41.850356 -59.856389) (xy 41.748047 -59.815625) (xy 41.648946 -59.767585)
			(xy 41.553569 -59.71252) (xy 41.462415 -59.650715) (xy 41.375958 -59.582495) (xy 41.294649 -59.508214)
			(xy 41.218912 -59.428259) (xy 41.149141 -59.343048) (xy 41.085702 -59.253024) (xy 41.028923 -59.158657)
			(xy 40.979102 -59.06044) (xy 40.936498 -58.958883) (xy 40.901333 -58.854517) (xy 40.87379 -58.747886)
			(xy 40.854014 -58.639545) (xy 40.842106 -58.530059) (xy 40.838131 -58.42) (xy 16.871434 -58.42) (xy 16.911893 -58.464679)
			(xy 17.001347 -58.575465) (xy 17.084389 -58.691134) (xy 17.160755 -58.811317) (xy 17.230199 -58.935627)
			(xy 17.292499 -59.063668) (xy 17.347455 -59.195027) (xy 17.394892 -59.329286) (xy 17.434656 -59.466013)
			(xy 17.466622 -59.604771) (xy 17.490687 -59.745115) (xy 17.506773 -59.886596) (xy 17.514828 -60.02876)
			(xy 17.515332 -60.099956) (xy 17.514828 -60.171152) (xy 17.506773 -60.313316) (xy 17.490687 -60.454797)
			(xy 17.466622 -60.595141) (xy 17.434656 -60.733899) (xy 17.394892 -60.870626) (xy 17.347455 -61.004885)
			(xy 17.292499 -61.136244) (xy 17.230199 -61.264285) (xy 17.160755 -61.388595) (xy 17.084389 -61.508778)
			(xy 17.001347 -61.624447) (xy 16.911893 -61.735233) (xy 16.816315 -61.840781) (xy 16.714918 -61.940753)
			(xy 16.608028 -62.034828) (xy 16.495987 -62.122705) (xy 16.379154 -62.204103) (xy 16.257903 -62.27876)
			(xy 16.132622 -62.346438) (xy 16.055974 -62.3824) (xy 111.565944 -62.3824) (xy 111.565944 -62.381892)
			(xy 111.566546 -62.33556) (xy 111.576218 -62.243402) (xy 111.595414 -62.152748) (xy 111.623928 -62.064579)
			(xy 111.642144 -62.021974) (xy 111.645952 -62.012032) (xy 111.645952 -61.990768) (xy 111.642144 -61.980826)
			(xy 111.623902 -61.938162) (xy 111.595357 -61.849871) (xy 111.576163 -61.759086) (xy 111.566529 -61.666796)
			(xy 111.565944 -61.6204) (xy 111.566522 -61.574004) (xy 111.576168 -61.481716) (xy 111.595365 -61.390932)
			(xy 111.623905 -61.302639) (xy 111.642144 -61.259974) (xy 111.645952 -61.250032) (xy 111.645952 -61.228768)
			(xy 111.642144 -61.218826) (xy 111.623902 -61.176162) (xy 111.595357 -61.087871) (xy 111.576163 -60.997086)
			(xy 111.566529 -60.904796) (xy 111.565944 -60.8584) (xy 111.566522 -60.812004) (xy 111.576168 -60.719716)
			(xy 111.595365 -60.628932) (xy 111.623905 -60.540639) (xy 111.642144 -60.497974) (xy 111.645952 -60.488032)
			(xy 111.645952 -60.466768) (xy 111.642144 -60.456826) (xy 111.623902 -60.414162) (xy 111.595357 -60.325871)
			(xy 111.576163 -60.235086) (xy 111.566529 -60.142796) (xy 111.565944 -60.0964) (xy 111.566522 -60.050004)
			(xy 111.576168 -59.957716) (xy 111.595365 -59.866932) (xy 111.623905 -59.778639) (xy 111.642144 -59.735974)
			(xy 111.645952 -59.726032) (xy 111.645952 -59.704768) (xy 111.642144 -59.694826) (xy 111.623919 -59.652224)
			(xy 111.595403 -59.564056) (xy 111.576211 -59.4734) (xy 111.566552 -59.38124) (xy 111.565944 -59.334908)
			(xy 111.565944 -59.3344) (xy 111.566467 -59.293299) (xy 111.574051 -59.211447) (xy 111.589155 -59.130645)
			(xy 111.61165 -59.05158) (xy 111.641344 -58.974929) (xy 111.677983 -58.901344) (xy 111.721256 -58.831453)
			(xy 111.770792 -58.765854) (xy 111.82617 -58.705104) (xy 111.886917 -58.649723) (xy 111.952514 -58.600183)
			(xy 112.022402 -58.556907) (xy 112.095985 -58.520263) (xy 112.172635 -58.490565) (xy 112.251698 -58.468066)
			(xy 112.3325 -58.452958) (xy 112.414351 -58.445369) (xy 112.455452 -58.444892) (xy 112.45596 -58.444892)
			(xy 112.502291 -58.445515) (xy 112.594449 -58.455181) (xy 112.685103 -58.474372) (xy 112.773272 -58.502879)
			(xy 112.815878 -58.521092) (xy 112.82582 -58.524898) (xy 112.847084 -58.524898) (xy 112.857026 -58.521092)
			(xy 112.899695 -58.502863) (xy 112.987985 -58.474315) (xy 113.078768 -58.455117) (xy 113.171056 -58.445479)
			(xy 113.217452 -58.444892) (xy 113.263847 -58.445492) (xy 113.356135 -58.455132) (xy 113.446919 -58.474323)
			(xy 113.535213 -58.502856) (xy 113.577878 -58.521092) (xy 113.58782 -58.524898) (xy 113.609084 -58.524898)
			(xy 113.619026 -58.521092) (xy 113.661695 -58.502863) (xy 113.749985 -58.474315) (xy 113.840768 -58.455117)
			(xy 113.933056 -58.445479) (xy 113.979452 -58.444892) (xy 114.025847 -58.445492) (xy 114.118135 -58.455132)
			(xy 114.208919 -58.474323) (xy 114.297213 -58.502856) (xy 114.339878 -58.521092) (xy 114.34982 -58.524898)
			(xy 114.371084 -58.524898) (xy 114.381026 -58.521092) (xy 114.423695 -58.502863) (xy 114.511985 -58.474315)
			(xy 114.602768 -58.455117) (xy 114.695056 -58.445479) (xy 114.741452 -58.444892) (xy 114.787847 -58.445492)
			(xy 114.880135 -58.455132) (xy 114.970919 -58.474323) (xy 115.059213 -58.502856) (xy 115.101878 -58.521092)
			(xy 115.11182 -58.524898) (xy 115.133084 -58.524898) (xy 115.143026 -58.521092) (xy 115.185635 -58.502886)
			(xy 115.2738 -58.474364) (xy 115.364454 -58.455167) (xy 115.456612 -58.445503) (xy 115.502944 -58.444892)
			(xy 115.503452 -58.444892) (xy 115.544554 -58.445398) (xy 115.626409 -58.452979) (xy 115.707215 -58.46808)
			(xy 115.786282 -58.490573) (xy 115.862937 -58.520265) (xy 115.936525 -58.556904) (xy 116.006418 -58.600177)
			(xy 116.072021 -58.649714) (xy 116.132772 -58.705094) (xy 116.188155 -58.765842) (xy 116.237696 -58.831442)
			(xy 116.280972 -58.901333) (xy 116.317615 -58.974919) (xy 116.347312 -59.051572) (xy 116.369809 -59.130639)
			(xy 116.384915 -59.211444) (xy 116.3925 -59.293298) (xy 116.39296 -59.3344) (xy 116.39296 -59.334908)
			(xy 116.392358 -59.38124) (xy 116.382686 -59.473398) (xy 116.363489 -59.564052) (xy 116.334976 -59.652221)
			(xy 116.31676 -59.694826) (xy 116.312952 -59.704768) (xy 116.312952 -59.726032) (xy 116.31676 -59.735974)
			(xy 116.335002 -59.778637) (xy 116.363547 -59.866929) (xy 116.382741 -59.957714) (xy 116.392375 -60.050004)
			(xy 116.39296 -60.0964) (xy 116.392381 -60.142796) (xy 116.382736 -60.235084) (xy 116.363539 -60.325868)
			(xy 116.334999 -60.414161) (xy 116.31676 -60.456826) (xy 116.312952 -60.466768) (xy 116.312952 -60.488032)
			(xy 116.31676 -60.497974) (xy 116.335002 -60.540637) (xy 116.363547 -60.628929) (xy 116.382741 -60.719714)
			(xy 116.392375 -60.812004) (xy 116.39296 -60.8584) (xy 116.392381 -60.904796) (xy 116.382736 -60.997084)
			(xy 116.363539 -61.087868) (xy 116.334999 -61.176161) (xy 116.31676 -61.218826) (xy 116.312952 -61.228768)
			(xy 116.312952 -61.250032) (xy 116.31676 -61.259974) (xy 116.335002 -61.302637) (xy 116.363547 -61.390929)
			(xy 116.382741 -61.481714) (xy 116.392375 -61.574004) (xy 116.39296 -61.6204) (xy 116.392381 -61.666796)
			(xy 116.382736 -61.759084) (xy 116.363539 -61.849868) (xy 116.334999 -61.938161) (xy 116.31676 -61.980826)
			(xy 116.312952 -61.990768) (xy 116.312952 -62.012032) (xy 116.31676 -62.021974) (xy 116.334985 -62.064576)
			(xy 116.363501 -62.152744) (xy 116.382693 -62.243399) (xy 116.392352 -62.33556) (xy 116.39296 -62.381892)
			(xy 116.39296 -62.3824) (xy 116.392548 -62.423505) (xy 116.384962 -62.505363) (xy 116.369856 -62.586172)
			(xy 116.347357 -62.665243) (xy 116.317659 -62.7419) (xy 116.281014 -62.81549) (xy 116.237735 -62.885385)
			(xy 116.188192 -62.950988) (xy 116.132806 -63.01174) (xy 116.072051 -63.067122) (xy 116.006446 -63.116662)
			(xy 115.936548 -63.159938) (xy 115.862956 -63.196579) (xy 115.786297 -63.226273) (xy 115.707226 -63.248767)
			(xy 115.626415 -63.263869) (xy 115.544557 -63.27145) (xy 115.503452 -63.271908) (xy 115.502944 -63.271908)
			(xy 115.456613 -63.271284) (xy 115.364455 -63.261618) (xy 115.273801 -63.242427) (xy 115.185632 -63.213921)
			(xy 115.143026 -63.195708) (xy 115.133084 -63.191902) (xy 115.11182 -63.191902) (xy 115.101878 -63.195708)
			(xy 115.059209 -63.213936) (xy 114.970919 -63.242484) (xy 114.880136 -63.261682) (xy 114.787847 -63.27132)
			(xy 114.741452 -63.271908) (xy 114.695057 -63.271307) (xy 114.602769 -63.261667) (xy 114.511985 -63.242476)
			(xy 114.423691 -63.213943) (xy 114.381026 -63.195708) (xy 114.371084 -63.191902) (xy 114.34982 -63.191902)
			(xy 114.339878 -63.195708) (xy 114.297209 -63.213936) (xy 114.208919 -63.242484) (xy 114.118136 -63.261682)
			(xy 114.025847 -63.27132) (xy 113.979452 -63.271908) (xy 113.933057 -63.271307) (xy 113.840769 -63.261667)
			(xy 113.749985 -63.242476) (xy 113.661691 -63.213943) (xy 113.619026 -63.195708) (xy 113.609084 -63.191902)
			(xy 113.58782 -63.191902) (xy 113.577878 -63.195708) (xy 113.535209 -63.213936) (xy 113.446919 -63.242484)
			(xy 113.356136 -63.261682) (xy 113.263847 -63.27132) (xy 113.217452 -63.271908) (xy 113.171057 -63.271307)
			(xy 113.078769 -63.261667) (xy 112.987985 -63.242476) (xy 112.899691 -63.213943) (xy 112.857026 -63.195708)
			(xy 112.847084 -63.191902) (xy 112.82582 -63.191902) (xy 112.815878 -63.195708) (xy 112.773268 -63.213913)
			(xy 112.685103 -63.242435) (xy 112.59445 -63.261633) (xy 112.502292 -63.271297) (xy 112.45596 -63.271908)
			(xy 112.455452 -63.271908) (xy 112.414349 -63.271479) (xy 112.332493 -63.26389) (xy 112.251687 -63.248781)
			(xy 112.17262 -63.22628) (xy 112.095965 -63.196581) (xy 112.022379 -63.159935) (xy 111.952487 -63.116657)
			(xy 111.886886 -63.067114) (xy 111.826136 -63.01173) (xy 111.770755 -62.950977) (xy 111.721216 -62.885374)
			(xy 111.677941 -62.815479) (xy 111.6413 -62.741891) (xy 111.611604 -62.665235) (xy 111.589108 -62.586166)
			(xy 111.574003 -62.505359) (xy 111.566419 -62.423503) (xy 111.565944 -62.3824) (xy 16.055974 -62.3824)
			(xy 16.003713 -62.40692) (xy 15.871589 -62.460011) (xy 15.736673 -62.505543) (xy 15.599397 -62.543369)
			(xy 15.4602 -62.573369) (xy 15.31953 -62.595445) (xy 15.177836 -62.609527) (xy 15.035572 -62.61557)
			(xy 14.893194 -62.613555) (xy 14.751158 -62.603488) (xy 14.609919 -62.585402) (xy 14.469929 -62.559354)
			(xy 14.331638 -62.525428) (xy 14.195487 -62.483732) (xy 14.061913 -62.4344) (xy 13.931344 -62.377591)
			(xy 13.804198 -62.313485) (xy 13.680883 -62.242289) (xy 13.561793 -62.164231) (xy 13.44731 -62.079559)
			(xy 13.337801 -61.988547) (xy 13.233616 -61.891485) (xy 13.135089 -61.788684) (xy 13.042536 -61.680473)
			(xy 12.956254 -61.5672) (xy 12.876517 -61.449227) (xy 12.803583 -61.326931) (xy 12.737685 -61.200705)
			(xy 12.679034 -61.070953) (xy 12.627817 -60.938091) (xy 12.584199 -60.802544) (xy 12.548319 -60.664746)
			(xy 12.520292 -60.525139) (xy 12.500209 -60.384171) (xy 12.488134 -60.242291) (xy 12.484104 -60.099956)
			(xy 0.509016 -60.099956) (xy 0.509016 -67.428561) (xy 111.362994 -67.428561) (xy 111.362994 -67.343839)
			(xy 111.371047 -67.259502) (xy 111.387081 -67.176312) (xy 111.410949 -67.095022) (xy 111.442437 -67.01637)
			(xy 111.481259 -66.941067) (xy 111.527062 -66.869795) (xy 111.579433 -66.803199) (xy 111.637898 -66.741884)
			(xy 111.701926 -66.686403) (xy 111.770938 -66.63726) (xy 111.844308 -66.5949) (xy 111.921373 -66.559705)
			(xy 112.001435 -66.531996) (xy 112.083768 -66.512022) (xy 112.167627 -66.499965) (xy 112.252252 -66.495934)
			(xy 112.336877 -66.499965) (xy 112.420736 -66.512022) (xy 112.503069 -66.531996) (xy 112.583131 -66.559705)
			(xy 112.660196 -66.5949) (xy 112.733566 -66.63726) (xy 112.802578 -66.686403) (xy 112.866606 -66.741884)
			(xy 112.925071 -66.803199) (xy 112.977442 -66.869795) (xy 113.023245 -66.941067) (xy 113.062067 -67.01637)
			(xy 113.093555 -67.095022) (xy 113.117423 -67.176312) (xy 113.133457 -67.259502) (xy 113.14151 -67.343839)
			(xy 113.142014 -67.3862) (xy 113.14151 -67.428561) (xy 113.133457 -67.512898) (xy 113.117423 -67.596088)
			(xy 113.093555 -67.677378) (xy 113.062067 -67.75603) (xy 113.023245 -67.831333) (xy 112.977442 -67.902605)
			(xy 112.925071 -67.969201) (xy 112.866606 -68.030516) (xy 112.802578 -68.085997) (xy 112.733566 -68.13514)
			(xy 112.660196 -68.1775) (xy 112.583131 -68.212695) (xy 112.503069 -68.240404) (xy 112.420736 -68.260378)
			(xy 112.336877 -68.272435) (xy 112.252252 -68.276467) (xy 112.167627 -68.272435) (xy 112.083768 -68.260378)
			(xy 112.001435 -68.240404) (xy 111.921373 -68.212695) (xy 111.844308 -68.1775) (xy 111.770938 -68.13514)
			(xy 111.701926 -68.085997) (xy 111.637898 -68.030516) (xy 111.579433 -67.969201) (xy 111.527062 -67.902605)
			(xy 111.481259 -67.831333) (xy 111.442437 -67.75603) (xy 111.410949 -67.677378) (xy 111.387081 -67.596088)
			(xy 111.371047 -67.512898) (xy 111.362994 -67.428561) (xy 0.509016 -67.428561) (xy 0.509016 -71.239888)
			(xy 41.345622 -71.239888) (xy 41.349604 -71.149938) (xy 41.361521 -71.060691) (xy 41.381279 -70.972847)
			(xy 41.408723 -70.887093) (xy 41.443639 -70.8041) (xy 41.485753 -70.724518) (xy 41.534736 -70.648969)
			(xy 41.590204 -70.578045) (xy 41.651724 -70.5123) (xy 41.718813 -70.45225) (xy 41.790947 -70.398365)
			(xy 41.867561 -70.351065) (xy 41.948055 -70.310722) (xy 42.0318 -70.27765) (xy 42.118141 -70.25211)
			(xy 42.2064 -70.2343) (xy 42.295889 -70.22436) (xy 42.385905 -70.222369) (xy 42.475746 -70.22834)
			(xy 42.564707 -70.242229) (xy 42.652092 -70.263925) (xy 42.737218 -70.29326) (xy 42.819418 -70.330003)
			(xy 42.898049 -70.373867) (xy 42.972496 -70.424509) (xy 43.042176 -70.481533) (xy 43.106543 -70.544492)
			(xy 43.165094 -70.612893) (xy 43.217371 -70.686201) (xy 43.262964 -70.763843) (xy 43.301517 -70.84521)
			(xy 43.332728 -70.929666) (xy 43.356352 -71.01655) (xy 43.372205 -71.105182) (xy 43.380162 -71.194869)
			(xy 43.38066 -71.239888) (xy 60.903622 -71.239888) (xy 60.907604 -71.149938) (xy 60.919521 -71.060691)
			(xy 60.939279 -70.972847) (xy 60.966723 -70.887093) (xy 61.001639 -70.8041) (xy 61.043753 -70.724518)
			(xy 61.092736 -70.648969) (xy 61.148204 -70.578045) (xy 61.209724 -70.5123) (xy 61.276813 -70.45225)
			(xy 61.348947 -70.398365) (xy 61.425561 -70.351065) (xy 61.506055 -70.310722) (xy 61.5898 -70.27765)
			(xy 61.676141 -70.25211) (xy 61.7644 -70.2343) (xy 61.853889 -70.22436) (xy 61.943905 -70.222369)
			(xy 62.033746 -70.22834) (xy 62.122707 -70.242229) (xy 62.210092 -70.263925) (xy 62.295218 -70.29326)
			(xy 62.377418 -70.330003) (xy 62.456049 -70.373867) (xy 62.530496 -70.424509) (xy 62.600176 -70.481533)
			(xy 62.664543 -70.544492) (xy 62.723094 -70.612893) (xy 62.775371 -70.686201) (xy 62.820964 -70.763843)
			(xy 62.859517 -70.84521) (xy 62.890728 -70.929666) (xy 62.914352 -71.01655) (xy 62.930205 -71.105182)
			(xy 62.938162 -71.194869) (xy 62.93866 -71.239888) (xy 62.938162 -71.284907) (xy 62.930205 -71.374594)
			(xy 62.914352 -71.463226) (xy 62.890728 -71.55011) (xy 62.859517 -71.634566) (xy 62.820964 -71.715933)
			(xy 62.775371 -71.793575) (xy 62.723094 -71.866883) (xy 62.664543 -71.935284) (xy 62.600176 -71.998243)
			(xy 62.530496 -72.055267) (xy 62.456049 -72.105909) (xy 62.377418 -72.149773) (xy 62.295218 -72.186516)
			(xy 62.210092 -72.215851) (xy 62.122707 -72.237547) (xy 62.033746 -72.251436) (xy 61.943905 -72.257407)
			(xy 61.853889 -72.255416) (xy 61.7644 -72.245476) (xy 61.676141 -72.227666) (xy 61.5898 -72.202126)
			(xy 61.506055 -72.169054) (xy 61.425561 -72.128711) (xy 61.348947 -72.081411) (xy 61.276813 -72.027526)
			(xy 61.209724 -71.967476) (xy 61.148204 -71.901731) (xy 61.092736 -71.830807) (xy 61.043753 -71.755258)
			(xy 61.001639 -71.675676) (xy 60.966723 -71.592683) (xy 60.939279 -71.506929) (xy 60.919521 -71.419085)
			(xy 60.907604 -71.329838) (xy 60.903622 -71.239888) (xy 43.38066 -71.239888) (xy 43.380162 -71.284907)
			(xy 43.372205 -71.374594) (xy 43.356352 -71.463226) (xy 43.332728 -71.55011) (xy 43.301517 -71.634566)
			(xy 43.262964 -71.715933) (xy 43.217371 -71.793575) (xy 43.165094 -71.866883) (xy 43.106543 -71.935284)
			(xy 43.042176 -71.998243) (xy 42.972496 -72.055267) (xy 42.898049 -72.105909) (xy 42.819418 -72.149773)
			(xy 42.737218 -72.186516) (xy 42.652092 -72.215851) (xy 42.564707 -72.237547) (xy 42.475746 -72.251436)
			(xy 42.385905 -72.257407) (xy 42.295889 -72.255416) (xy 42.2064 -72.245476) (xy 42.118141 -72.227666)
			(xy 42.0318 -72.202126) (xy 41.948055 -72.169054) (xy 41.867561 -72.128711) (xy 41.790947 -72.081411)
			(xy 41.718813 -72.027526) (xy 41.651724 -71.967476) (xy 41.590204 -71.901731) (xy 41.534736 -71.830807)
			(xy 41.485753 -71.755258) (xy 41.443639 -71.675676) (xy 41.408723 -71.592683) (xy 41.381279 -71.506929)
			(xy 41.361521 -71.419085) (xy 41.349604 -71.329838) (xy 41.345622 -71.239888) (xy 0.509016 -71.239888)
			(xy 0.509016 -73.66) (xy 111.565944 -73.66) (xy 111.565944 -73.659492) (xy 111.566546 -73.61316)
			(xy 111.576218 -73.521002) (xy 111.595414 -73.430348) (xy 111.623928 -73.342179) (xy 111.642144 -73.299574)
			(xy 111.645952 -73.289632) (xy 111.645952 -73.268368) (xy 111.642144 -73.258426) (xy 111.623902 -73.215762)
			(xy 111.595357 -73.127471) (xy 111.576163 -73.036686) (xy 111.566529 -72.944396) (xy 111.565944 -72.898)
			(xy 111.566522 -72.851604) (xy 111.576168 -72.759316) (xy 111.595365 -72.668532) (xy 111.623905 -72.580239)
			(xy 111.642144 -72.537574) (xy 111.645952 -72.527632) (xy 111.645952 -72.506368) (xy 111.642144 -72.496426)
			(xy 111.623902 -72.453762) (xy 111.595357 -72.365471) (xy 111.576163 -72.274686) (xy 111.566529 -72.182396)
			(xy 111.565944 -72.136) (xy 111.566522 -72.089604) (xy 111.576168 -71.997316) (xy 111.595365 -71.906532)
			(xy 111.623905 -71.818239) (xy 111.642144 -71.775574) (xy 111.645952 -71.765632) (xy 111.645952 -71.744368)
			(xy 111.642144 -71.734426) (xy 111.623902 -71.691762) (xy 111.595357 -71.603471) (xy 111.576163 -71.512686)
			(xy 111.566529 -71.420396) (xy 111.565944 -71.374) (xy 111.566522 -71.327604) (xy 111.576168 -71.235316)
			(xy 111.595365 -71.144532) (xy 111.623905 -71.056239) (xy 111.642144 -71.013574) (xy 111.645952 -71.003632)
			(xy 111.645952 -70.982368) (xy 111.642144 -70.972426) (xy 111.623919 -70.929824) (xy 111.595403 -70.841656)
			(xy 111.576211 -70.751) (xy 111.566552 -70.65884) (xy 111.565944 -70.612508) (xy 111.565944 -70.612)
			(xy 111.566467 -70.570899) (xy 111.574051 -70.489047) (xy 111.589155 -70.408245) (xy 111.61165 -70.32918)
			(xy 111.641344 -70.252529) (xy 111.677983 -70.178944) (xy 111.721256 -70.109053) (xy 111.770792 -70.043454)
			(xy 111.82617 -69.982704) (xy 111.886917 -69.927323) (xy 111.952514 -69.877783) (xy 112.022402 -69.834507)
			(xy 112.095985 -69.797863) (xy 112.172635 -69.768165) (xy 112.251698 -69.745666) (xy 112.3325 -69.730558)
			(xy 112.414351 -69.722969) (xy 112.455452 -69.722492) (xy 112.45596 -69.722492) (xy 112.502291 -69.723115)
			(xy 112.594449 -69.732781) (xy 112.685103 -69.751972) (xy 112.773272 -69.780479) (xy 112.815878 -69.798692)
			(xy 112.82582 -69.802498) (xy 112.847084 -69.802498) (xy 112.857026 -69.798692) (xy 112.899695 -69.780463)
			(xy 112.987985 -69.751915) (xy 113.078768 -69.732717) (xy 113.171056 -69.723079) (xy 113.217452 -69.722492)
			(xy 113.263847 -69.723092) (xy 113.356135 -69.732732) (xy 113.446919 -69.751923) (xy 113.535213 -69.780456)
			(xy 113.577878 -69.798692) (xy 113.58782 -69.802498) (xy 113.609084 -69.802498) (xy 113.619026 -69.798692)
			(xy 113.661695 -69.780463) (xy 113.749985 -69.751915) (xy 113.840768 -69.732717) (xy 113.933056 -69.723079)
			(xy 113.979452 -69.722492) (xy 114.025847 -69.723092) (xy 114.118135 -69.732732) (xy 114.208919 -69.751923)
			(xy 114.297213 -69.780456) (xy 114.339878 -69.798692) (xy 114.34982 -69.802498) (xy 114.371084 -69.802498)
			(xy 114.381026 -69.798692) (xy 114.423695 -69.780463) (xy 114.511985 -69.751915) (xy 114.602768 -69.732717)
			(xy 114.695056 -69.723079) (xy 114.741452 -69.722492) (xy 114.787847 -69.723092) (xy 114.880135 -69.732732)
			(xy 114.970919 -69.751923) (xy 115.059213 -69.780456) (xy 115.101878 -69.798692) (xy 115.11182 -69.802498)
			(xy 115.133084 -69.802498) (xy 115.143026 -69.798692) (xy 115.185635 -69.780486) (xy 115.2738 -69.751964)
			(xy 115.364454 -69.732767) (xy 115.456612 -69.723103) (xy 115.502944 -69.722492) (xy 115.503452 -69.722492)
			(xy 115.544554 -69.722998) (xy 115.626409 -69.730579) (xy 115.707215 -69.74568) (xy 115.786282 -69.768173)
			(xy 115.862937 -69.797865) (xy 115.936525 -69.834504) (xy 116.006418 -69.877777) (xy 116.072021 -69.927314)
			(xy 116.132772 -69.982694) (xy 116.188155 -70.043442) (xy 116.237696 -70.109042) (xy 116.280972 -70.178933)
			(xy 116.317615 -70.252519) (xy 116.347312 -70.329172) (xy 116.369809 -70.408239) (xy 116.384915 -70.489044)
			(xy 116.3925 -70.570898) (xy 116.39296 -70.612) (xy 116.39296 -70.612508) (xy 116.392358 -70.65884)
			(xy 116.382686 -70.750998) (xy 116.363489 -70.841652) (xy 116.334976 -70.929821) (xy 116.31676 -70.972426)
			(xy 116.312952 -70.982368) (xy 116.312952 -71.003632) (xy 116.31676 -71.013574) (xy 116.335002 -71.056237)
			(xy 116.363547 -71.144529) (xy 116.382741 -71.235314) (xy 116.392375 -71.327604) (xy 116.39296 -71.374)
			(xy 116.392381 -71.420396) (xy 116.382736 -71.512684) (xy 116.363539 -71.603468) (xy 116.334999 -71.691761)
			(xy 116.31676 -71.734426) (xy 116.312952 -71.744368) (xy 116.312952 -71.765632) (xy 116.31676 -71.775574)
			(xy 116.335002 -71.818237) (xy 116.363547 -71.906529) (xy 116.382741 -71.997314) (xy 116.392375 -72.089604)
			(xy 116.39296 -72.136) (xy 116.392381 -72.182396) (xy 116.382736 -72.274684) (xy 116.363539 -72.365468)
			(xy 116.334999 -72.453761) (xy 116.31676 -72.496426) (xy 116.312952 -72.506368) (xy 116.312952 -72.527632)
			(xy 116.31676 -72.537574) (xy 116.335002 -72.580237) (xy 116.363547 -72.668529) (xy 116.382741 -72.759314)
			(xy 116.392375 -72.851604) (xy 116.39296 -72.898) (xy 116.392381 -72.944396) (xy 116.382736 -73.036684)
			(xy 116.363539 -73.127468) (xy 116.334999 -73.215761) (xy 116.31676 -73.258426) (xy 116.312952 -73.268368)
			(xy 116.312952 -73.289632) (xy 116.31676 -73.299574) (xy 116.334985 -73.342176) (xy 116.363501 -73.430344)
			(xy 116.382693 -73.520999) (xy 116.392352 -73.61316) (xy 116.39296 -73.659492) (xy 116.39296 -73.66)
			(xy 116.392548 -73.701105) (xy 116.384962 -73.782963) (xy 116.369856 -73.863772) (xy 116.347357 -73.942843)
			(xy 116.317659 -74.0195) (xy 116.281014 -74.09309) (xy 116.237735 -74.162985) (xy 116.188192 -74.228588)
			(xy 116.132806 -74.28934) (xy 116.072051 -74.344722) (xy 116.006446 -74.394262) (xy 115.936548 -74.437538)
			(xy 115.862956 -74.474179) (xy 115.786297 -74.503873) (xy 115.707226 -74.526367) (xy 115.626415 -74.541469)
			(xy 115.544557 -74.54905) (xy 115.503452 -74.549508) (xy 115.502944 -74.549508) (xy 115.456613 -74.548884)
			(xy 115.364455 -74.539218) (xy 115.273801 -74.520027) (xy 115.185632 -74.491521) (xy 115.143026 -74.473308)
			(xy 115.133084 -74.469502) (xy 115.11182 -74.469502) (xy 115.101878 -74.473308) (xy 115.059209 -74.491536)
			(xy 114.970919 -74.520084) (xy 114.880136 -74.539282) (xy 114.787847 -74.54892) (xy 114.741452 -74.549508)
			(xy 114.695057 -74.548907) (xy 114.602769 -74.539267) (xy 114.511985 -74.520076) (xy 114.423691 -74.491543)
			(xy 114.381026 -74.473308) (xy 114.371084 -74.469502) (xy 114.34982 -74.469502) (xy 114.339878 -74.473308)
			(xy 114.297209 -74.491536) (xy 114.208919 -74.520084) (xy 114.118136 -74.539282) (xy 114.025847 -74.54892)
			(xy 113.979452 -74.549508) (xy 113.933057 -74.548907) (xy 113.840769 -74.539267) (xy 113.749985 -74.520076)
			(xy 113.661691 -74.491543) (xy 113.619026 -74.473308) (xy 113.609084 -74.469502) (xy 113.58782 -74.469502)
			(xy 113.577878 -74.473308) (xy 113.535209 -74.491536) (xy 113.446919 -74.520084) (xy 113.356136 -74.539282)
			(xy 113.263847 -74.54892) (xy 113.217452 -74.549508) (xy 113.171057 -74.548907) (xy 113.078769 -74.539267)
			(xy 112.987985 -74.520076) (xy 112.899691 -74.491543) (xy 112.857026 -74.473308) (xy 112.847084 -74.469502)
			(xy 112.82582 -74.469502) (xy 112.815878 -74.473308) (xy 112.773268 -74.491513) (xy 112.685103 -74.520035)
			(xy 112.59445 -74.539233) (xy 112.502292 -74.548897) (xy 112.45596 -74.549508) (xy 112.455452 -74.549508)
			(xy 112.414349 -74.549079) (xy 112.332493 -74.54149) (xy 112.251687 -74.526381) (xy 112.17262 -74.50388)
			(xy 112.095965 -74.474181) (xy 112.022379 -74.437535) (xy 111.952487 -74.394257) (xy 111.886886 -74.344714)
			(xy 111.826136 -74.28933) (xy 111.770755 -74.228577) (xy 111.721216 -74.162974) (xy 111.677941 -74.093079)
			(xy 111.6413 -74.019491) (xy 111.611604 -73.942835) (xy 111.589108 -73.863766) (xy 111.574003 -73.782959)
			(xy 111.566419 -73.701103) (xy 111.565944 -73.66) (xy 0.509016 -73.66) (xy 0.509016 -78.74) (xy 40.838131 -78.74)
			(xy 40.842106 -78.629941) (xy 40.854014 -78.520455) (xy 40.87379 -78.412114) (xy 40.901333 -78.305483)
			(xy 40.936498 -78.201117) (xy 40.979102 -78.09956) (xy 41.028923 -78.001343) (xy 41.085702 -77.906976)
			(xy 41.149141 -77.816952) (xy 41.218912 -77.731741) (xy 41.294649 -77.651786) (xy 41.375958 -77.577505)
			(xy 41.462415 -77.509285) (xy 41.553569 -77.44748) (xy 41.648946 -77.392415) (xy 41.748047 -77.344375)
			(xy 41.850356 -77.303611) (xy 41.95534 -77.270336) (xy 42.062451 -77.244723) (xy 42.171131 -77.226906)
			(xy 42.280814 -77.216977) (xy 42.390927 -77.214989) (xy 42.500897 -77.220951) (xy 42.61015 -77.234833)
			(xy 42.718116 -77.256563) (xy 42.824233 -77.286026) (xy 42.927947 -77.323069) (xy 43.028718 -77.3675)
			(xy 43.12602 -77.419087) (xy 43.219346 -77.477559) (xy 43.308209 -77.542614) (xy 43.392147 -77.613912)
			(xy 43.470722 -77.69108) (xy 43.543523 -77.773717) (xy 43.610171 -77.861391) (xy 43.67032 -77.953647)
			(xy 43.723654 -78.050002) (xy 43.769897 -78.149954) (xy 43.808807 -78.252982) (xy 43.840181 -78.35855)
			(xy 43.863856 -78.466106) (xy 43.879708 -78.57509) (xy 43.887655 -78.684934) (xy 43.888152 -78.74)
			(xy 60.396131 -78.74) (xy 60.400106 -78.629941) (xy 60.412014 -78.520455) (xy 60.43179 -78.412114)
			(xy 60.459333 -78.305483) (xy 60.494498 -78.201117) (xy 60.537102 -78.09956) (xy 60.586923 -78.001343)
			(xy 60.643702 -77.906976) (xy 60.707141 -77.816952) (xy 60.776912 -77.731741) (xy 60.852649 -77.651786)
			(xy 60.933958 -77.577505) (xy 61.020415 -77.509285) (xy 61.111569 -77.44748) (xy 61.206946 -77.392415)
			(xy 61.306047 -77.344375) (xy 61.408356 -77.303611) (xy 61.51334 -77.270336) (xy 61.620451 -77.244723)
			(xy 61.729131 -77.226906) (xy 61.838814 -77.216977) (xy 61.948927 -77.214989) (xy 62.058897 -77.220951)
			(xy 62.16815 -77.234833) (xy 62.276116 -77.256563) (xy 62.382233 -77.286026) (xy 62.485947 -77.323069)
			(xy 62.586718 -77.3675) (xy 62.68402 -77.419087) (xy 62.777346 -77.477559) (xy 62.866209 -77.542614)
			(xy 62.950147 -77.613912) (xy 63.028722 -77.69108) (xy 63.101523 -77.773717) (xy 63.168171 -77.861391)
			(xy 63.22832 -77.953647) (xy 63.281654 -78.050002) (xy 63.327897 -78.149954) (xy 63.366807 -78.252982)
			(xy 63.398181 -78.35855) (xy 63.421856 -78.466106) (xy 63.437708 -78.57509) (xy 63.445655 -78.684934)
			(xy 63.445847 -78.706161) (xy 111.362994 -78.706161) (xy 111.362994 -78.621439) (xy 111.371047 -78.537102)
			(xy 111.387081 -78.453912) (xy 111.410949 -78.372622) (xy 111.442437 -78.29397) (xy 111.481259 -78.218667)
			(xy 111.527062 -78.147395) (xy 111.579433 -78.080799) (xy 111.637898 -78.019484) (xy 111.701926 -77.964003)
			(xy 111.770938 -77.91486) (xy 111.844308 -77.8725) (xy 111.921373 -77.837305) (xy 112.001435 -77.809596)
			(xy 112.083768 -77.789622) (xy 112.167627 -77.777565) (xy 112.252252 -77.773534) (xy 112.336877 -77.777565)
			(xy 112.420736 -77.789622) (xy 112.503069 -77.809596) (xy 112.583131 -77.837305) (xy 112.660196 -77.8725)
			(xy 112.733566 -77.91486) (xy 112.802578 -77.964003) (xy 112.866606 -78.019484) (xy 112.925071 -78.080799)
			(xy 112.977442 -78.147395) (xy 113.023245 -78.218667) (xy 113.062067 -78.29397) (xy 113.093555 -78.372622)
			(xy 113.117423 -78.453912) (xy 113.133457 -78.537102) (xy 113.14151 -78.621439) (xy 113.142014 -78.6638)
			(xy 113.14151 -78.706161) (xy 113.133457 -78.790498) (xy 113.117423 -78.873688) (xy 113.093555 -78.954978)
			(xy 113.062067 -79.03363) (xy 113.023245 -79.108933) (xy 112.977442 -79.180205) (xy 112.925071 -79.246801)
			(xy 112.866606 -79.308116) (xy 112.802578 -79.363597) (xy 112.733566 -79.41274) (xy 112.660196 -79.4551)
			(xy 112.583131 -79.490295) (xy 112.503069 -79.518004) (xy 112.420736 -79.537978) (xy 112.336877 -79.550035)
			(xy 112.252252 -79.554067) (xy 112.167627 -79.550035) (xy 112.083768 -79.537978) (xy 112.001435 -79.518004)
			(xy 111.921373 -79.490295) (xy 111.844308 -79.4551) (xy 111.770938 -79.41274) (xy 111.701926 -79.363597)
			(xy 111.637898 -79.308116) (xy 111.579433 -79.246801) (xy 111.527062 -79.180205) (xy 111.481259 -79.108933)
			(xy 111.442437 -79.03363) (xy 111.410949 -78.954978) (xy 111.387081 -78.873688) (xy 111.371047 -78.790498)
			(xy 111.362994 -78.706161) (xy 63.445847 -78.706161) (xy 63.446152 -78.74) (xy 63.445655 -78.795066)
			(xy 63.437708 -78.90491) (xy 63.421856 -79.013894) (xy 63.398181 -79.12145) (xy 63.366807 -79.227018)
			(xy 63.327897 -79.330046) (xy 63.281654 -79.429998) (xy 63.22832 -79.526353) (xy 63.168171 -79.618609)
			(xy 63.101523 -79.706283) (xy 63.028722 -79.78892) (xy 62.950147 -79.866088) (xy 62.930237 -79.883)
			(xy 122.3264 -79.883) (xy 122.3264 -13.081) (xy 122.326939 -13.047741) (xy 122.335625 -12.981791)
			(xy 122.352847 -12.91754) (xy 122.378311 -12.856089) (xy 122.411582 -12.798488) (xy 122.452088 -12.745724)
			(xy 122.475244 -12.721844) (xy 123.110244 -12.086844) (xy 123.134129 -12.063692) (xy 123.186889 -12.023179)
			(xy 123.244488 -11.989903) (xy 123.305939 -11.964434) (xy 123.37019 -11.947209) (xy 123.43614 -11.938521)
			(xy 123.4694 -11.938) (xy 156.980382 -11.938) (xy 157.013641 -11.938551) (xy 157.07959 -11.947234)
			(xy 157.143841 -11.964454) (xy 157.205292 -11.989916) (xy 157.262894 -12.023184) (xy 157.315658 -12.063689)
			(xy 157.339538 -12.086844) (xy 161.039556 -15.786862) (xy 161.062716 -15.810739) (xy 161.103229 -15.863501)
			(xy 161.136504 -15.921101) (xy 161.161971 -15.982554) (xy 161.179195 -16.046806) (xy 161.18788 -16.112758)
			(xy 161.1884 -16.146018) (xy 161.1884 -22.560114) (xy 205.177635 -22.560114) (xy 205.177635 -22.389758)
			(xy 205.18562 -22.21959) (xy 205.201572 -22.049983) (xy 205.225457 -21.881311) (xy 205.257221 -21.713943)
			(xy 205.296796 -21.548248) (xy 205.344093 -21.38459) (xy 205.39901 -21.223329) (xy 205.461425 -21.064819)
			(xy 205.531201 -20.909409) (xy 205.608184 -20.757441) (xy 205.692206 -20.609247) (xy 205.783082 -20.465155)
			(xy 205.880612 -20.325481) (xy 205.984582 -20.190532) (xy 206.094763 -20.060604) (xy 206.210912 -19.935984)
			(xy 206.332776 -19.816945) (xy 206.460084 -19.703749) (xy 206.592559 -19.596644) (xy 206.729909 -19.495867)
			(xy 206.871831 -19.401638) (xy 207.018013 -19.314165) (xy 207.168136 -19.23364) (xy 207.321867 -19.16024)
			(xy 207.47887 -19.094126) (xy 207.6388 -19.035444) (xy 207.801304 -18.984323) (xy 207.966025 -18.940875)
			(xy 208.132603 -18.905196) (xy 208.300669 -18.877364) (xy 208.469855 -18.85744) (xy 208.639789 -18.845468)
			(xy 208.810098 -18.841475) (xy 208.980407 -18.845468) (xy 209.150341 -18.85744) (xy 209.319527 -18.877364)
			(xy 209.487593 -18.905196) (xy 209.654171 -18.940875) (xy 209.818892 -18.984323) (xy 209.981396 -19.035444)
			(xy 210.141326 -19.094126) (xy 210.298329 -19.16024) (xy 210.45206 -19.23364) (xy 210.602183 -19.314165)
			(xy 210.748365 -19.401638) (xy 210.890287 -19.495867) (xy 211.027637 -19.596644) (xy 211.160112 -19.703749)
			(xy 211.28742 -19.816945) (xy 211.409284 -19.935984) (xy 211.525433 -20.060604) (xy 211.635614 -20.190532)
			(xy 211.739584 -20.325481) (xy 211.837114 -20.465155) (xy 211.92799 -20.609247) (xy 212.012012 -20.757441)
			(xy 212.088995 -20.909409) (xy 212.158771 -21.064819) (xy 212.221186 -21.223329) (xy 212.276103 -21.38459)
			(xy 212.3234 -21.548248) (xy 212.362975 -21.713943) (xy 212.394739 -21.881311) (xy 212.418624 -22.049983)
			(xy 212.434576 -22.21959) (xy 212.442561 -22.389758) (xy 212.44306 -22.474936) (xy 212.442561 -22.560114)
			(xy 235.177575 -22.560114) (xy 235.177575 -22.389758) (xy 235.18556 -22.21959) (xy 235.201512 -22.049983)
			(xy 235.225397 -21.881311) (xy 235.257161 -21.713943) (xy 235.296736 -21.548248) (xy 235.344033 -21.38459)
			(xy 235.39895 -21.223329) (xy 235.461365 -21.064819) (xy 235.531141 -20.909409) (xy 235.608124 -20.757441)
			(xy 235.692146 -20.609247) (xy 235.783022 -20.465155) (xy 235.880552 -20.325481) (xy 235.984522 -20.190532)
			(xy 236.094703 -20.060604) (xy 236.210852 -19.935984) (xy 236.332716 -19.816945) (xy 236.460024 -19.703749)
			(xy 236.592499 -19.596644) (xy 236.729849 -19.495867) (xy 236.871771 -19.401638) (xy 237.017953 -19.314165)
			(xy 237.168076 -19.23364) (xy 237.321807 -19.16024) (xy 237.47881 -19.094126) (xy 237.63874 -19.035444)
			(xy 237.801244 -18.984323) (xy 237.965965 -18.940875) (xy 238.132543 -18.905196) (xy 238.300609 -18.877364)
			(xy 238.469795 -18.85744) (xy 238.639729 -18.845468) (xy 238.810038 -18.841475) (xy 238.980347 -18.845468)
			(xy 239.150281 -18.85744) (xy 239.319467 -18.877364) (xy 239.487533 -18.905196) (xy 239.654111 -18.940875)
			(xy 239.818832 -18.984323) (xy 239.981336 -19.035444) (xy 240.141266 -19.094126) (xy 240.298269 -19.16024)
			(xy 240.452 -19.23364) (xy 240.602123 -19.314165) (xy 240.748305 -19.401638) (xy 240.890227 -19.495867)
			(xy 241.027577 -19.596644) (xy 241.160052 -19.703749) (xy 241.28736 -19.816945) (xy 241.409224 -19.935984)
			(xy 241.525373 -20.060604) (xy 241.635554 -20.190532) (xy 241.739524 -20.325481) (xy 241.837054 -20.465155)
			(xy 241.92793 -20.609247) (xy 242.011952 -20.757441) (xy 242.088935 -20.909409) (xy 242.158711 -21.064819)
			(xy 242.221126 -21.223329) (xy 242.276043 -21.38459) (xy 242.32334 -21.548248) (xy 242.362915 -21.713943)
			(xy 242.394679 -21.881311) (xy 242.418564 -22.049983) (xy 242.434516 -22.21959) (xy 242.442501 -22.389758)
			(xy 242.443 -22.474936) (xy 242.442501 -22.560114) (xy 242.434516 -22.730282) (xy 242.418564 -22.899889)
			(xy 242.394679 -23.068561) (xy 242.362915 -23.235929) (xy 242.32334 -23.401624) (xy 242.276043 -23.565282)
			(xy 242.221126 -23.726543) (xy 242.158711 -23.885053) (xy 242.088935 -24.040463) (xy 242.011952 -24.192431)
			(xy 241.92793 -24.340625) (xy 241.837054 -24.484717) (xy 241.739524 -24.624391) (xy 241.635554 -24.75934)
			(xy 241.525373 -24.889268) (xy 241.409224 -25.013888) (xy 241.28736 -25.132927) (xy 241.160052 -25.246123)
			(xy 241.027577 -25.353228) (xy 240.890227 -25.454005) (xy 240.748305 -25.548234) (xy 240.602123 -25.635707)
			(xy 240.452 -25.716232) (xy 240.298269 -25.789632) (xy 240.141266 -25.855746) (xy 239.981336 -25.914428)
			(xy 239.818832 -25.965549) (xy 239.654111 -26.008997) (xy 239.487533 -26.044676) (xy 239.319467 -26.072508)
			(xy 239.150281 -26.092432) (xy 238.980347 -26.104404) (xy 238.810038 -26.108398) (xy 238.639729 -26.104404)
			(xy 238.469795 -26.092432) (xy 238.300609 -26.072508) (xy 238.132543 -26.044676) (xy 237.965965 -26.008997)
			(xy 237.801244 -25.965549) (xy 237.63874 -25.914428) (xy 237.47881 -25.855746) (xy 237.321807 -25.789632)
			(xy 237.168076 -25.716232) (xy 237.017953 -25.635707) (xy 236.871771 -25.548234) (xy 236.729849 -25.454005)
			(xy 236.592499 -25.353228) (xy 236.460024 -25.246123) (xy 236.332716 -25.132927) (xy 236.210852 -25.013888)
			(xy 236.094703 -24.889268) (xy 235.984522 -24.75934) (xy 235.880552 -24.624391) (xy 235.783022 -24.484717)
			(xy 235.692146 -24.340625) (xy 235.608124 -24.192431) (xy 235.531141 -24.040463) (xy 235.461365 -23.885053)
			(xy 235.39895 -23.726543) (xy 235.344033 -23.565282) (xy 235.296736 -23.401624) (xy 235.257161 -23.235929)
			(xy 235.225397 -23.068561) (xy 235.201512 -22.899889) (xy 235.18556 -22.730282) (xy 235.177575 -22.560114)
			(xy 212.442561 -22.560114) (xy 212.434576 -22.730282) (xy 212.418624 -22.899889) (xy 212.394739 -23.068561)
			(xy 212.362975 -23.235929) (xy 212.3234 -23.401624) (xy 212.276103 -23.565282) (xy 212.221186 -23.726543)
			(xy 212.158771 -23.885053) (xy 212.088995 -24.040463) (xy 212.012012 -24.192431) (xy 211.92799 -24.340625)
			(xy 211.837114 -24.484717) (xy 211.739584 -24.624391) (xy 211.635614 -24.75934) (xy 211.525433 -24.889268)
			(xy 211.409284 -25.013888) (xy 211.28742 -25.132927) (xy 211.160112 -25.246123) (xy 211.027637 -25.353228)
			(xy 210.890287 -25.454005) (xy 210.748365 -25.548234) (xy 210.602183 -25.635707) (xy 210.45206 -25.716232)
			(xy 210.298329 -25.789632) (xy 210.141326 -25.855746) (xy 209.981396 -25.914428) (xy 209.818892 -25.965549)
			(xy 209.654171 -26.008997) (xy 209.487593 -26.044676) (xy 209.319527 -26.072508) (xy 209.150341 -26.092432)
			(xy 208.980407 -26.104404) (xy 208.810098 -26.108398) (xy 208.639789 -26.104404) (xy 208.469855 -26.092432)
			(xy 208.300669 -26.072508) (xy 208.132603 -26.044676) (xy 207.966025 -26.008997) (xy 207.801304 -25.965549)
			(xy 207.6388 -25.914428) (xy 207.47887 -25.855746) (xy 207.321867 -25.789632) (xy 207.168136 -25.716232)
			(xy 207.018013 -25.635707) (xy 206.871831 -25.548234) (xy 206.729909 -25.454005) (xy 206.592559 -25.353228)
			(xy 206.460084 -25.246123) (xy 206.332776 -25.132927) (xy 206.210912 -25.013888) (xy 206.094763 -24.889268)
			(xy 205.984582 -24.75934) (xy 205.880612 -24.624391) (xy 205.783082 -24.484717) (xy 205.692206 -24.340625)
			(xy 205.608184 -24.192431) (xy 205.531201 -24.040463) (xy 205.461425 -23.885053) (xy 205.39901 -23.726543)
			(xy 205.344093 -23.565282) (xy 205.296796 -23.401624) (xy 205.257221 -23.235929) (xy 205.225457 -23.068561)
			(xy 205.201572 -22.899889) (xy 205.18562 -22.730282) (xy 205.177635 -22.560114) (xy 161.1884 -22.560114)
			(xy 161.1884 -26.950924) (xy 161.188786 -26.960998) (xy 161.196532 -26.979597) (xy 161.203386 -26.986992)
			(xy 162.141408 -27.925014) (xy 162.14881 -27.931852) (xy 162.167408 -27.939572) (xy 162.177476 -27.94)
			(xy 209.1944 -27.94) (xy 209.227659 -27.940539) (xy 209.293609 -27.949225) (xy 209.35786 -27.966447)
			(xy 209.419311 -27.991911) (xy 209.476912 -28.025182) (xy 209.529676 -28.065688) (xy 209.553556 -28.088844)
			(xy 211.331556 -29.866844) (xy 211.354708 -29.890729) (xy 211.395221 -29.943489) (xy 211.428497 -30.001088)
			(xy 211.453966 -30.062539) (xy 211.471191 -30.12679) (xy 211.479879 -30.19274) (xy 211.4804 -30.226)
			(xy 211.4804 -46.99) (xy 228.854 -46.99) (xy 228.854 -30.226) (xy 228.854539 -30.192741) (xy 228.863225 -30.126791)
			(xy 228.880447 -30.06254) (xy 228.905911 -30.001089) (xy 228.939182 -29.943488) (xy 228.979688 -29.890724)
			(xy 229.002844 -29.866844) (xy 230.780844 -28.088844) (xy 230.804729 -28.065692) (xy 230.857489 -28.025179)
			(xy 230.915088 -27.991903) (xy 230.976539 -27.966434) (xy 231.04079 -27.949209) (xy 231.10674 -27.940521)
			(xy 231.14 -27.94) (xy 278.156924 -27.94) (xy 278.166998 -27.939614) (xy 278.185597 -27.931868) (xy 278.192992 -27.925014)
			(xy 279.131014 -26.986992) (xy 279.137852 -26.97959) (xy 279.145572 -26.960992) (xy 279.146 -26.950924)
			(xy 279.146 -16.146018) (xy 279.146551 -16.112759) (xy 279.155234 -16.04681) (xy 279.172454 -15.982559)
			(xy 279.197916 -15.921108) (xy 279.231184 -15.863506) (xy 279.271689 -15.810742) (xy 279.294844 -15.786862)
			(xy 282.994862 -12.086844) (xy 283.018739 -12.063684) (xy 283.071501 -12.023171) (xy 283.129101 -11.989896)
			(xy 283.190554 -11.964429) (xy 283.254806 -11.947205) (xy 283.320758 -11.93852) (xy 283.354018 -11.938)
			(xy 323.977 -11.938) (xy 324.010259 -11.938539) (xy 324.076209 -11.947225) (xy 324.14046 -11.964447)
			(xy 324.201911 -11.989911) (xy 324.259512 -12.023182) (xy 324.312276 -12.063688) (xy 324.336156 -12.086844)
			(xy 324.971156 -12.721844) (xy 324.994308 -12.745729) (xy 325.034821 -12.798489) (xy 325.068097 -12.856088)
			(xy 325.093566 -12.917539) (xy 325.110791 -12.98179) (xy 325.119479 -13.04774) (xy 325.12 -13.081)
			(xy 325.12 -17.288961) (xy 334.478626 -17.288961) (xy 334.478626 -17.204239) (xy 334.486679 -17.119902)
			(xy 334.502713 -17.036712) (xy 334.526581 -16.955422) (xy 334.558069 -16.87677) (xy 334.596891 -16.801467)
			(xy 334.642694 -16.730195) (xy 334.695065 -16.663599) (xy 334.75353 -16.602284) (xy 334.817558 -16.546803)
			(xy 334.88657 -16.49766) (xy 334.95994 -16.4553) (xy 335.037005 -16.420105) (xy 335.117067 -16.392396)
			(xy 335.1994 -16.372422) (xy 335.283259 -16.360365) (xy 335.367884 -16.356334) (xy 335.452509 -16.360365)
			(xy 335.536368 -16.372422) (xy 335.618701 -16.392396) (xy 335.698763 -16.420105) (xy 335.775828 -16.4553)
			(xy 335.849198 -16.49766) (xy 335.91821 -16.546803) (xy 335.982238 -16.602284) (xy 336.040703 -16.663599)
			(xy 336.093074 -16.730195) (xy 336.138877 -16.801467) (xy 336.177699 -16.87677) (xy 336.209187 -16.955422)
			(xy 336.233055 -17.036712) (xy 336.249089 -17.119902) (xy 336.257142 -17.204239) (xy 336.257646 -17.2466)
			(xy 336.257142 -17.288961) (xy 336.249089 -17.373298) (xy 336.233055 -17.456488) (xy 336.209187 -17.537778)
			(xy 336.177699 -17.61643) (xy 336.138877 -17.691733) (xy 336.093074 -17.763005) (xy 336.040703 -17.829601)
			(xy 335.982238 -17.890916) (xy 335.91821 -17.946397) (xy 335.849198 -17.99554) (xy 335.775828 -18.0379)
			(xy 335.698763 -18.073095) (xy 335.618701 -18.100804) (xy 335.536368 -18.120778) (xy 335.452509 -18.132835)
			(xy 335.367884 -18.136867) (xy 335.283259 -18.132835) (xy 335.1994 -18.120778) (xy 335.117067 -18.100804)
			(xy 335.037005 -18.073095) (xy 334.95994 -18.0379) (xy 334.88657 -17.99554) (xy 334.817558 -17.946397)
			(xy 334.75353 -17.890916) (xy 334.695065 -17.829601) (xy 334.642694 -17.763005) (xy 334.596891 -17.691733)
			(xy 334.558069 -17.61643) (xy 334.526581 -17.537778) (xy 334.502713 -17.456488) (xy 334.486679 -17.373298)
			(xy 334.478626 -17.288961) (xy 325.12 -17.288961) (xy 325.12 -23.0886) (xy 331.266292 -23.0886) (xy 331.266292 -23.088092)
			(xy 331.266898 -23.04176) (xy 331.276569 -22.949602) (xy 331.295765 -22.858948) (xy 331.324277 -22.770779)
			(xy 331.342492 -22.728174) (xy 331.346298 -22.718232) (xy 331.346298 -22.696968) (xy 331.342492 -22.687026)
			(xy 331.324247 -22.644364) (xy 331.295703 -22.556071) (xy 331.27651 -22.465286) (xy 331.266877 -22.372996)
			(xy 331.266292 -22.3266) (xy 331.266875 -22.280204) (xy 331.27652 -22.187916) (xy 331.295716 -22.097132)
			(xy 331.324254 -22.008839) (xy 331.342492 -21.966174) (xy 331.346298 -21.956232) (xy 331.346298 -21.934968)
			(xy 331.342492 -21.925026) (xy 331.324247 -21.882364) (xy 331.295703 -21.794071) (xy 331.27651 -21.703286)
			(xy 331.266877 -21.610996) (xy 331.266292 -21.5646) (xy 331.266875 -21.518204) (xy 331.27652 -21.425916)
			(xy 331.295716 -21.335132) (xy 331.324254 -21.246839) (xy 331.342492 -21.204174) (xy 331.346298 -21.194232)
			(xy 331.346298 -21.172968) (xy 331.342492 -21.163026) (xy 331.324247 -21.120364) (xy 331.295703 -21.032071)
			(xy 331.27651 -20.941286) (xy 331.266877 -20.848996) (xy 331.266292 -20.8026) (xy 331.266875 -20.756204)
			(xy 331.27652 -20.663916) (xy 331.295716 -20.573132) (xy 331.324254 -20.484839) (xy 331.342492 -20.442174)
			(xy 331.346298 -20.432232) (xy 331.346298 -20.410968) (xy 331.342492 -20.401026) (xy 331.32427 -20.358423)
			(xy 331.295752 -20.270256) (xy 331.27656 -20.1796) (xy 331.2669 -20.08744) (xy 331.266292 -20.041108)
			(xy 331.266292 -20.0406) (xy 331.266767 -19.999498) (xy 331.274352 -19.917643) (xy 331.289457 -19.836838)
			(xy 331.311953 -19.757771) (xy 331.341649 -19.681117) (xy 331.378291 -19.60753) (xy 331.421566 -19.537638)
			(xy 331.471106 -19.472037) (xy 331.526487 -19.411287) (xy 331.587237 -19.355906) (xy 331.652838 -19.306366)
			(xy 331.72273 -19.263091) (xy 331.796317 -19.226449) (xy 331.872971 -19.196753) (xy 331.952038 -19.174257)
			(xy 332.032843 -19.159152) (xy 332.114698 -19.151567) (xy 332.1558 -19.151092) (xy 332.156308 -19.151092)
			(xy 332.20264 -19.151698) (xy 332.294798 -19.161369) (xy 332.385452 -19.180565) (xy 332.473621 -19.209077)
			(xy 332.516226 -19.227292) (xy 332.526168 -19.231098) (xy 332.547432 -19.231098) (xy 332.557374 -19.227292)
			(xy 332.600036 -19.209047) (xy 332.688329 -19.180503) (xy 332.779114 -19.16131) (xy 332.871404 -19.151677)
			(xy 332.9178 -19.151092) (xy 332.964196 -19.151675) (xy 333.056484 -19.16132) (xy 333.147268 -19.180516)
			(xy 333.235561 -19.209054) (xy 333.278226 -19.227292) (xy 333.288168 -19.231098) (xy 333.309432 -19.231098)
			(xy 333.319374 -19.227292) (xy 333.362036 -19.209047) (xy 333.450329 -19.180503) (xy 333.541114 -19.16131)
			(xy 333.633404 -19.151677) (xy 333.6798 -19.151092) (xy 333.726196 -19.151675) (xy 333.818484 -19.16132)
			(xy 333.909268 -19.180516) (xy 333.997561 -19.209054) (xy 334.040226 -19.227292) (xy 334.050168 -19.231098)
			(xy 334.071432 -19.231098) (xy 334.081374 -19.227292) (xy 334.124036 -19.209047) (xy 334.212329 -19.180503)
			(xy 334.303114 -19.16131) (xy 334.395404 -19.151677) (xy 334.4418 -19.151092) (xy 334.488196 -19.151675)
			(xy 334.580484 -19.16132) (xy 334.671268 -19.180516) (xy 334.759561 -19.209054) (xy 334.802226 -19.227292)
			(xy 334.812168 -19.231098) (xy 334.833432 -19.231098) (xy 334.843374 -19.227292) (xy 334.885977 -19.20907)
			(xy 334.974144 -19.180552) (xy 335.0648 -19.16136) (xy 335.15696 -19.1517) (xy 335.203292 -19.151092)
			(xy 335.2038 -19.151092) (xy 335.244902 -19.151567) (xy 335.326757 -19.159152) (xy 335.407562 -19.174257)
			(xy 335.486629 -19.196753) (xy 335.563283 -19.226449) (xy 335.63687 -19.263091) (xy 335.706762 -19.306366)
			(xy 335.772363 -19.355906) (xy 335.833113 -19.411287) (xy 335.888494 -19.472037) (xy 335.938034 -19.537638)
			(xy 335.981309 -19.60753) (xy 336.017951 -19.681117) (xy 336.047647 -19.757771) (xy 336.070143 -19.836838)
			(xy 336.085248 -19.917643) (xy 336.092833 -19.999498) (xy 336.09288 -20.00357) (xy 386.295635 -20.00357)
			(xy 386.295635 -19.87443) (xy 386.303585 -19.745535) (xy 386.319455 -19.617375) (xy 386.343184 -19.490434)
			(xy 386.374683 -19.365195) (xy 386.413832 -19.242132) (xy 386.460483 -19.121713) (xy 386.514458 -19.004394)
			(xy 386.575553 -18.89062) (xy 386.643536 -18.780823) (xy 386.71815 -18.67542) (xy 386.799111 -18.57481)
			(xy 386.886111 -18.479375) (xy 386.978822 -18.389476) (xy 387.076892 -18.305455) (xy 387.179947 -18.227631)
			(xy 387.287598 -18.156299) (xy 387.399437 -18.091729) (xy 387.515038 -18.034167) (xy 387.633963 -17.98383)
			(xy 387.755762 -17.94091) (xy 387.879972 -17.905569) (xy 388.006121 -17.877942) (xy 388.133733 -17.858133)
			(xy 388.262322 -17.846217) (xy 388.3914 -17.842241) (xy 388.520478 -17.846217) (xy 388.649067 -17.858133)
			(xy 388.776679 -17.877942) (xy 388.902828 -17.905569) (xy 389.027038 -17.94091) (xy 389.148837 -17.98383)
			(xy 389.267762 -18.034167) (xy 389.383363 -18.091729) (xy 389.495202 -18.156299) (xy 389.602853 -18.227631)
			(xy 389.705908 -18.305455) (xy 389.803978 -18.389476) (xy 389.896689 -18.479375) (xy 389.983689 -18.57481)
			(xy 390.06465 -18.67542) (xy 390.139264 -18.780823) (xy 390.207247 -18.89062) (xy 390.268342 -19.004394)
			(xy 390.322317 -19.121713) (xy 390.368968 -19.242132) (xy 390.408117 -19.365195) (xy 390.439616 -19.490434)
			(xy 390.463345 -19.617375) (xy 390.479215 -19.745535) (xy 390.487165 -19.87443) (xy 390.487662 -19.939)
			(xy 390.487165 -20.00357) (xy 390.479215 -20.132465) (xy 390.463345 -20.260625) (xy 390.439616 -20.387566)
			(xy 390.408117 -20.512805) (xy 390.368968 -20.635868) (xy 390.322317 -20.756287) (xy 390.268342 -20.873606)
			(xy 390.207247 -20.98738) (xy 390.139264 -21.097177) (xy 390.06465 -21.20258) (xy 389.983689 -21.30319)
			(xy 389.896689 -21.398625) (xy 389.803978 -21.488524) (xy 389.705908 -21.572545) (xy 389.602853 -21.650369)
			(xy 389.495202 -21.721701) (xy 389.383363 -21.786271) (xy 389.267762 -21.843833) (xy 389.148837 -21.89417)
			(xy 389.027038 -21.93709) (xy 388.902828 -21.972431) (xy 388.776679 -22.000058) (xy 388.649067 -22.019867)
			(xy 388.520478 -22.031783) (xy 388.3914 -22.03576) (xy 388.262322 -22.031783) (xy 388.133733 -22.019867)
			(xy 388.006121 -22.000058) (xy 387.879972 -21.972431) (xy 387.755762 -21.93709) (xy 387.633963 -21.89417)
			(xy 387.515038 -21.843833) (xy 387.399437 -21.786271) (xy 387.287598 -21.721701) (xy 387.179947 -21.650369)
			(xy 387.076892 -21.572545) (xy 386.978822 -21.488524) (xy 386.886111 -21.398625) (xy 386.799111 -21.30319)
			(xy 386.71815 -21.20258) (xy 386.643536 -21.097177) (xy 386.575553 -20.98738) (xy 386.514458 -20.873606)
			(xy 386.460483 -20.756287) (xy 386.413832 -20.635868) (xy 386.374683 -20.512805) (xy 386.343184 -20.387566)
			(xy 386.319455 -20.260625) (xy 386.303585 -20.132465) (xy 386.295635 -20.00357) (xy 336.09288 -20.00357)
			(xy 336.093308 -20.0406) (xy 336.093308 -20.041108) (xy 336.092702 -20.08744) (xy 336.083031 -20.179598)
			(xy 336.063835 -20.270252) (xy 336.035323 -20.358421) (xy 336.017108 -20.401026) (xy 336.013302 -20.410968)
			(xy 336.013302 -20.432232) (xy 336.017108 -20.442174) (xy 336.035353 -20.484836) (xy 336.063897 -20.573129)
			(xy 336.08309 -20.663914) (xy 336.092723 -20.756204) (xy 336.093308 -20.8026) (xy 336.092725 -20.848996)
			(xy 336.08308 -20.941284) (xy 336.063884 -21.032068) (xy 336.035346 -21.120361) (xy 336.017108 -21.163026)
			(xy 336.013302 -21.172968) (xy 336.013302 -21.194232) (xy 336.017108 -21.204174) (xy 336.035353 -21.246836)
			(xy 336.063897 -21.335129) (xy 336.08309 -21.425914) (xy 336.092723 -21.518204) (xy 336.093308 -21.5646)
			(xy 336.092725 -21.610996) (xy 336.08308 -21.703284) (xy 336.063884 -21.794068) (xy 336.035346 -21.882361)
			(xy 336.017108 -21.925026) (xy 336.013302 -21.934968) (xy 336.013302 -21.956232) (xy 336.017108 -21.966174)
			(xy 336.035353 -22.008836) (xy 336.063897 -22.097129) (xy 336.08309 -22.187914) (xy 336.092723 -22.280204)
			(xy 336.093308 -22.3266) (xy 336.092725 -22.372996) (xy 336.08308 -22.465284) (xy 336.063884 -22.556068)
			(xy 336.035346 -22.644361) (xy 336.017108 -22.687026) (xy 336.013302 -22.696968) (xy 336.013302 -22.718232)
			(xy 336.017108 -22.728174) (xy 336.03533 -22.770777) (xy 336.063848 -22.858944) (xy 336.08304 -22.9496)
			(xy 336.0927 -23.04176) (xy 336.093308 -23.088092) (xy 336.093308 -23.0886) (xy 336.092833 -23.129702)
			(xy 336.085248 -23.211557) (xy 336.070143 -23.292362) (xy 336.047647 -23.371429) (xy 336.017951 -23.448083)
			(xy 335.981309 -23.52167) (xy 335.938034 -23.591562) (xy 335.888494 -23.657163) (xy 335.833113 -23.717913)
			(xy 335.772363 -23.773294) (xy 335.706762 -23.822834) (xy 335.63687 -23.866109) (xy 335.563283 -23.902751)
			(xy 335.486629 -23.932447) (xy 335.407562 -23.954943) (xy 335.326757 -23.970048) (xy 335.244902 -23.977633)
			(xy 335.2038 -23.978108) (xy 335.203292 -23.978108) (xy 335.15696 -23.977502) (xy 335.064802 -23.967831)
			(xy 334.974148 -23.948635) (xy 334.885979 -23.920123) (xy 334.843374 -23.901908) (xy 334.833432 -23.898102)
			(xy 334.812168 -23.898102) (xy 334.802226 -23.901908) (xy 334.759564 -23.920153) (xy 334.671271 -23.948697)
			(xy 334.580486 -23.96789) (xy 334.488196 -23.977523) (xy 334.4418 -23.978108) (xy 334.395404 -23.977525)
			(xy 334.303116 -23.96788) (xy 334.212332 -23.948684) (xy 334.124039 -23.920146) (xy 334.081374 -23.901908)
			(xy 334.071432 -23.898102) (xy 334.050168 -23.898102) (xy 334.040226 -23.901908) (xy 333.997564 -23.920153)
			(xy 333.909271 -23.948697) (xy 333.818486 -23.96789) (xy 333.726196 -23.977523) (xy 333.6798 -23.978108)
			(xy 333.633404 -23.977525) (xy 333.541116 -23.96788) (xy 333.450332 -23.948684) (xy 333.362039 -23.920146)
			(xy 333.319374 -23.901908) (xy 333.309432 -23.898102) (xy 333.288168 -23.898102) (xy 333.278226 -23.901908)
			(xy 333.235564 -23.920153) (xy 333.147271 -23.948697) (xy 333.056486 -23.96789) (xy 332.964196 -23.977523)
			(xy 332.9178 -23.978108) (xy 332.871404 -23.977525) (xy 332.779116 -23.96788) (xy 332.688332 -23.948684)
			(xy 332.600039 -23.920146) (xy 332.557374 -23.901908) (xy 332.547432 -23.898102) (xy 332.526168 -23.898102)
			(xy 332.516226 -23.901908) (xy 332.473623 -23.92013) (xy 332.385456 -23.948648) (xy 332.2948 -23.96784)
			(xy 332.20264 -23.9775) (xy 332.156308 -23.978108) (xy 332.1558 -23.978108) (xy 332.114698 -23.977633)
			(xy 332.032843 -23.970048) (xy 331.952038 -23.954943) (xy 331.872971 -23.932447) (xy 331.796317 -23.902751)
			(xy 331.72273 -23.866109) (xy 331.652838 -23.822834) (xy 331.587237 -23.773294) (xy 331.526487 -23.717913)
			(xy 331.471106 -23.657163) (xy 331.421566 -23.591562) (xy 331.378291 -23.52167) (xy 331.341649 -23.448083)
			(xy 331.311953 -23.371429) (xy 331.289457 -23.292362) (xy 331.274352 -23.211557) (xy 331.266767 -23.129702)
			(xy 331.266292 -23.0886) (xy 325.12 -23.0886) (xy 325.12 -28.566561) (xy 334.478626 -28.566561) (xy 334.478626 -28.481839)
			(xy 334.486679 -28.397502) (xy 334.502713 -28.314312) (xy 334.526581 -28.233022) (xy 334.558069 -28.15437)
			(xy 334.596891 -28.079067) (xy 334.642694 -28.007795) (xy 334.695065 -27.941199) (xy 334.75353 -27.879884)
			(xy 334.817558 -27.824403) (xy 334.88657 -27.77526) (xy 334.95994 -27.7329) (xy 335.037005 -27.697705)
			(xy 335.117067 -27.669996) (xy 335.1994 -27.650022) (xy 335.283259 -27.637965) (xy 335.367884 -27.633934)
			(xy 335.452509 -27.637965) (xy 335.536368 -27.650022) (xy 335.618701 -27.669996) (xy 335.698763 -27.697705)
			(xy 335.775828 -27.7329) (xy 335.849198 -27.77526) (xy 335.91821 -27.824403) (xy 335.982238 -27.879884)
			(xy 336.040703 -27.941199) (xy 336.093074 -28.007795) (xy 336.138877 -28.079067) (xy 336.177699 -28.15437)
			(xy 336.209187 -28.233022) (xy 336.233055 -28.314312) (xy 336.249089 -28.397502) (xy 336.257142 -28.481839)
			(xy 336.257646 -28.5242) (xy 336.257142 -28.566561) (xy 336.249089 -28.650898) (xy 336.233055 -28.734088)
			(xy 336.209187 -28.815378) (xy 336.177699 -28.89403) (xy 336.138877 -28.969333) (xy 336.093074 -29.040605)
			(xy 336.040703 -29.107201) (xy 335.982238 -29.168516) (xy 335.91821 -29.223997) (xy 335.849198 -29.27314)
			(xy 335.775828 -29.3155) (xy 335.698763 -29.350695) (xy 335.618701 -29.378404) (xy 335.536368 -29.398378)
			(xy 335.452509 -29.410435) (xy 335.367884 -29.414467) (xy 335.283259 -29.410435) (xy 335.1994 -29.398378)
			(xy 335.117067 -29.378404) (xy 335.037005 -29.350695) (xy 334.95994 -29.3155) (xy 334.88657 -29.27314)
			(xy 334.817558 -29.223997) (xy 334.75353 -29.168516) (xy 334.695065 -29.107201) (xy 334.642694 -29.040605)
			(xy 334.596891 -28.969333) (xy 334.558069 -28.89403) (xy 334.526581 -28.815378) (xy 334.502713 -28.734088)
			(xy 334.486679 -28.650898) (xy 334.478626 -28.566561) (xy 325.12 -28.566561) (xy 325.12 -34.3662)
			(xy 331.266292 -34.3662) (xy 331.266292 -34.365692) (xy 331.266898 -34.31936) (xy 331.276569 -34.227202)
			(xy 331.295765 -34.136548) (xy 331.324277 -34.048379) (xy 331.342492 -34.005774) (xy 331.346298 -33.995832)
			(xy 331.346298 -33.974568) (xy 331.342492 -33.964626) (xy 331.324247 -33.921964) (xy 331.295703 -33.833671)
			(xy 331.27651 -33.742886) (xy 331.266877 -33.650596) (xy 331.266292 -33.6042) (xy 331.266875 -33.557804)
			(xy 331.27652 -33.465516) (xy 331.295716 -33.374732) (xy 331.324254 -33.286439) (xy 331.342492 -33.243774)
			(xy 331.346298 -33.233832) (xy 331.346298 -33.212568) (xy 331.342492 -33.202626) (xy 331.324247 -33.159964)
			(xy 331.295703 -33.071671) (xy 331.27651 -32.980886) (xy 331.266877 -32.888596) (xy 331.266292 -32.8422)
			(xy 331.266875 -32.795804) (xy 331.27652 -32.703516) (xy 331.295716 -32.612732) (xy 331.324254 -32.524439)
			(xy 331.342492 -32.481774) (xy 331.346298 -32.471832) (xy 331.346298 -32.450568) (xy 331.342492 -32.440626)
			(xy 331.324247 -32.397964) (xy 331.295703 -32.309671) (xy 331.27651 -32.218886) (xy 331.266877 -32.126596)
			(xy 331.266292 -32.0802) (xy 331.266875 -32.033804) (xy 331.27652 -31.941516) (xy 331.295716 -31.850732)
			(xy 331.324254 -31.762439) (xy 331.342492 -31.719774) (xy 331.346298 -31.709832) (xy 331.346298 -31.688568)
			(xy 331.342492 -31.678626) (xy 331.32427 -31.636023) (xy 331.295752 -31.547856) (xy 331.27656 -31.4572)
			(xy 331.2669 -31.36504) (xy 331.266292 -31.318708) (xy 331.266292 -31.3182) (xy 331.266767 -31.277098)
			(xy 331.274352 -31.195243) (xy 331.289457 -31.114438) (xy 331.311953 -31.035371) (xy 331.341649 -30.958717)
			(xy 331.378291 -30.88513) (xy 331.421566 -30.815238) (xy 331.471106 -30.749637) (xy 331.526487 -30.688887)
			(xy 331.587237 -30.633506) (xy 331.652838 -30.583966) (xy 331.72273 -30.540691) (xy 331.796317 -30.504049)
			(xy 331.872971 -30.474353) (xy 331.952038 -30.451857) (xy 332.032843 -30.436752) (xy 332.114698 -30.429167)
			(xy 332.1558 -30.428692) (xy 332.156308 -30.428692) (xy 332.20264 -30.429298) (xy 332.294798 -30.438969)
			(xy 332.385452 -30.458165) (xy 332.473621 -30.486677) (xy 332.516226 -30.504892) (xy 332.526168 -30.508698)
			(xy 332.547432 -30.508698) (xy 332.557374 -30.504892) (xy 332.600036 -30.486647) (xy 332.688329 -30.458103)
			(xy 332.779114 -30.43891) (xy 332.871404 -30.429277) (xy 332.9178 -30.428692) (xy 332.964196 -30.429275)
			(xy 333.056484 -30.43892) (xy 333.147268 -30.458116) (xy 333.235561 -30.486654) (xy 333.278226 -30.504892)
			(xy 333.288168 -30.508698) (xy 333.309432 -30.508698) (xy 333.319374 -30.504892) (xy 333.362036 -30.486647)
			(xy 333.450329 -30.458103) (xy 333.541114 -30.43891) (xy 333.633404 -30.429277) (xy 333.6798 -30.428692)
			(xy 333.726196 -30.429275) (xy 333.818484 -30.43892) (xy 333.909268 -30.458116) (xy 333.997561 -30.486654)
			(xy 334.040226 -30.504892) (xy 334.050168 -30.508698) (xy 334.071432 -30.508698) (xy 334.081374 -30.504892)
			(xy 334.124036 -30.486647) (xy 334.212329 -30.458103) (xy 334.303114 -30.43891) (xy 334.395404 -30.429277)
			(xy 334.4418 -30.428692) (xy 334.488196 -30.429275) (xy 334.580484 -30.43892) (xy 334.671268 -30.458116)
			(xy 334.759561 -30.486654) (xy 334.802226 -30.504892) (xy 334.812168 -30.508698) (xy 334.833432 -30.508698)
			(xy 334.843374 -30.504892) (xy 334.885977 -30.48667) (xy 334.974144 -30.458152) (xy 335.0648 -30.43896)
			(xy 335.15696 -30.4293) (xy 335.203292 -30.428692) (xy 335.2038 -30.428692) (xy 335.244902 -30.429167)
			(xy 335.326757 -30.436752) (xy 335.407562 -30.451857) (xy 335.486629 -30.474353) (xy 335.563283 -30.504049)
			(xy 335.63687 -30.540691) (xy 335.706762 -30.583966) (xy 335.772363 -30.633506) (xy 335.833113 -30.688887)
			(xy 335.888494 -30.749637) (xy 335.938034 -30.815238) (xy 335.981309 -30.88513) (xy 336.017951 -30.958717)
			(xy 336.047647 -31.035371) (xy 336.070143 -31.114438) (xy 336.085248 -31.195243) (xy 336.092833 -31.277098)
			(xy 336.093308 -31.3182) (xy 336.093308 -31.318708) (xy 336.092702 -31.36504) (xy 336.083031 -31.457198)
			(xy 336.063835 -31.547852) (xy 336.035323 -31.636021) (xy 336.017108 -31.678626) (xy 336.013302 -31.688568)
			(xy 336.013302 -31.709832) (xy 336.017108 -31.719774) (xy 336.035353 -31.762436) (xy 336.063897 -31.850729)
			(xy 336.08309 -31.941514) (xy 336.092723 -32.033804) (xy 336.093308 -32.0802) (xy 336.092725 -32.126596)
			(xy 336.08308 -32.218884) (xy 336.063884 -32.309668) (xy 336.035346 -32.397961) (xy 336.017108 -32.440626)
			(xy 336.013302 -32.450568) (xy 336.013302 -32.471832) (xy 336.017108 -32.481774) (xy 336.035353 -32.524436)
			(xy 336.063897 -32.612729) (xy 336.08309 -32.703514) (xy 336.092723 -32.795804) (xy 336.093308 -32.8422)
			(xy 336.092725 -32.888596) (xy 336.08308 -32.980884) (xy 336.063884 -33.071668) (xy 336.035346 -33.159961)
			(xy 336.017108 -33.202626) (xy 336.013302 -33.212568) (xy 336.013302 -33.233832) (xy 336.017108 -33.243774)
			(xy 336.035353 -33.286436) (xy 336.063897 -33.374729) (xy 336.08309 -33.465514) (xy 336.092723 -33.557804)
			(xy 336.093308 -33.6042) (xy 336.092725 -33.650596) (xy 336.08308 -33.742884) (xy 336.063884 -33.833668)
			(xy 336.035346 -33.921961) (xy 336.017108 -33.964626) (xy 336.013302 -33.974568) (xy 336.013302 -33.995832)
			(xy 336.017108 -34.005774) (xy 336.03533 -34.048377) (xy 336.063848 -34.136544) (xy 336.08304 -34.2272)
			(xy 336.0927 -34.31936) (xy 336.093308 -34.365692) (xy 336.093308 -34.3662) (xy 336.092833 -34.407302)
			(xy 336.085248 -34.489157) (xy 336.070143 -34.569962) (xy 336.047647 -34.649029) (xy 336.017951 -34.725683)
			(xy 335.981309 -34.79927) (xy 335.938034 -34.869162) (xy 335.888494 -34.934763) (xy 335.833113 -34.995513)
			(xy 335.772363 -35.050894) (xy 335.706762 -35.100434) (xy 335.63687 -35.143709) (xy 335.563283 -35.180351)
			(xy 335.486629 -35.210047) (xy 335.407562 -35.232543) (xy 335.326757 -35.247648) (xy 335.244902 -35.255233)
			(xy 335.2038 -35.255708) (xy 335.203292 -35.255708) (xy 335.15696 -35.255102) (xy 335.064802 -35.245431)
			(xy 334.974148 -35.226235) (xy 334.885979 -35.197723) (xy 334.843374 -35.179508) (xy 334.833432 -35.175702)
			(xy 334.812168 -35.175702) (xy 334.802226 -35.179508) (xy 334.759564 -35.197753) (xy 334.671271 -35.226297)
			(xy 334.580486 -35.24549) (xy 334.488196 -35.255123) (xy 334.4418 -35.255708) (xy 334.395404 -35.255125)
			(xy 334.303116 -35.24548) (xy 334.212332 -35.226284) (xy 334.124039 -35.197746) (xy 334.081374 -35.179508)
			(xy 334.071432 -35.175702) (xy 334.050168 -35.175702) (xy 334.040226 -35.179508) (xy 333.997564 -35.197753)
			(xy 333.909271 -35.226297) (xy 333.818486 -35.24549) (xy 333.726196 -35.255123) (xy 333.6798 -35.255708)
			(xy 333.633404 -35.255125) (xy 333.541116 -35.24548) (xy 333.450332 -35.226284) (xy 333.362039 -35.197746)
			(xy 333.319374 -35.179508) (xy 333.309432 -35.175702) (xy 333.288168 -35.175702) (xy 333.278226 -35.179508)
			(xy 333.235564 -35.197753) (xy 333.147271 -35.226297) (xy 333.056486 -35.24549) (xy 332.964196 -35.255123)
			(xy 332.9178 -35.255708) (xy 332.871404 -35.255125) (xy 332.779116 -35.24548) (xy 332.688332 -35.226284)
			(xy 332.600039 -35.197746) (xy 332.557374 -35.179508) (xy 332.547432 -35.175702) (xy 332.526168 -35.175702)
			(xy 332.516226 -35.179508) (xy 332.473623 -35.19773) (xy 332.385456 -35.226248) (xy 332.2948 -35.24544)
			(xy 332.20264 -35.2551) (xy 332.156308 -35.255708) (xy 332.1558 -35.255708) (xy 332.114698 -35.255233)
			(xy 332.032843 -35.247648) (xy 331.952038 -35.232543) (xy 331.872971 -35.210047) (xy 331.796317 -35.180351)
			(xy 331.72273 -35.143709) (xy 331.652838 -35.100434) (xy 331.587237 -35.050894) (xy 331.526487 -34.995513)
			(xy 331.471106 -34.934763) (xy 331.421566 -34.869162) (xy 331.378291 -34.79927) (xy 331.341649 -34.725683)
			(xy 331.311953 -34.649029) (xy 331.289457 -34.569962) (xy 331.274352 -34.489157) (xy 331.266767 -34.407302)
			(xy 331.266292 -34.3662) (xy 325.12 -34.3662) (xy 325.12 -37.289429) (xy 337.982302 -37.289429) (xy 337.982302 -37.204707)
			(xy 337.990355 -37.12037) (xy 338.006389 -37.03718) (xy 338.030257 -36.95589) (xy 338.061745 -36.877238)
			(xy 338.100567 -36.801935) (xy 338.14637 -36.730663) (xy 338.198741 -36.664067) (xy 338.257206 -36.602752)
			(xy 338.321234 -36.547271) (xy 338.390246 -36.498128) (xy 338.463616 -36.455768) (xy 338.540681 -36.420573)
			(xy 338.620743 -36.392864) (xy 338.703076 -36.37289) (xy 338.786935 -36.360833) (xy 338.87156 -36.356802)
			(xy 338.956185 -36.360833) (xy 339.040044 -36.37289) (xy 339.122377 -36.392864) (xy 339.202439 -36.420573)
			(xy 339.279504 -36.455768) (xy 339.352874 -36.498128) (xy 339.421886 -36.547271) (xy 339.485914 -36.602752)
			(xy 339.544379 -36.664067) (xy 339.59675 -36.730663) (xy 339.642553 -36.801935) (xy 339.681375 -36.877238)
			(xy 339.712863 -36.95589) (xy 339.736731 -37.03718) (xy 339.752765 -37.12037) (xy 339.760818 -37.204707)
			(xy 339.761322 -37.247068) (xy 339.760818 -37.289429) (xy 339.752765 -37.373766) (xy 339.736731 -37.456956)
			(xy 339.712863 -37.538246) (xy 339.681375 -37.616898) (xy 339.642553 -37.692201) (xy 339.59675 -37.763473)
			(xy 339.544379 -37.830069) (xy 339.485914 -37.891384) (xy 339.421886 -37.946865) (xy 339.352874 -37.996008)
			(xy 339.279504 -38.038368) (xy 339.202439 -38.073563) (xy 339.122377 -38.101272) (xy 339.040044 -38.121246)
			(xy 338.956185 -38.133303) (xy 338.87156 -38.137335) (xy 338.786935 -38.133303) (xy 338.703076 -38.121246)
			(xy 338.620743 -38.101272) (xy 338.540681 -38.073563) (xy 338.463616 -38.038368) (xy 338.390246 -37.996008)
			(xy 338.321234 -37.946865) (xy 338.257206 -37.891384) (xy 338.198741 -37.830069) (xy 338.14637 -37.763473)
			(xy 338.100567 -37.692201) (xy 338.061745 -37.616898) (xy 338.030257 -37.538246) (xy 338.006389 -37.456956)
			(xy 337.990355 -37.373766) (xy 337.982302 -37.289429) (xy 325.12 -37.289429) (xy 325.12 -39.787831)
			(xy 334.477997 -39.787831) (xy 334.483261 -39.704146) (xy 334.496377 -39.621328) (xy 334.517229 -39.540112)
			(xy 334.545631 -39.461218) (xy 334.581332 -39.385348) (xy 334.624014 -39.313173) (xy 334.673299 -39.245336)
			(xy 334.728749 -39.182438) (xy 334.789873 -39.125038) (xy 334.856127 -39.073645) (xy 334.926923 -39.028714)
			(xy 335.001634 -38.990646) (xy 335.079595 -38.959777) (xy 335.160116 -38.936382) (xy 335.242481 -38.920669)
			(xy 335.325959 -38.912776) (xy 335.367884 -38.912292) (xy 335.368392 -38.912292) (xy 335.404819 -38.912666)
			(xy 335.477428 -38.918641) (xy 335.513426 -38.92423) (xy 335.528472 -38.926165) (xy 335.558521 -38.922119)
			(xy 335.586063 -38.909441) (xy 335.608678 -38.889246) (xy 335.624379 -38.863308) (xy 335.631785 -38.833906)
			(xy 335.630246 -38.803626) (xy 335.619897 -38.775127) (xy 335.611216 -38.762686) (xy 335.586864 -38.729613)
			(xy 335.543671 -38.659752) (xy 335.507099 -38.586206) (xy 335.477461 -38.509604) (xy 335.455009 -38.430596)
			(xy 335.439934 -38.349855) (xy 335.432365 -38.268068) (xy 335.431892 -38.227) (xy 335.432376 -38.185075)
			(xy 335.440267 -38.101596) (xy 335.455979 -38.019231) (xy 335.479372 -37.938709) (xy 335.51024 -37.860747)
			(xy 335.548307 -37.786036) (xy 335.593237 -37.715238) (xy 335.644629 -37.648983) (xy 335.702029 -37.587859)
			(xy 335.764926 -37.532407) (xy 335.832763 -37.483121) (xy 335.904937 -37.440438) (xy 335.980807 -37.404736)
			(xy 336.0597 -37.376332) (xy 336.140917 -37.355479) (xy 336.223735 -37.342362) (xy 336.30742 -37.337097)
			(xy 336.39123 -37.339731) (xy 336.474419 -37.35024) (xy 336.55625 -37.368532) (xy 336.635997 -37.394443)
			(xy 336.712951 -37.427744) (xy 336.78643 -37.46814) (xy 336.855782 -37.515271) (xy 336.92039 -37.568719)
			(xy 336.979681 -37.62801) (xy 337.033129 -37.692618) (xy 337.08026 -37.76197) (xy 337.120656 -37.835449)
			(xy 337.153957 -37.912403) (xy 337.179868 -37.99215) (xy 337.19816 -38.073981) (xy 337.208669 -38.15717)
			(xy 337.211303 -38.24098) (xy 337.206038 -38.324665) (xy 337.192921 -38.407483) (xy 337.172068 -38.4887)
			(xy 337.143664 -38.567593) (xy 337.107962 -38.643463) (xy 337.065279 -38.715637) (xy 337.015993 -38.783474)
			(xy 336.960541 -38.846371) (xy 336.899417 -38.903771) (xy 336.833162 -38.955163) (xy 336.762364 -39.000093)
			(xy 336.687653 -39.03816) (xy 336.609691 -39.069028) (xy 336.529169 -39.092421) (xy 336.446804 -39.108133)
			(xy 336.363325 -39.116024) (xy 336.3214 -39.116508) (xy 336.320892 -39.116508) (xy 336.284465 -39.116136)
			(xy 336.211856 -39.110159) (xy 336.175858 -39.10457) (xy 336.160814 -39.102622) (xy 336.130765 -39.106672)
			(xy 336.103223 -39.119352) (xy 336.080609 -39.139549) (xy 336.064909 -39.165489) (xy 336.057502 -39.194891)
			(xy 336.05904 -39.225172) (xy 336.069388 -39.253672) (xy 336.078068 -39.266114) (xy 336.102418 -39.299188)
			(xy 336.145612 -39.36905) (xy 336.182184 -39.442594) (xy 336.211822 -39.519197) (xy 336.234274 -39.598205)
			(xy 336.249349 -39.678945) (xy 336.256919 -39.760732) (xy 336.257392 -39.8018) (xy 336.256924 -39.843725)
			(xy 336.249033 -39.927203) (xy 336.233322 -40.009569) (xy 336.209928 -40.090089) (xy 336.179061 -40.168052)
			(xy 336.140994 -40.242763) (xy 336.096065 -40.31356) (xy 336.044672 -40.379815) (xy 335.987273 -40.440939)
			(xy 335.924376 -40.496391) (xy 335.85654 -40.545677) (xy 335.784367 -40.588361) (xy 335.708497 -40.624063)
			(xy 335.629604 -40.652466) (xy 335.548388 -40.67332) (xy 335.46557 -40.686437) (xy 335.381885 -40.691703)
			(xy 335.298076 -40.689069) (xy 335.214887 -40.678561) (xy 335.133056 -40.66027) (xy 335.053309 -40.634359)
			(xy 334.976355 -40.601059) (xy 334.902876 -40.560664) (xy 334.833525 -40.513534) (xy 334.768916 -40.460086)
			(xy 334.709625 -40.400796) (xy 334.656176 -40.336188) (xy 334.609044 -40.266838) (xy 334.568648 -40.19336)
			(xy 334.535346 -40.116406) (xy 334.509434 -40.03666) (xy 334.491142 -39.954829) (xy 334.480632 -39.87164)
			(xy 334.477997 -39.787831) (xy 325.12 -39.787831) (xy 325.12 -45.6438) (xy 331.266292 -45.6438) (xy 331.266292 -45.643292)
			(xy 331.266898 -45.59696) (xy 331.276569 -45.504802) (xy 331.295765 -45.414148) (xy 331.324277 -45.325979)
			(xy 331.342492 -45.283374) (xy 331.346298 -45.273432) (xy 331.346298 -45.252168) (xy 331.342492 -45.242226)
			(xy 331.324247 -45.199564) (xy 331.295703 -45.111271) (xy 331.27651 -45.020486) (xy 331.266877 -44.928196)
			(xy 331.266292 -44.8818) (xy 331.266875 -44.835404) (xy 331.27652 -44.743116) (xy 331.295716 -44.652332)
			(xy 331.324254 -44.564039) (xy 331.342492 -44.521374) (xy 331.346298 -44.511432) (xy 331.346298 -44.490168)
			(xy 331.342492 -44.480226) (xy 331.324247 -44.437564) (xy 331.295703 -44.349271) (xy 331.27651 -44.258486)
			(xy 331.266877 -44.166196) (xy 331.266292 -44.1198) (xy 331.266875 -44.073404) (xy 331.27652 -43.981116)
			(xy 331.295716 -43.890332) (xy 331.324254 -43.802039) (xy 331.342492 -43.759374) (xy 331.346298 -43.749432)
			(xy 331.346298 -43.728168) (xy 331.342492 -43.718226) (xy 331.324247 -43.675564) (xy 331.295703 -43.587271)
			(xy 331.27651 -43.496486) (xy 331.266877 -43.404196) (xy 331.266292 -43.3578) (xy 331.266875 -43.311404)
			(xy 331.27652 -43.219116) (xy 331.295716 -43.128332) (xy 331.324254 -43.040039) (xy 331.342492 -42.997374)
			(xy 331.346298 -42.987432) (xy 331.346298 -42.966168) (xy 331.342492 -42.956226) (xy 331.32427 -42.913623)
			(xy 331.295752 -42.825456) (xy 331.27656 -42.7348) (xy 331.2669 -42.64264) (xy 331.266292 -42.596308)
			(xy 331.266292 -42.5958) (xy 331.266767 -42.554698) (xy 331.274352 -42.472843) (xy 331.289457 -42.392038)
			(xy 331.311953 -42.312971) (xy 331.341649 -42.236317) (xy 331.378291 -42.16273) (xy 331.421566 -42.092838)
			(xy 331.471106 -42.027237) (xy 331.526487 -41.966487) (xy 331.587237 -41.911106) (xy 331.652838 -41.861566)
			(xy 331.72273 -41.818291) (xy 331.796317 -41.781649) (xy 331.872971 -41.751953) (xy 331.952038 -41.729457)
			(xy 332.032843 -41.714352) (xy 332.114698 -41.706767) (xy 332.1558 -41.706292) (xy 332.156308 -41.706292)
			(xy 332.20264 -41.706898) (xy 332.294798 -41.716569) (xy 332.385452 -41.735765) (xy 332.473621 -41.764277)
			(xy 332.516226 -41.782492) (xy 332.526168 -41.786298) (xy 332.547432 -41.786298) (xy 332.557374 -41.782492)
			(xy 332.600036 -41.764247) (xy 332.688329 -41.735703) (xy 332.779114 -41.71651) (xy 332.871404 -41.706877)
			(xy 332.9178 -41.706292) (xy 332.964196 -41.706875) (xy 333.056484 -41.71652) (xy 333.147268 -41.735716)
			(xy 333.235561 -41.764254) (xy 333.278226 -41.782492) (xy 333.288168 -41.786298) (xy 333.309432 -41.786298)
			(xy 333.319374 -41.782492) (xy 333.362036 -41.764247) (xy 333.450329 -41.735703) (xy 333.541114 -41.71651)
			(xy 333.633404 -41.706877) (xy 333.6798 -41.706292) (xy 333.726196 -41.706875) (xy 333.818484 -41.71652)
			(xy 333.909268 -41.735716) (xy 333.997561 -41.764254) (xy 334.040226 -41.782492) (xy 334.050168 -41.786298)
			(xy 334.071432 -41.786298) (xy 334.081374 -41.782492) (xy 334.124036 -41.764247) (xy 334.212329 -41.735703)
			(xy 334.303114 -41.71651) (xy 334.395404 -41.706877) (xy 334.4418 -41.706292) (xy 334.488196 -41.706875)
			(xy 334.580484 -41.71652) (xy 334.671268 -41.735716) (xy 334.759561 -41.764254) (xy 334.802226 -41.782492)
			(xy 334.812168 -41.786298) (xy 334.833432 -41.786298) (xy 334.843374 -41.782492) (xy 334.885977 -41.76427)
			(xy 334.974144 -41.735752) (xy 335.0648 -41.71656) (xy 335.15696 -41.7069) (xy 335.203292 -41.706292)
			(xy 335.2038 -41.706292) (xy 335.244902 -41.706767) (xy 335.326757 -41.714352) (xy 335.407562 -41.729457)
			(xy 335.486629 -41.751953) (xy 335.563283 -41.781649) (xy 335.63687 -41.818291) (xy 335.706762 -41.861566)
			(xy 335.772363 -41.911106) (xy 335.833113 -41.966487) (xy 335.888494 -42.027237) (xy 335.938034 -42.092838)
			(xy 335.981309 -42.16273) (xy 336.017951 -42.236317) (xy 336.047647 -42.312971) (xy 336.070143 -42.392038)
			(xy 336.085248 -42.472843) (xy 336.092833 -42.554698) (xy 336.093308 -42.5958) (xy 336.093308 -42.596308)
			(xy 336.092702 -42.64264) (xy 336.083031 -42.734798) (xy 336.063835 -42.825452) (xy 336.035323 -42.913621)
			(xy 336.017108 -42.956226) (xy 336.013302 -42.966168) (xy 336.013302 -42.987432) (xy 336.017108 -42.997374)
			(xy 336.035353 -43.040036) (xy 336.063897 -43.128329) (xy 336.08309 -43.219114) (xy 336.092723 -43.311404)
			(xy 336.093308 -43.3578) (xy 336.092725 -43.404196) (xy 336.08308 -43.496484) (xy 336.063884 -43.587268)
			(xy 336.035346 -43.675561) (xy 336.017108 -43.718226) (xy 336.013302 -43.728168) (xy 336.013302 -43.749432)
			(xy 336.017108 -43.759374) (xy 336.035353 -43.802036) (xy 336.063897 -43.890329) (xy 336.08309 -43.981114)
			(xy 336.092723 -44.073404) (xy 336.093308 -44.1198) (xy 336.092725 -44.166196) (xy 336.08308 -44.258484)
			(xy 336.063884 -44.349268) (xy 336.035346 -44.437561) (xy 336.017108 -44.480226) (xy 336.013302 -44.490168)
			(xy 336.013302 -44.511432) (xy 336.017108 -44.521374) (xy 336.03533 -44.563977) (xy 336.063848 -44.652144)
			(xy 336.08304 -44.7428) (xy 336.0927 -44.83496) (xy 336.093308 -44.881292) (xy 336.093308 -44.8818)
			(xy 336.092833 -44.922902) (xy 336.085248 -45.004757) (xy 336.070143 -45.085562) (xy 336.047647 -45.164629)
			(xy 336.017951 -45.241283) (xy 335.981309 -45.31487) (xy 335.938034 -45.384762) (xy 335.888494 -45.450363)
			(xy 335.833113 -45.511113) (xy 335.772363 -45.566494) (xy 335.706762 -45.616034) (xy 335.63687 -45.659309)
			(xy 335.563283 -45.695951) (xy 335.486629 -45.725647) (xy 335.407562 -45.748143) (xy 335.326757 -45.763248)
			(xy 335.244902 -45.770833) (xy 335.2038 -45.771308) (xy 335.203292 -45.771308) (xy 335.15696 -45.770702)
			(xy 335.064802 -45.761031) (xy 334.974148 -45.741835) (xy 334.885979 -45.713323) (xy 334.843374 -45.695108)
			(xy 334.833432 -45.691302) (xy 334.812168 -45.691302) (xy 334.802226 -45.695108) (xy 334.769307 -45.709337)
			(xy 334.701622 -45.733057) (xy 334.632242 -45.751237) (xy 334.596994 -45.757846) (xy 334.58687 -45.760144)
			(xy 334.569549 -45.771549) (xy 334.558144 -45.78887) (xy 334.555846 -45.798994) (xy 334.548139 -45.839659)
			(xy 334.526175 -45.919465) (xy 334.496893 -45.996885) (xy 334.460547 -46.071251) (xy 334.417451 -46.14192)
			(xy 334.367977 -46.20828) (xy 334.312554 -46.269759) (xy 334.251659 -46.325823) (xy 334.185821 -46.375989)
			(xy 334.115608 -46.419824) (xy 334.041627 -46.456947) (xy 333.964517 -46.487038) (xy 333.884946 -46.509837)
			(xy 333.803601 -46.525147) (xy 333.721186 -46.532835) (xy 333.6798 -46.533308) (xy 333.679292 -46.533308)
			(xy 333.63296 -46.532702) (xy 333.540802 -46.523031) (xy 333.450148 -46.503835) (xy 333.361979 -46.475323)
			(xy 333.319374 -46.457108) (xy 333.309432 -46.453302) (xy 333.288168 -46.453302) (xy 333.278226 -46.457108)
			(xy 333.235564 -46.475353) (xy 333.147271 -46.503897) (xy 333.056486 -46.52309) (xy 332.964196 -46.532723)
			(xy 332.9178 -46.533308) (xy 332.871404 -46.532725) (xy 332.779116 -46.52308) (xy 332.688332 -46.503884)
			(xy 332.600039 -46.475346) (xy 332.557374 -46.457108) (xy 332.547432 -46.453302) (xy 332.526168 -46.453302)
			(xy 332.516226 -46.457108) (xy 332.473623 -46.47533) (xy 332.385456 -46.503848) (xy 332.2948 -46.52304)
			(xy 332.20264 -46.5327) (xy 332.156308 -46.533308) (xy 332.1558 -46.533308) (xy 332.114698 -46.532833)
			(xy 332.032843 -46.525248) (xy 331.952038 -46.510143) (xy 331.872971 -46.487647) (xy 331.796317 -46.457951)
			(xy 331.72273 -46.421309) (xy 331.652838 -46.378034) (xy 331.587237 -46.328494) (xy 331.526487 -46.273113)
			(xy 331.471106 -46.212363) (xy 331.421566 -46.146762) (xy 331.378291 -46.07687) (xy 331.341649 -46.003283)
			(xy 331.311953 -45.926629) (xy 331.289457 -45.847562) (xy 331.274352 -45.766757) (xy 331.266767 -45.684902)
			(xy 331.266292 -45.6438) (xy 325.12 -45.6438) (xy 325.12 -48.465937) (xy 337.609176 -48.465937) (xy 337.609176 -48.381215)
			(xy 337.617229 -48.296878) (xy 337.633263 -48.213688) (xy 337.657131 -48.132398) (xy 337.688619 -48.053746)
			(xy 337.727441 -47.978443) (xy 337.773244 -47.907171) (xy 337.825615 -47.840575) (xy 337.88408 -47.77926)
			(xy 337.948108 -47.723779) (xy 338.01712 -47.674636) (xy 338.09049 -47.632276) (xy 338.167555 -47.597081)
			(xy 338.247617 -47.569372) (xy 338.32995 -47.549398) (xy 338.413809 -47.537341) (xy 338.498434 -47.53331)
			(xy 338.583059 -47.537341) (xy 338.666918 -47.549398) (xy 338.749251 -47.569372) (xy 338.829313 -47.597081)
			(xy 338.906378 -47.632276) (xy 338.979748 -47.674636) (xy 339.04876 -47.723779) (xy 339.112788 -47.77926)
			(xy 339.171253 -47.840575) (xy 339.223624 -47.907171) (xy 339.269427 -47.978443) (xy 339.308249 -48.053746)
			(xy 339.339737 -48.132398) (xy 339.363605 -48.213688) (xy 339.379639 -48.296878) (xy 339.387692 -48.381215)
			(xy 339.388196 -48.423576) (xy 339.387692 -48.465937) (xy 339.379639 -48.550274) (xy 339.363605 -48.633464)
			(xy 339.339737 -48.714754) (xy 339.308249 -48.793406) (xy 339.269427 -48.868709) (xy 339.223624 -48.939981)
			(xy 339.171253 -49.006577) (xy 339.112788 -49.067892) (xy 339.04876 -49.123373) (xy 338.979748 -49.172516)
			(xy 338.906378 -49.214876) (xy 338.829313 -49.250071) (xy 338.749251 -49.27778) (xy 338.666918 -49.297754)
			(xy 338.583059 -49.309811) (xy 338.498434 -49.313843) (xy 338.413809 -49.309811) (xy 338.32995 -49.297754)
			(xy 338.247617 -49.27778) (xy 338.167555 -49.250071) (xy 338.09049 -49.214876) (xy 338.01712 -49.172516)
			(xy 337.948108 -49.123373) (xy 337.88408 -49.067892) (xy 337.825615 -49.006577) (xy 337.773244 -48.939981)
			(xy 337.727441 -48.868709) (xy 337.688619 -48.793406) (xy 337.657131 -48.714754) (xy 337.633263 -48.633464)
			(xy 337.617229 -48.550274) (xy 337.609176 -48.465937) (xy 325.12 -48.465937) (xy 325.12 -51.065431)
			(xy 334.477997 -51.065431) (xy 334.483261 -50.981746) (xy 334.496377 -50.898928) (xy 334.517229 -50.817712)
			(xy 334.545631 -50.738818) (xy 334.581332 -50.662948) (xy 334.624014 -50.590773) (xy 334.673299 -50.522936)
			(xy 334.728749 -50.460038) (xy 334.789873 -50.402638) (xy 334.856127 -50.351245) (xy 334.926923 -50.306314)
			(xy 335.001634 -50.268246) (xy 335.079595 -50.237377) (xy 335.160116 -50.213982) (xy 335.242481 -50.198269)
			(xy 335.325959 -50.190376) (xy 335.367884 -50.189892) (xy 335.368392 -50.189892) (xy 335.404819 -50.190266)
			(xy 335.477428 -50.196241) (xy 335.513426 -50.20183) (xy 335.528472 -50.203765) (xy 335.558521 -50.199719)
			(xy 335.586063 -50.187041) (xy 335.608678 -50.166846) (xy 335.624379 -50.140908) (xy 335.631785 -50.111506)
			(xy 335.630246 -50.081226) (xy 335.619897 -50.052727) (xy 335.611216 -50.040286) (xy 335.586864 -50.007213)
			(xy 335.543671 -49.937352) (xy 335.507099 -49.863806) (xy 335.477461 -49.787204) (xy 335.455009 -49.708196)
			(xy 335.439934 -49.627455) (xy 335.432365 -49.545668) (xy 335.431892 -49.5046) (xy 335.432376 -49.462675)
			(xy 335.440267 -49.379196) (xy 335.455979 -49.296831) (xy 335.479372 -49.216309) (xy 335.51024 -49.138347)
			(xy 335.548307 -49.063636) (xy 335.593237 -48.992838) (xy 335.644629 -48.926583) (xy 335.702029 -48.865459)
			(xy 335.764926 -48.810007) (xy 335.832763 -48.760721) (xy 335.904937 -48.718038) (xy 335.980807 -48.682336)
			(xy 336.0597 -48.653932) (xy 336.140917 -48.633079) (xy 336.223735 -48.619962) (xy 336.30742 -48.614697)
			(xy 336.39123 -48.617331) (xy 336.474419 -48.62784) (xy 336.55625 -48.646132) (xy 336.635997 -48.672043)
			(xy 336.712951 -48.705344) (xy 336.78643 -48.74574) (xy 336.855782 -48.792871) (xy 336.92039 -48.846319)
			(xy 336.979681 -48.90561) (xy 337.033129 -48.970218) (xy 337.08026 -49.03957) (xy 337.120656 -49.113049)
			(xy 337.153957 -49.190003) (xy 337.179868 -49.26975) (xy 337.19816 -49.351581) (xy 337.208669 -49.43477)
			(xy 337.211303 -49.51858) (xy 337.206038 -49.602265) (xy 337.192921 -49.685083) (xy 337.172068 -49.7663)
			(xy 337.143664 -49.845193) (xy 337.107962 -49.921063) (xy 337.065279 -49.993237) (xy 337.015993 -50.061074)
			(xy 336.960541 -50.123971) (xy 336.899417 -50.181371) (xy 336.833162 -50.232763) (xy 336.762364 -50.277693)
			(xy 336.687653 -50.31576) (xy 336.609691 -50.346628) (xy 336.529169 -50.370021) (xy 336.446804 -50.385733)
			(xy 336.363325 -50.393624) (xy 336.3214 -50.394108) (xy 336.320892 -50.394108) (xy 336.284465 -50.393736)
			(xy 336.211856 -50.387759) (xy 336.175858 -50.38217) (xy 336.160814 -50.380222) (xy 336.130765 -50.384272)
			(xy 336.103223 -50.396952) (xy 336.080609 -50.417149) (xy 336.064909 -50.443089) (xy 336.057502 -50.472491)
			(xy 336.05904 -50.502772) (xy 336.069388 -50.531272) (xy 336.078068 -50.543714) (xy 336.102418 -50.576788)
			(xy 336.145612 -50.64665) (xy 336.182184 -50.720194) (xy 336.211822 -50.796797) (xy 336.234274 -50.875805)
			(xy 336.242505 -50.919888) (xy 377.061232 -50.919888) (xy 377.065214 -50.829938) (xy 377.077131 -50.740691)
			(xy 377.096889 -50.652847) (xy 377.124333 -50.567093) (xy 377.159249 -50.4841) (xy 377.201363 -50.404518)
			(xy 377.250346 -50.328969) (xy 377.305814 -50.258045) (xy 377.367334 -50.1923) (xy 377.434423 -50.13225)
			(xy 377.506557 -50.078365) (xy 377.583171 -50.031065) (xy 377.663665 -49.990722) (xy 377.74741 -49.95765)
			(xy 377.833751 -49.93211) (xy 377.92201 -49.9143) (xy 378.011499 -49.90436) (xy 378.101515 -49.902369)
			(xy 378.191356 -49.90834) (xy 378.280317 -49.922229) (xy 378.367702 -49.943925) (xy 378.452828 -49.97326)
			(xy 378.535028 -50.010003) (xy 378.613659 -50.053867) (xy 378.688106 -50.104509) (xy 378.757786 -50.161533)
			(xy 378.822153 -50.224492) (xy 378.880704 -50.292893) (xy 378.932981 -50.366201) (xy 378.978574 -50.443843)
			(xy 379.017127 -50.52521) (xy 379.048338 -50.609666) (xy 379.071962 -50.69655) (xy 379.087815 -50.785182)
			(xy 379.095772 -50.874869) (xy 379.09627 -50.919888) (xy 396.619232 -50.919888) (xy 396.623214 -50.829938)
			(xy 396.635131 -50.740691) (xy 396.654889 -50.652847) (xy 396.682333 -50.567093) (xy 396.717249 -50.4841)
			(xy 396.759363 -50.404518) (xy 396.808346 -50.328969) (xy 396.863814 -50.258045) (xy 396.925334 -50.1923)
			(xy 396.992423 -50.13225) (xy 397.064557 -50.078365) (xy 397.141171 -50.031065) (xy 397.221665 -49.990722)
			(xy 397.30541 -49.95765) (xy 397.391751 -49.93211) (xy 397.48001 -49.9143) (xy 397.569499 -49.90436)
			(xy 397.659515 -49.902369) (xy 397.749356 -49.90834) (xy 397.838317 -49.922229) (xy 397.925702 -49.943925)
			(xy 398.010828 -49.97326) (xy 398.093028 -50.010003) (xy 398.171659 -50.053867) (xy 398.246106 -50.104509)
			(xy 398.315786 -50.161533) (xy 398.380153 -50.224492) (xy 398.438704 -50.292893) (xy 398.490981 -50.366201)
			(xy 398.536574 -50.443843) (xy 398.575127 -50.52521) (xy 398.606338 -50.609666) (xy 398.629962 -50.69655)
			(xy 398.645815 -50.785182) (xy 398.653772 -50.874869) (xy 398.65427 -50.919888) (xy 398.653772 -50.964907)
			(xy 398.645815 -51.054594) (xy 398.629962 -51.143226) (xy 398.606338 -51.23011) (xy 398.575127 -51.314566)
			(xy 398.536574 -51.395933) (xy 398.490981 -51.473575) (xy 398.438704 -51.546883) (xy 398.380153 -51.615284)
			(xy 398.315786 -51.678243) (xy 398.246106 -51.735267) (xy 398.171659 -51.785909) (xy 398.093028 -51.829773)
			(xy 398.010828 -51.866516) (xy 397.925702 -51.895851) (xy 397.838317 -51.917547) (xy 397.749356 -51.931436)
			(xy 397.659515 -51.937407) (xy 397.569499 -51.935416) (xy 397.48001 -51.925476) (xy 397.391751 -51.907666)
			(xy 397.30541 -51.882126) (xy 397.221665 -51.849054) (xy 397.141171 -51.808711) (xy 397.064557 -51.761411)
			(xy 396.992423 -51.707526) (xy 396.925334 -51.647476) (xy 396.863814 -51.581731) (xy 396.808346 -51.510807)
			(xy 396.759363 -51.435258) (xy 396.717249 -51.355676) (xy 396.682333 -51.272683) (xy 396.654889 -51.186929)
			(xy 396.635131 -51.099085) (xy 396.623214 -51.009838) (xy 396.619232 -50.919888) (xy 379.09627 -50.919888)
			(xy 379.095772 -50.964907) (xy 379.087815 -51.054594) (xy 379.071962 -51.143226) (xy 379.048338 -51.23011)
			(xy 379.017127 -51.314566) (xy 378.978574 -51.395933) (xy 378.932981 -51.473575) (xy 378.880704 -51.546883)
			(xy 378.822153 -51.615284) (xy 378.757786 -51.678243) (xy 378.688106 -51.735267) (xy 378.613659 -51.785909)
			(xy 378.535028 -51.829773) (xy 378.452828 -51.866516) (xy 378.367702 -51.895851) (xy 378.280317 -51.917547)
			(xy 378.191356 -51.931436) (xy 378.101515 -51.937407) (xy 378.011499 -51.935416) (xy 377.92201 -51.925476)
			(xy 377.833751 -51.907666) (xy 377.74741 -51.882126) (xy 377.663665 -51.849054) (xy 377.583171 -51.808711)
			(xy 377.506557 -51.761411) (xy 377.434423 -51.707526) (xy 377.367334 -51.647476) (xy 377.305814 -51.581731)
			(xy 377.250346 -51.510807) (xy 377.201363 -51.435258) (xy 377.159249 -51.355676) (xy 377.124333 -51.272683)
			(xy 377.096889 -51.186929) (xy 377.077131 -51.099085) (xy 377.065214 -51.009838) (xy 377.061232 -50.919888)
			(xy 336.242505 -50.919888) (xy 336.249349 -50.956545) (xy 336.256919 -51.038332) (xy 336.257392 -51.0794)
			(xy 336.256924 -51.121325) (xy 336.249033 -51.204803) (xy 336.233322 -51.287169) (xy 336.209928 -51.367689)
			(xy 336.179061 -51.445652) (xy 336.140994 -51.520363) (xy 336.096065 -51.59116) (xy 336.044672 -51.657415)
			(xy 335.987273 -51.718539) (xy 335.924376 -51.773991) (xy 335.85654 -51.823277) (xy 335.784367 -51.865961)
			(xy 335.708497 -51.901663) (xy 335.629604 -51.930066) (xy 335.548388 -51.95092) (xy 335.46557 -51.964037)
			(xy 335.381885 -51.969303) (xy 335.298076 -51.966669) (xy 335.214887 -51.956161) (xy 335.133056 -51.93787)
			(xy 335.053309 -51.911959) (xy 334.976355 -51.878659) (xy 334.902876 -51.838264) (xy 334.833525 -51.791134)
			(xy 334.768916 -51.737686) (xy 334.709625 -51.678396) (xy 334.656176 -51.613788) (xy 334.609044 -51.544438)
			(xy 334.568648 -51.47096) (xy 334.535346 -51.394006) (xy 334.509434 -51.31426) (xy 334.491142 -51.232429)
			(xy 334.480632 -51.14924) (xy 334.477997 -51.065431) (xy 325.12 -51.065431) (xy 325.12 -56.9214)
			(xy 331.266292 -56.9214) (xy 331.266292 -56.920892) (xy 331.266898 -56.87456) (xy 331.276569 -56.782402)
			(xy 331.295765 -56.691748) (xy 331.324277 -56.603579) (xy 331.342492 -56.560974) (xy 331.346298 -56.551032)
			(xy 331.346298 -56.529768) (xy 331.342492 -56.519826) (xy 331.324247 -56.477164) (xy 331.295703 -56.388871)
			(xy 331.27651 -56.298086) (xy 331.266877 -56.205796) (xy 331.266292 -56.1594) (xy 331.266875 -56.113004)
			(xy 331.27652 -56.020716) (xy 331.295716 -55.929932) (xy 331.324254 -55.841639) (xy 331.342492 -55.798974)
			(xy 331.346298 -55.789032) (xy 331.346298 -55.767768) (xy 331.342492 -55.757826) (xy 331.324247 -55.715164)
			(xy 331.295703 -55.626871) (xy 331.27651 -55.536086) (xy 331.266877 -55.443796) (xy 331.266292 -55.3974)
			(xy 331.266875 -55.351004) (xy 331.27652 -55.258716) (xy 331.295716 -55.167932) (xy 331.324254 -55.079639)
			(xy 331.342492 -55.036974) (xy 331.346298 -55.027032) (xy 331.346298 -55.005768) (xy 331.342492 -54.995826)
			(xy 331.324247 -54.953164) (xy 331.295703 -54.864871) (xy 331.27651 -54.774086) (xy 331.266877 -54.681796)
			(xy 331.266292 -54.6354) (xy 331.266875 -54.589004) (xy 331.27652 -54.496716) (xy 331.295716 -54.405932)
			(xy 331.324254 -54.317639) (xy 331.342492 -54.274974) (xy 331.346298 -54.265032) (xy 331.346298 -54.243768)
			(xy 331.342492 -54.233826) (xy 331.32427 -54.191223) (xy 331.295752 -54.103056) (xy 331.27656 -54.0124)
			(xy 331.2669 -53.92024) (xy 331.266292 -53.873908) (xy 331.266292 -53.8734) (xy 331.266767 -53.832298)
			(xy 331.274352 -53.750443) (xy 331.289457 -53.669638) (xy 331.311953 -53.590571) (xy 331.341649 -53.513917)
			(xy 331.378291 -53.44033) (xy 331.421566 -53.370438) (xy 331.471106 -53.304837) (xy 331.526487 -53.244087)
			(xy 331.587237 -53.188706) (xy 331.652838 -53.139166) (xy 331.72273 -53.095891) (xy 331.796317 -53.059249)
			(xy 331.872971 -53.029553) (xy 331.952038 -53.007057) (xy 332.032843 -52.991952) (xy 332.114698 -52.984367)
			(xy 332.1558 -52.983892) (xy 332.156308 -52.983892) (xy 332.20264 -52.984498) (xy 332.294798 -52.994169)
			(xy 332.385452 -53.013365) (xy 332.473621 -53.041877) (xy 332.516226 -53.060092) (xy 332.526168 -53.063898)
			(xy 332.547432 -53.063898) (xy 332.557374 -53.060092) (xy 332.600036 -53.041847) (xy 332.688329 -53.013303)
			(xy 332.779114 -52.99411) (xy 332.871404 -52.984477) (xy 332.9178 -52.983892) (xy 332.964196 -52.984475)
			(xy 333.056484 -52.99412) (xy 333.147268 -53.013316) (xy 333.235561 -53.041854) (xy 333.278226 -53.060092)
			(xy 333.288168 -53.063898) (xy 333.309432 -53.063898) (xy 333.319374 -53.060092) (xy 333.362036 -53.041847)
			(xy 333.450329 -53.013303) (xy 333.541114 -52.99411) (xy 333.633404 -52.984477) (xy 333.6798 -52.983892)
			(xy 333.726196 -52.984475) (xy 333.818484 -52.99412) (xy 333.909268 -53.013316) (xy 333.997561 -53.041854)
			(xy 334.040226 -53.060092) (xy 334.050168 -53.063898) (xy 334.071432 -53.063898) (xy 334.081374 -53.060092)
			(xy 334.124036 -53.041847) (xy 334.212329 -53.013303) (xy 334.303114 -52.99411) (xy 334.395404 -52.984477)
			(xy 334.4418 -52.983892) (xy 334.488196 -52.984475) (xy 334.580484 -52.99412) (xy 334.671268 -53.013316)
			(xy 334.759561 -53.041854) (xy 334.802226 -53.060092) (xy 334.812168 -53.063898) (xy 334.833432 -53.063898)
			(xy 334.843374 -53.060092) (xy 334.885977 -53.04187) (xy 334.974144 -53.013352) (xy 335.0648 -52.99416)
			(xy 335.15696 -52.9845) (xy 335.203292 -52.983892) (xy 335.2038 -52.983892) (xy 335.244902 -52.984367)
			(xy 335.326757 -52.991952) (xy 335.407562 -53.007057) (xy 335.486629 -53.029553) (xy 335.563283 -53.059249)
			(xy 335.63687 -53.095891) (xy 335.706762 -53.139166) (xy 335.772363 -53.188706) (xy 335.833113 -53.244087)
			(xy 335.888494 -53.304837) (xy 335.938034 -53.370438) (xy 335.981309 -53.44033) (xy 336.017951 -53.513917)
			(xy 336.047647 -53.590571) (xy 336.070143 -53.669638) (xy 336.085248 -53.750443) (xy 336.092833 -53.832298)
			(xy 336.093308 -53.8734) (xy 336.093308 -53.873908) (xy 336.092702 -53.92024) (xy 336.083031 -54.012398)
			(xy 336.063835 -54.103052) (xy 336.035323 -54.191221) (xy 336.017108 -54.233826) (xy 336.013302 -54.243768)
			(xy 336.013302 -54.265032) (xy 336.017108 -54.274974) (xy 336.035353 -54.317636) (xy 336.063897 -54.405929)
			(xy 336.08309 -54.496714) (xy 336.092723 -54.589004) (xy 336.093308 -54.6354) (xy 336.092725 -54.681796)
			(xy 336.08308 -54.774084) (xy 336.063884 -54.864868) (xy 336.035346 -54.953161) (xy 336.017108 -54.995826)
			(xy 336.013302 -55.005768) (xy 336.013302 -55.027032) (xy 336.017108 -55.036974) (xy 336.035353 -55.079636)
			(xy 336.063897 -55.167929) (xy 336.08309 -55.258714) (xy 336.092723 -55.351004) (xy 336.093308 -55.3974)
			(xy 336.092725 -55.443796) (xy 336.08308 -55.536084) (xy 336.063884 -55.626868) (xy 336.035346 -55.715161)
			(xy 336.017108 -55.757826) (xy 336.013302 -55.767768) (xy 336.013302 -55.789032) (xy 336.017108 -55.798974)
			(xy 336.035353 -55.841636) (xy 336.063897 -55.929929) (xy 336.076593 -55.989982) (xy 468.668363 -55.989982)
			(xy 468.672353 -55.876999) (xy 468.684302 -55.764578) (xy 468.704152 -55.653281) (xy 468.731804 -55.543661)
			(xy 468.767118 -55.436264) (xy 468.809921 -55.331626) (xy 468.859998 -55.230268) (xy 468.9171 -55.132695)
			(xy 468.980942 -55.039393) (xy 469.051207 -54.950827) (xy 469.127544 -54.867437) (xy 469.209573 -54.78964)
			(xy 469.296886 -54.717823) (xy 469.389047 -54.652344) (xy 469.485597 -54.593529) (xy 469.586055 -54.541671)
			(xy 469.689922 -54.497029) (xy 469.796678 -54.459824) (xy 469.905793 -54.430242) (xy 470.016723 -54.408431)
			(xy 470.128915 -54.3945) (xy 470.24181 -54.388516) (xy 470.354846 -54.390512) (xy 470.46746 -54.400475)
			(xy 470.579091 -54.418358) (xy 470.689182 -54.44407) (xy 470.797185 -54.477484) (xy 470.902562 -54.518433)
			(xy 471.004788 -54.566714) (xy 471.103353 -54.622085) (xy 471.197768 -54.68427) (xy 471.28756 -54.752961)
			(xy 471.372284 -54.827815) (xy 471.451517 -54.908458) (xy 471.524863 -54.99449) (xy 471.591959 -55.085481)
			(xy 471.652468 -55.180978) (xy 471.706091 -55.280505) (xy 471.75256 -55.383568) (xy 471.791643 -55.489651)
			(xy 471.823146 -55.598227) (xy 471.846911 -55.708754) (xy 471.862821 -55.820683) (xy 471.870795 -55.933455)
			(xy 471.871294 -55.989982) (xy 471.870795 -56.046509) (xy 471.862821 -56.159281) (xy 471.846911 -56.27121)
			(xy 471.823146 -56.381737) (xy 471.791643 -56.490313) (xy 471.75256 -56.596396) (xy 471.706091 -56.699459)
			(xy 471.652468 -56.798986) (xy 471.591959 -56.894483) (xy 471.524863 -56.985474) (xy 471.451517 -57.071506)
			(xy 471.372284 -57.152149) (xy 471.28756 -57.227003) (xy 471.197768 -57.295694) (xy 471.103353 -57.357879)
			(xy 471.004788 -57.41325) (xy 470.902562 -57.461531) (xy 470.797185 -57.50248) (xy 470.689182 -57.535894)
			(xy 470.579091 -57.561606) (xy 470.46746 -57.579489) (xy 470.354846 -57.589452) (xy 470.24181 -57.591448)
			(xy 470.128915 -57.585464) (xy 470.016723 -57.571533) (xy 469.905793 -57.549722) (xy 469.796678 -57.52014)
			(xy 469.689922 -57.482935) (xy 469.586055 -57.438293) (xy 469.485597 -57.386435) (xy 469.389047 -57.32762)
			(xy 469.296886 -57.262141) (xy 469.209573 -57.190324) (xy 469.127544 -57.112527) (xy 469.051207 -57.029137)
			(xy 468.980942 -56.940571) (xy 468.9171 -56.847269) (xy 468.859998 -56.749696) (xy 468.809921 -56.648338)
			(xy 468.767118 -56.5437) (xy 468.731804 -56.436303) (xy 468.704152 -56.326683) (xy 468.684302 -56.215386)
			(xy 468.672353 -56.102965) (xy 468.668363 -55.989982) (xy 336.076593 -55.989982) (xy 336.08309 -56.020714)
			(xy 336.092723 -56.113004) (xy 336.093308 -56.1594) (xy 336.092725 -56.205796) (xy 336.08308 -56.298084)
			(xy 336.063884 -56.388868) (xy 336.035346 -56.477161) (xy 336.017108 -56.519826) (xy 336.013302 -56.529768)
			(xy 336.013302 -56.551032) (xy 336.017108 -56.560974) (xy 336.03533 -56.603577) (xy 336.063848 -56.691744)
			(xy 336.08304 -56.7824) (xy 336.0927 -56.87456) (xy 336.093308 -56.920892) (xy 336.093308 -56.9214)
			(xy 336.092833 -56.962502) (xy 336.085248 -57.044357) (xy 336.070143 -57.125162) (xy 336.047647 -57.204229)
			(xy 336.017951 -57.280883) (xy 335.981309 -57.35447) (xy 335.938034 -57.424362) (xy 335.888494 -57.489963)
			(xy 335.833113 -57.550713) (xy 335.772363 -57.606094) (xy 335.706762 -57.655634) (xy 335.63687 -57.698909)
			(xy 335.563283 -57.735551) (xy 335.486629 -57.765247) (xy 335.407562 -57.787743) (xy 335.326757 -57.802848)
			(xy 335.244902 -57.810433) (xy 335.2038 -57.810908) (xy 335.203292 -57.810908) (xy 335.15696 -57.810302)
			(xy 335.064802 -57.800631) (xy 334.974148 -57.781435) (xy 334.885979 -57.752923) (xy 334.843374 -57.734708)
			(xy 334.833432 -57.730902) (xy 334.812168 -57.730902) (xy 334.802226 -57.734708) (xy 334.759564 -57.752953)
			(xy 334.671271 -57.781497) (xy 334.580486 -57.80069) (xy 334.488196 -57.810323) (xy 334.4418 -57.810908)
			(xy 334.395404 -57.810325) (xy 334.303116 -57.80068) (xy 334.212332 -57.781484) (xy 334.124039 -57.752946)
			(xy 334.081374 -57.734708) (xy 334.071432 -57.730902) (xy 334.050168 -57.730902) (xy 334.040226 -57.734708)
			(xy 333.997564 -57.752953) (xy 333.909271 -57.781497) (xy 333.818486 -57.80069) (xy 333.726196 -57.810323)
			(xy 333.6798 -57.810908) (xy 333.633404 -57.810325) (xy 333.541116 -57.80068) (xy 333.450332 -57.781484)
			(xy 333.362039 -57.752946) (xy 333.319374 -57.734708) (xy 333.309432 -57.730902) (xy 333.288168 -57.730902)
			(xy 333.278226 -57.734708) (xy 333.235564 -57.752953) (xy 333.147271 -57.781497) (xy 333.056486 -57.80069)
			(xy 332.964196 -57.810323) (xy 332.9178 -57.810908) (xy 332.871404 -57.810325) (xy 332.779116 -57.80068)
			(xy 332.688332 -57.781484) (xy 332.600039 -57.752946) (xy 332.557374 -57.734708) (xy 332.547432 -57.730902)
			(xy 332.526168 -57.730902) (xy 332.516226 -57.734708) (xy 332.473623 -57.75293) (xy 332.385456 -57.781448)
			(xy 332.2948 -57.80064) (xy 332.20264 -57.8103) (xy 332.156308 -57.810908) (xy 332.1558 -57.810908)
			(xy 332.114698 -57.810433) (xy 332.032843 -57.802848) (xy 331.952038 -57.787743) (xy 331.872971 -57.765247)
			(xy 331.796317 -57.735551) (xy 331.72273 -57.698909) (xy 331.652838 -57.655634) (xy 331.587237 -57.606094)
			(xy 331.526487 -57.550713) (xy 331.471106 -57.489963) (xy 331.421566 -57.424362) (xy 331.378291 -57.35447)
			(xy 331.341649 -57.280883) (xy 331.311953 -57.204229) (xy 331.289457 -57.125162) (xy 331.274352 -57.044357)
			(xy 331.266767 -56.962502) (xy 331.266292 -56.9214) (xy 325.12 -56.9214) (xy 325.12 -58.42) (xy 376.553741 -58.42)
			(xy 376.557716 -58.309941) (xy 376.569624 -58.200455) (xy 376.5894 -58.092114) (xy 376.616943 -57.985483)
			(xy 376.652108 -57.881117) (xy 376.694712 -57.77956) (xy 376.744533 -57.681343) (xy 376.801312 -57.586976)
			(xy 376.864751 -57.496952) (xy 376.934522 -57.411741) (xy 377.010259 -57.331786) (xy 377.091568 -57.257505)
			(xy 377.178025 -57.189285) (xy 377.269179 -57.12748) (xy 377.364556 -57.072415) (xy 377.463657 -57.024375)
			(xy 377.565966 -56.983611) (xy 377.67095 -56.950336) (xy 377.778061 -56.924723) (xy 377.886741 -56.906906)
			(xy 377.996424 -56.896977) (xy 378.106537 -56.894989) (xy 378.216507 -56.900951) (xy 378.32576 -56.914833)
			(xy 378.433726 -56.936563) (xy 378.539843 -56.966026) (xy 378.643557 -57.003069) (xy 378.744328 -57.0475)
			(xy 378.84163 -57.099087) (xy 378.934956 -57.157559) (xy 379.023819 -57.222614) (xy 379.107757 -57.293912)
			(xy 379.186332 -57.37108) (xy 379.259133 -57.453717) (xy 379.325781 -57.541391) (xy 379.38593 -57.633647)
			(xy 379.439264 -57.730002) (xy 379.485507 -57.829954) (xy 379.524417 -57.932982) (xy 379.555791 -58.03855)
			(xy 379.579466 -58.146106) (xy 379.595318 -58.25509) (xy 379.603265 -58.364934) (xy 379.603762 -58.42)
			(xy 396.111741 -58.42) (xy 396.115716 -58.309941) (xy 396.127624 -58.200455) (xy 396.1474 -58.092114)
			(xy 396.174943 -57.985483) (xy 396.210108 -57.881117) (xy 396.252712 -57.77956) (xy 396.302533 -57.681343)
			(xy 396.359312 -57.586976) (xy 396.422751 -57.496952) (xy 396.492522 -57.411741) (xy 396.568259 -57.331786)
			(xy 396.649568 -57.257505) (xy 396.736025 -57.189285) (xy 396.827179 -57.12748) (xy 396.922556 -57.072415)
			(xy 397.021657 -57.024375) (xy 397.123966 -56.983611) (xy 397.22895 -56.950336) (xy 397.336061 -56.924723)
			(xy 397.444741 -56.906906) (xy 397.554424 -56.896977) (xy 397.664537 -56.894989) (xy 397.774507 -56.900951)
			(xy 397.88376 -56.914833) (xy 397.991726 -56.936563) (xy 398.097843 -56.966026) (xy 398.201557 -57.003069)
			(xy 398.302328 -57.0475) (xy 398.39963 -57.099087) (xy 398.492956 -57.157559) (xy 398.581819 -57.222614)
			(xy 398.665757 -57.293912) (xy 398.744332 -57.37108) (xy 398.817133 -57.453717) (xy 398.883781 -57.541391)
			(xy 398.94393 -57.633647) (xy 398.997264 -57.730002) (xy 399.043507 -57.829954) (xy 399.082417 -57.932982)
			(xy 399.113791 -58.03855) (xy 399.137466 -58.146106) (xy 399.153318 -58.25509) (xy 399.161265 -58.364934)
			(xy 399.161762 -58.42) (xy 399.161265 -58.475066) (xy 399.153318 -58.58491) (xy 399.137466 -58.693894)
			(xy 399.113791 -58.80145) (xy 399.082417 -58.907018) (xy 399.043507 -59.010046) (xy 398.997264 -59.109998)
			(xy 398.94393 -59.206353) (xy 398.883781 -59.298609) (xy 398.817133 -59.386283) (xy 398.744332 -59.46892)
			(xy 398.665757 -59.546088) (xy 398.581819 -59.617386) (xy 398.492956 -59.682441) (xy 398.39963 -59.740913)
			(xy 398.302328 -59.7925) (xy 398.201557 -59.836931) (xy 398.097843 -59.873974) (xy 397.991726 -59.903437)
			(xy 397.88376 -59.925167) (xy 397.774507 -59.939049) (xy 397.664537 -59.945011) (xy 397.554424 -59.943023)
			(xy 397.444741 -59.933094) (xy 397.336061 -59.915277) (xy 397.22895 -59.889664) (xy 397.123966 -59.856389)
			(xy 397.021657 -59.815625) (xy 396.922556 -59.767585) (xy 396.827179 -59.71252) (xy 396.736025 -59.650715)
			(xy 396.649568 -59.582495) (xy 396.568259 -59.508214) (xy 396.492522 -59.428259) (xy 396.422751 -59.343048)
			(xy 396.359312 -59.253024) (xy 396.302533 -59.158657) (xy 396.252712 -59.06044) (xy 396.210108 -58.958883)
			(xy 396.174943 -58.854517) (xy 396.1474 -58.747886) (xy 396.127624 -58.639545) (xy 396.115716 -58.530059)
			(xy 396.111741 -58.42) (xy 379.603762 -58.42) (xy 379.603265 -58.475066) (xy 379.595318 -58.58491)
			(xy 379.579466 -58.693894) (xy 379.555791 -58.80145) (xy 379.524417 -58.907018) (xy 379.485507 -59.010046)
			(xy 379.439264 -59.109998) (xy 379.38593 -59.206353) (xy 379.325781 -59.298609) (xy 379.259133 -59.386283)
			(xy 379.186332 -59.46892) (xy 379.107757 -59.546088) (xy 379.023819 -59.617386) (xy 378.934956 -59.682441)
			(xy 378.84163 -59.740913) (xy 378.744328 -59.7925) (xy 378.643557 -59.836931) (xy 378.539843 -59.873974)
			(xy 378.433726 -59.903437) (xy 378.32576 -59.925167) (xy 378.216507 -59.939049) (xy 378.106537 -59.945011)
			(xy 377.996424 -59.943023) (xy 377.886741 -59.933094) (xy 377.778061 -59.915277) (xy 377.67095 -59.889664)
			(xy 377.565966 -59.856389) (xy 377.463657 -59.815625) (xy 377.364556 -59.767585) (xy 377.269179 -59.71252)
			(xy 377.178025 -59.650715) (xy 377.091568 -59.582495) (xy 377.010259 -59.508214) (xy 376.934522 -59.428259)
			(xy 376.864751 -59.343048) (xy 376.801312 -59.253024) (xy 376.744533 -59.158657) (xy 376.694712 -59.06044)
			(xy 376.652108 -58.958883) (xy 376.616943 -58.854517) (xy 376.5894 -58.747886) (xy 376.569624 -58.639545)
			(xy 376.557716 -58.530059) (xy 376.553741 -58.42) (xy 325.12 -58.42) (xy 325.12 -60.099956) (xy 422.484046 -60.099956)
			(xy 422.488076 -59.957621) (xy 422.500151 -59.815741) (xy 422.520234 -59.674773) (xy 422.548261 -59.535166)
			(xy 422.584141 -59.397368) (xy 422.627759 -59.261821) (xy 422.678976 -59.128959) (xy 422.737627 -58.999207)
			(xy 422.803525 -58.872981) (xy 422.876459 -58.750685) (xy 422.956196 -58.632712) (xy 423.042478 -58.519439)
			(xy 423.135031 -58.411228) (xy 423.233558 -58.308427) (xy 423.337743 -58.211365) (xy 423.447252 -58.120353)
			(xy 423.561735 -58.035681) (xy 423.680825 -57.957623) (xy 423.80414 -57.886427) (xy 423.931286 -57.822321)
			(xy 424.061855 -57.765512) (xy 424.195429 -57.71618) (xy 424.33158 -57.674484) (xy 424.469871 -57.640558)
			(xy 424.609861 -57.61451) (xy 424.7511 -57.596424) (xy 424.893136 -57.586357) (xy 425.035514 -57.584342)
			(xy 425.177778 -57.590385) (xy 425.319472 -57.604467) (xy 425.460142 -57.626543) (xy 425.599339 -57.656543)
			(xy 425.736615 -57.694369) (xy 425.871531 -57.739901) (xy 426.003655 -57.792992) (xy 426.132564 -57.853474)
			(xy 426.257845 -57.921152) (xy 426.379096 -57.995809) (xy 426.495929 -58.077207) (xy 426.60797 -58.165084)
			(xy 426.71486 -58.259159) (xy 426.816257 -58.359131) (xy 426.911835 -58.464679) (xy 427.001289 -58.575465)
			(xy 427.084331 -58.691134) (xy 427.160697 -58.811317) (xy 427.230141 -58.935627) (xy 427.292441 -59.063668)
			(xy 427.347397 -59.195027) (xy 427.394834 -59.329286) (xy 427.434598 -59.466013) (xy 427.466564 -59.604771)
			(xy 427.490629 -59.745115) (xy 427.506715 -59.886596) (xy 427.51477 -60.02876) (xy 427.515274 -60.099956)
			(xy 427.51477 -60.171152) (xy 427.506715 -60.313316) (xy 427.490629 -60.454797) (xy 427.466564 -60.595141)
			(xy 427.434598 -60.733899) (xy 427.394834 -60.870626) (xy 427.347397 -61.004885) (xy 427.292441 -61.136244)
			(xy 427.230141 -61.264285) (xy 427.160697 -61.388595) (xy 427.084331 -61.508778) (xy 427.001289 -61.624447)
			(xy 426.911835 -61.735233) (xy 426.816257 -61.840781) (xy 426.71486 -61.940753) (xy 426.60797 -62.034828)
			(xy 426.495929 -62.122705) (xy 426.379096 -62.204103) (xy 426.257845 -62.27876) (xy 426.132564 -62.346438)
			(xy 426.003655 -62.40692) (xy 425.871531 -62.460011) (xy 425.736615 -62.505543) (xy 425.599339 -62.543369)
			(xy 425.460142 -62.573369) (xy 425.319472 -62.595445) (xy 425.177778 -62.609527) (xy 425.035514 -62.61557)
			(xy 424.893136 -62.613555) (xy 424.7511 -62.603488) (xy 424.609861 -62.585402) (xy 424.469871 -62.559354)
			(xy 424.33158 -62.525428) (xy 424.195429 -62.483732) (xy 424.061855 -62.4344) (xy 423.931286 -62.377591)
			(xy 423.80414 -62.313485) (xy 423.680825 -62.242289) (xy 423.561735 -62.164231) (xy 423.447252 -62.079559)
			(xy 423.337743 -61.988547) (xy 423.233558 -61.891485) (xy 423.135031 -61.788684) (xy 423.042478 -61.680473)
			(xy 422.956196 -61.5672) (xy 422.876459 -61.449227) (xy 422.803525 -61.326931) (xy 422.737627 -61.200705)
			(xy 422.678976 -61.070953) (xy 422.627759 -60.938091) (xy 422.584141 -60.802544) (xy 422.548261 -60.664746)
			(xy 422.520234 -60.525139) (xy 422.500151 -60.384171) (xy 422.488076 -60.242291) (xy 422.484046 -60.099956)
			(xy 325.12 -60.099956) (xy 325.12 -62.399361) (xy 334.478626 -62.399361) (xy 334.478626 -62.314639)
			(xy 334.486679 -62.230302) (xy 334.502713 -62.147112) (xy 334.526581 -62.065822) (xy 334.558069 -61.98717)
			(xy 334.596891 -61.911867) (xy 334.642694 -61.840595) (xy 334.695065 -61.773999) (xy 334.75353 -61.712684)
			(xy 334.817558 -61.657203) (xy 334.88657 -61.60806) (xy 334.95994 -61.5657) (xy 335.037005 -61.530505)
			(xy 335.117067 -61.502796) (xy 335.1994 -61.482822) (xy 335.283259 -61.470765) (xy 335.367884 -61.466734)
			(xy 335.452509 -61.470765) (xy 335.536368 -61.482822) (xy 335.618701 -61.502796) (xy 335.698763 -61.530505)
			(xy 335.775828 -61.5657) (xy 335.849198 -61.60806) (xy 335.91821 -61.657203) (xy 335.982238 -61.712684)
			(xy 336.040703 -61.773999) (xy 336.093074 -61.840595) (xy 336.138877 -61.911867) (xy 336.177699 -61.98717)
			(xy 336.209187 -62.065822) (xy 336.233055 -62.147112) (xy 336.249089 -62.230302) (xy 336.257142 -62.314639)
			(xy 336.257646 -62.357) (xy 336.257142 -62.399361) (xy 336.249089 -62.483698) (xy 336.233055 -62.566888)
			(xy 336.209187 -62.648178) (xy 336.177699 -62.72683) (xy 336.138877 -62.802133) (xy 336.093074 -62.873405)
			(xy 336.040703 -62.940001) (xy 335.982238 -63.001316) (xy 335.91821 -63.056797) (xy 335.849198 -63.10594)
			(xy 335.775828 -63.1483) (xy 335.698763 -63.183495) (xy 335.618701 -63.211204) (xy 335.536368 -63.231178)
			(xy 335.452509 -63.243235) (xy 335.367884 -63.247267) (xy 335.283259 -63.243235) (xy 335.1994 -63.231178)
			(xy 335.117067 -63.211204) (xy 335.037005 -63.183495) (xy 334.95994 -63.1483) (xy 334.88657 -63.10594)
			(xy 334.817558 -63.056797) (xy 334.75353 -63.001316) (xy 334.695065 -62.940001) (xy 334.642694 -62.873405)
			(xy 334.596891 -62.802133) (xy 334.558069 -62.72683) (xy 334.526581 -62.648178) (xy 334.502713 -62.566888)
			(xy 334.486679 -62.483698) (xy 334.478626 -62.399361) (xy 325.12 -62.399361) (xy 325.12 -68.199)
			(xy 331.266292 -68.199) (xy 331.266292 -68.198492) (xy 331.266898 -68.15216) (xy 331.276569 -68.060002)
			(xy 331.295765 -67.969348) (xy 331.324277 -67.881179) (xy 331.342492 -67.838574) (xy 331.346298 -67.828632)
			(xy 331.346298 -67.807368) (xy 331.342492 -67.797426) (xy 331.324247 -67.754764) (xy 331.295703 -67.666471)
			(xy 331.27651 -67.575686) (xy 331.266877 -67.483396) (xy 331.266292 -67.437) (xy 331.266875 -67.390604)
			(xy 331.27652 -67.298316) (xy 331.295716 -67.207532) (xy 331.324254 -67.119239) (xy 331.342492 -67.076574)
			(xy 331.346298 -67.066632) (xy 331.346298 -67.045368) (xy 331.342492 -67.035426) (xy 331.324247 -66.992764)
			(xy 331.295703 -66.904471) (xy 331.27651 -66.813686) (xy 331.266877 -66.721396) (xy 331.266292 -66.675)
			(xy 331.266875 -66.628604) (xy 331.27652 -66.536316) (xy 331.295716 -66.445532) (xy 331.324254 -66.357239)
			(xy 331.342492 -66.314574) (xy 331.346298 -66.304632) (xy 331.346298 -66.283368) (xy 331.342492 -66.273426)
			(xy 331.324247 -66.230764) (xy 331.295703 -66.142471) (xy 331.27651 -66.051686) (xy 331.266877 -65.959396)
			(xy 331.266292 -65.913) (xy 331.266875 -65.866604) (xy 331.27652 -65.774316) (xy 331.295716 -65.683532)
			(xy 331.324254 -65.595239) (xy 331.342492 -65.552574) (xy 331.346298 -65.542632) (xy 331.346298 -65.521368)
			(xy 331.342492 -65.511426) (xy 331.32427 -65.468823) (xy 331.295752 -65.380656) (xy 331.27656 -65.29)
			(xy 331.2669 -65.19784) (xy 331.266292 -65.151508) (xy 331.266292 -65.151) (xy 331.266767 -65.109898)
			(xy 331.274352 -65.028043) (xy 331.289457 -64.947238) (xy 331.311953 -64.868171) (xy 331.341649 -64.791517)
			(xy 331.378291 -64.71793) (xy 331.421566 -64.648038) (xy 331.471106 -64.582437) (xy 331.526487 -64.521687)
			(xy 331.587237 -64.466306) (xy 331.652838 -64.416766) (xy 331.72273 -64.373491) (xy 331.796317 -64.336849)
			(xy 331.872971 -64.307153) (xy 331.952038 -64.284657) (xy 332.032843 -64.269552) (xy 332.114698 -64.261967)
			(xy 332.1558 -64.261492) (xy 332.156308 -64.261492) (xy 332.20264 -64.262098) (xy 332.294798 -64.271769)
			(xy 332.385452 -64.290965) (xy 332.473621 -64.319477) (xy 332.516226 -64.337692) (xy 332.526168 -64.341498)
			(xy 332.547432 -64.341498) (xy 332.557374 -64.337692) (xy 332.600036 -64.319447) (xy 332.688329 -64.290903)
			(xy 332.779114 -64.27171) (xy 332.871404 -64.262077) (xy 332.9178 -64.261492) (xy 332.964196 -64.262075)
			(xy 333.056484 -64.27172) (xy 333.147268 -64.290916) (xy 333.235561 -64.319454) (xy 333.278226 -64.337692)
			(xy 333.288168 -64.341498) (xy 333.309432 -64.341498) (xy 333.319374 -64.337692) (xy 333.362036 -64.319447)
			(xy 333.450329 -64.290903) (xy 333.541114 -64.27171) (xy 333.633404 -64.262077) (xy 333.6798 -64.261492)
			(xy 333.726196 -64.262075) (xy 333.818484 -64.27172) (xy 333.909268 -64.290916) (xy 333.997561 -64.319454)
			(xy 334.040226 -64.337692) (xy 334.050168 -64.341498) (xy 334.071432 -64.341498) (xy 334.081374 -64.337692)
			(xy 334.124036 -64.319447) (xy 334.212329 -64.290903) (xy 334.303114 -64.27171) (xy 334.395404 -64.262077)
			(xy 334.4418 -64.261492) (xy 334.488196 -64.262075) (xy 334.580484 -64.27172) (xy 334.671268 -64.290916)
			(xy 334.759561 -64.319454) (xy 334.802226 -64.337692) (xy 334.812168 -64.341498) (xy 334.833432 -64.341498)
			(xy 334.843374 -64.337692) (xy 334.885977 -64.31947) (xy 334.974144 -64.290952) (xy 335.0648 -64.27176)
			(xy 335.15696 -64.2621) (xy 335.203292 -64.261492) (xy 335.2038 -64.261492) (xy 335.244902 -64.261967)
			(xy 335.326757 -64.269552) (xy 335.407562 -64.284657) (xy 335.486629 -64.307153) (xy 335.563283 -64.336849)
			(xy 335.63687 -64.373491) (xy 335.706762 -64.416766) (xy 335.772363 -64.466306) (xy 335.833113 -64.521687)
			(xy 335.888494 -64.582437) (xy 335.938034 -64.648038) (xy 335.981309 -64.71793) (xy 336.017951 -64.791517)
			(xy 336.047647 -64.868171) (xy 336.070143 -64.947238) (xy 336.085248 -65.028043) (xy 336.092833 -65.109898)
			(xy 336.093308 -65.151) (xy 336.093308 -65.151508) (xy 336.092702 -65.19784) (xy 336.083031 -65.289998)
			(xy 336.063835 -65.380652) (xy 336.035323 -65.468821) (xy 336.017108 -65.511426) (xy 336.013302 -65.521368)
			(xy 336.013302 -65.542632) (xy 336.017108 -65.552574) (xy 336.035353 -65.595236) (xy 336.063897 -65.683529)
			(xy 336.08309 -65.774314) (xy 336.092723 -65.866604) (xy 336.093308 -65.913) (xy 336.092725 -65.959396)
			(xy 336.08308 -66.051684) (xy 336.063884 -66.142468) (xy 336.035346 -66.230761) (xy 336.017108 -66.273426)
			(xy 336.013302 -66.283368) (xy 336.013302 -66.304632) (xy 336.017108 -66.314574) (xy 336.035353 -66.357236)
			(xy 336.063897 -66.445529) (xy 336.08309 -66.536314) (xy 336.092723 -66.628604) (xy 336.093308 -66.675)
			(xy 336.092725 -66.721396) (xy 336.08308 -66.813684) (xy 336.063884 -66.904468) (xy 336.035346 -66.992761)
			(xy 336.017108 -67.035426) (xy 336.013302 -67.045368) (xy 336.013302 -67.066632) (xy 336.017108 -67.076574)
			(xy 336.035353 -67.119236) (xy 336.063897 -67.207529) (xy 336.08309 -67.298314) (xy 336.092723 -67.390604)
			(xy 336.093308 -67.437) (xy 336.092725 -67.483396) (xy 336.08308 -67.575684) (xy 336.063884 -67.666468)
			(xy 336.035346 -67.754761) (xy 336.017108 -67.797426) (xy 336.013302 -67.807368) (xy 336.013302 -67.828632)
			(xy 336.017108 -67.838574) (xy 336.03533 -67.881177) (xy 336.063848 -67.969344) (xy 336.08304 -68.06)
			(xy 336.0927 -68.15216) (xy 336.093308 -68.198492) (xy 336.093308 -68.199) (xy 336.092833 -68.240102)
			(xy 336.085248 -68.321957) (xy 336.070143 -68.402762) (xy 336.047647 -68.481829) (xy 336.017951 -68.558483)
			(xy 335.981309 -68.63207) (xy 335.938034 -68.701962) (xy 335.888494 -68.767563) (xy 335.833113 -68.828313)
			(xy 335.772363 -68.883694) (xy 335.706762 -68.933234) (xy 335.63687 -68.976509) (xy 335.563283 -69.013151)
			(xy 335.486629 -69.042847) (xy 335.407562 -69.065343) (xy 335.326757 -69.080448) (xy 335.244902 -69.088033)
			(xy 335.2038 -69.088508) (xy 335.203292 -69.088508) (xy 335.15696 -69.087902) (xy 335.064802 -69.078231)
			(xy 334.974148 -69.059035) (xy 334.885979 -69.030523) (xy 334.843374 -69.012308) (xy 334.833432 -69.008502)
			(xy 334.812168 -69.008502) (xy 334.802226 -69.012308) (xy 334.759564 -69.030553) (xy 334.671271 -69.059097)
			(xy 334.580486 -69.07829) (xy 334.488196 -69.087923) (xy 334.4418 -69.088508) (xy 334.395404 -69.087925)
			(xy 334.303116 -69.07828) (xy 334.212332 -69.059084) (xy 334.124039 -69.030546) (xy 334.081374 -69.012308)
			(xy 334.071432 -69.008502) (xy 334.050168 -69.008502) (xy 334.040226 -69.012308) (xy 333.997564 -69.030553)
			(xy 333.909271 -69.059097) (xy 333.818486 -69.07829) (xy 333.726196 -69.087923) (xy 333.6798 -69.088508)
			(xy 333.633404 -69.087925) (xy 333.541116 -69.07828) (xy 333.450332 -69.059084) (xy 333.362039 -69.030546)
			(xy 333.319374 -69.012308) (xy 333.309432 -69.008502) (xy 333.288168 -69.008502) (xy 333.278226 -69.012308)
			(xy 333.235564 -69.030553) (xy 333.147271 -69.059097) (xy 333.056486 -69.07829) (xy 332.964196 -69.087923)
			(xy 332.9178 -69.088508) (xy 332.871404 -69.087925) (xy 332.779116 -69.07828) (xy 332.688332 -69.059084)
			(xy 332.600039 -69.030546) (xy 332.557374 -69.012308) (xy 332.547432 -69.008502) (xy 332.526168 -69.008502)
			(xy 332.516226 -69.012308) (xy 332.473623 -69.03053) (xy 332.385456 -69.059048) (xy 332.2948 -69.07824)
			(xy 332.20264 -69.0879) (xy 332.156308 -69.088508) (xy 332.1558 -69.088508) (xy 332.114698 -69.088033)
			(xy 332.032843 -69.080448) (xy 331.952038 -69.065343) (xy 331.872971 -69.042847) (xy 331.796317 -69.013151)
			(xy 331.72273 -68.976509) (xy 331.652838 -68.933234) (xy 331.587237 -68.883694) (xy 331.526487 -68.828313)
			(xy 331.471106 -68.767563) (xy 331.421566 -68.701962) (xy 331.378291 -68.63207) (xy 331.341649 -68.558483)
			(xy 331.311953 -68.481829) (xy 331.289457 -68.402762) (xy 331.274352 -68.321957) (xy 331.266767 -68.240102)
			(xy 331.266292 -68.199) (xy 325.12 -68.199) (xy 325.12 -71.239888) (xy 377.061232 -71.239888) (xy 377.065214 -71.149938)
			(xy 377.077131 -71.060691) (xy 377.096889 -70.972847) (xy 377.124333 -70.887093) (xy 377.159249 -70.8041)
			(xy 377.201363 -70.724518) (xy 377.250346 -70.648969) (xy 377.305814 -70.578045) (xy 377.367334 -70.5123)
			(xy 377.434423 -70.45225) (xy 377.506557 -70.398365) (xy 377.583171 -70.351065) (xy 377.663665 -70.310722)
			(xy 377.74741 -70.27765) (xy 377.833751 -70.25211) (xy 377.92201 -70.2343) (xy 378.011499 -70.22436)
			(xy 378.101515 -70.222369) (xy 378.191356 -70.22834) (xy 378.280317 -70.242229) (xy 378.367702 -70.263925)
			(xy 378.452828 -70.29326) (xy 378.535028 -70.330003) (xy 378.613659 -70.373867) (xy 378.688106 -70.424509)
			(xy 378.757786 -70.481533) (xy 378.822153 -70.544492) (xy 378.880704 -70.612893) (xy 378.932981 -70.686201)
			(xy 378.978574 -70.763843) (xy 379.017127 -70.84521) (xy 379.048338 -70.929666) (xy 379.071962 -71.01655)
			(xy 379.087815 -71.105182) (xy 379.095772 -71.194869) (xy 379.09627 -71.239888) (xy 396.619232 -71.239888)
			(xy 396.623214 -71.149938) (xy 396.635131 -71.060691) (xy 396.654889 -70.972847) (xy 396.682333 -70.887093)
			(xy 396.717249 -70.8041) (xy 396.759363 -70.724518) (xy 396.808346 -70.648969) (xy 396.863814 -70.578045)
			(xy 396.925334 -70.5123) (xy 396.992423 -70.45225) (xy 397.064557 -70.398365) (xy 397.141171 -70.351065)
			(xy 397.221665 -70.310722) (xy 397.30541 -70.27765) (xy 397.391751 -70.25211) (xy 397.48001 -70.2343)
			(xy 397.569499 -70.22436) (xy 397.659515 -70.222369) (xy 397.749356 -70.22834) (xy 397.838317 -70.242229)
			(xy 397.925702 -70.263925) (xy 398.010828 -70.29326) (xy 398.093028 -70.330003) (xy 398.171659 -70.373867)
			(xy 398.246106 -70.424509) (xy 398.315786 -70.481533) (xy 398.380153 -70.544492) (xy 398.438704 -70.612893)
			(xy 398.490981 -70.686201) (xy 398.536574 -70.763843) (xy 398.575127 -70.84521) (xy 398.606338 -70.929666)
			(xy 398.629962 -71.01655) (xy 398.645815 -71.105182) (xy 398.653772 -71.194869) (xy 398.65427 -71.239888)
			(xy 398.653772 -71.284907) (xy 398.645815 -71.374594) (xy 398.629962 -71.463226) (xy 398.606338 -71.55011)
			(xy 398.575127 -71.634566) (xy 398.536574 -71.715933) (xy 398.490981 -71.793575) (xy 398.438704 -71.866883)
			(xy 398.380153 -71.935284) (xy 398.315786 -71.998243) (xy 398.246106 -72.055267) (xy 398.171659 -72.105909)
			(xy 398.093028 -72.149773) (xy 398.010828 -72.186516) (xy 397.925702 -72.215851) (xy 397.838317 -72.237547)
			(xy 397.749356 -72.251436) (xy 397.659515 -72.257407) (xy 397.569499 -72.255416) (xy 397.48001 -72.245476)
			(xy 397.391751 -72.227666) (xy 397.30541 -72.202126) (xy 397.221665 -72.169054) (xy 397.141171 -72.128711)
			(xy 397.064557 -72.081411) (xy 396.992423 -72.027526) (xy 396.925334 -71.967476) (xy 396.863814 -71.901731)
			(xy 396.808346 -71.830807) (xy 396.759363 -71.755258) (xy 396.717249 -71.675676) (xy 396.682333 -71.592683)
			(xy 396.654889 -71.506929) (xy 396.635131 -71.419085) (xy 396.623214 -71.329838) (xy 396.619232 -71.239888)
			(xy 379.09627 -71.239888) (xy 379.095772 -71.284907) (xy 379.087815 -71.374594) (xy 379.071962 -71.463226)
			(xy 379.048338 -71.55011) (xy 379.017127 -71.634566) (xy 378.978574 -71.715933) (xy 378.932981 -71.793575)
			(xy 378.880704 -71.866883) (xy 378.822153 -71.935284) (xy 378.757786 -71.998243) (xy 378.688106 -72.055267)
			(xy 378.613659 -72.105909) (xy 378.535028 -72.149773) (xy 378.452828 -72.186516) (xy 378.367702 -72.215851)
			(xy 378.280317 -72.237547) (xy 378.191356 -72.251436) (xy 378.101515 -72.257407) (xy 378.011499 -72.255416)
			(xy 377.92201 -72.245476) (xy 377.833751 -72.227666) (xy 377.74741 -72.202126) (xy 377.663665 -72.169054)
			(xy 377.583171 -72.128711) (xy 377.506557 -72.081411) (xy 377.434423 -72.027526) (xy 377.367334 -71.967476)
			(xy 377.305814 -71.901731) (xy 377.250346 -71.830807) (xy 377.201363 -71.755258) (xy 377.159249 -71.675676)
			(xy 377.124333 -71.592683) (xy 377.096889 -71.506929) (xy 377.077131 -71.419085) (xy 377.065214 -71.329838)
			(xy 377.061232 -71.239888) (xy 325.12 -71.239888) (xy 325.12 -73.676961) (xy 334.478626 -73.676961)
			(xy 334.478626 -73.592239) (xy 334.486679 -73.507902) (xy 334.502713 -73.424712) (xy 334.526581 -73.343422)
			(xy 334.558069 -73.26477) (xy 334.596891 -73.189467) (xy 334.642694 -73.118195) (xy 334.695065 -73.051599)
			(xy 334.75353 -72.990284) (xy 334.817558 -72.934803) (xy 334.88657 -72.88566) (xy 334.95994 -72.8433)
			(xy 335.037005 -72.808105) (xy 335.117067 -72.780396) (xy 335.1994 -72.760422) (xy 335.283259 -72.748365)
			(xy 335.367884 -72.744334) (xy 335.452509 -72.748365) (xy 335.536368 -72.760422) (xy 335.618701 -72.780396)
			(xy 335.698763 -72.808105) (xy 335.775828 -72.8433) (xy 335.849198 -72.88566) (xy 335.91821 -72.934803)
			(xy 335.982238 -72.990284) (xy 336.040703 -73.051599) (xy 336.093074 -73.118195) (xy 336.138877 -73.189467)
			(xy 336.177699 -73.26477) (xy 336.209187 -73.343422) (xy 336.233055 -73.424712) (xy 336.249089 -73.507902)
			(xy 336.257142 -73.592239) (xy 336.257646 -73.6346) (xy 336.257142 -73.676961) (xy 336.249089 -73.761298)
			(xy 336.233055 -73.844488) (xy 336.209187 -73.925778) (xy 336.177699 -74.00443) (xy 336.138877 -74.079733)
			(xy 336.093074 -74.151005) (xy 336.040703 -74.217601) (xy 335.982238 -74.278916) (xy 335.91821 -74.334397)
			(xy 335.849198 -74.38354) (xy 335.775828 -74.4259) (xy 335.698763 -74.461095) (xy 335.618701 -74.488804)
			(xy 335.536368 -74.508778) (xy 335.452509 -74.520835) (xy 335.367884 -74.524867) (xy 335.283259 -74.520835)
			(xy 335.1994 -74.508778) (xy 335.117067 -74.488804) (xy 335.037005 -74.461095) (xy 334.95994 -74.4259)
			(xy 334.88657 -74.38354) (xy 334.817558 -74.334397) (xy 334.75353 -74.278916) (xy 334.695065 -74.217601)
			(xy 334.642694 -74.151005) (xy 334.596891 -74.079733) (xy 334.558069 -74.00443) (xy 334.526581 -73.925778)
			(xy 334.502713 -73.844488) (xy 334.486679 -73.761298) (xy 334.478626 -73.676961) (xy 325.12 -73.676961)
			(xy 325.12 -79.4766) (xy 331.266292 -79.4766) (xy 331.266292 -79.476092) (xy 331.266898 -79.42976)
			(xy 331.276569 -79.337602) (xy 331.295765 -79.246948) (xy 331.324277 -79.158779) (xy 331.342492 -79.116174)
			(xy 331.346298 -79.106232) (xy 331.346298 -79.084968) (xy 331.342492 -79.075026) (xy 331.324247 -79.032364)
			(xy 331.295703 -78.944071) (xy 331.27651 -78.853286) (xy 331.266877 -78.760996) (xy 331.266292 -78.7146)
			(xy 331.266875 -78.668204) (xy 331.27652 -78.575916) (xy 331.295716 -78.485132) (xy 331.324254 -78.396839)
			(xy 331.342492 -78.354174) (xy 331.346298 -78.344232) (xy 331.346298 -78.322968) (xy 331.342492 -78.313026)
			(xy 331.324247 -78.270364) (xy 331.295703 -78.182071) (xy 331.27651 -78.091286) (xy 331.266877 -77.998996)
			(xy 331.266292 -77.9526) (xy 331.266875 -77.906204) (xy 331.27652 -77.813916) (xy 331.295716 -77.723132)
			(xy 331.324254 -77.634839) (xy 331.342492 -77.592174) (xy 331.346298 -77.582232) (xy 331.346298 -77.560968)
			(xy 331.342492 -77.551026) (xy 331.324247 -77.508364) (xy 331.295703 -77.420071) (xy 331.27651 -77.329286)
			(xy 331.266877 -77.236996) (xy 331.266292 -77.1906) (xy 331.266875 -77.144204) (xy 331.27652 -77.051916)
			(xy 331.295716 -76.961132) (xy 331.324254 -76.872839) (xy 331.342492 -76.830174) (xy 331.346298 -76.820232)
			(xy 331.346298 -76.798968) (xy 331.342492 -76.789026) (xy 331.32427 -76.746423) (xy 331.295752 -76.658256)
			(xy 331.27656 -76.5676) (xy 331.2669 -76.47544) (xy 331.266292 -76.429108) (xy 331.266292 -76.4286)
			(xy 331.266767 -76.387498) (xy 331.274352 -76.305643) (xy 331.289457 -76.224838) (xy 331.311953 -76.145771)
			(xy 331.341649 -76.069117) (xy 331.378291 -75.99553) (xy 331.421566 -75.925638) (xy 331.471106 -75.860037)
			(xy 331.526487 -75.799287) (xy 331.587237 -75.743906) (xy 331.652838 -75.694366) (xy 331.72273 -75.651091)
			(xy 331.796317 -75.614449) (xy 331.872971 -75.584753) (xy 331.952038 -75.562257) (xy 332.032843 -75.547152)
			(xy 332.114698 -75.539567) (xy 332.1558 -75.539092) (xy 332.156308 -75.539092) (xy 332.20264 -75.539698)
			(xy 332.294798 -75.549369) (xy 332.385452 -75.568565) (xy 332.473621 -75.597077) (xy 332.516226 -75.615292)
			(xy 332.526168 -75.619098) (xy 332.547432 -75.619098) (xy 332.557374 -75.615292) (xy 332.600036 -75.597047)
			(xy 332.688329 -75.568503) (xy 332.779114 -75.54931) (xy 332.871404 -75.539677) (xy 332.9178 -75.539092)
			(xy 332.964196 -75.539675) (xy 333.056484 -75.54932) (xy 333.147268 -75.568516) (xy 333.235561 -75.597054)
			(xy 333.278226 -75.615292) (xy 333.288168 -75.619098) (xy 333.309432 -75.619098) (xy 333.319374 -75.615292)
			(xy 333.362036 -75.597047) (xy 333.450329 -75.568503) (xy 333.541114 -75.54931) (xy 333.633404 -75.539677)
			(xy 333.6798 -75.539092) (xy 333.726196 -75.539675) (xy 333.818484 -75.54932) (xy 333.909268 -75.568516)
			(xy 333.997561 -75.597054) (xy 334.040226 -75.615292) (xy 334.050168 -75.619098) (xy 334.071432 -75.619098)
			(xy 334.081374 -75.615292) (xy 334.124036 -75.597047) (xy 334.212329 -75.568503) (xy 334.303114 -75.54931)
			(xy 334.395404 -75.539677) (xy 334.4418 -75.539092) (xy 334.488196 -75.539675) (xy 334.580484 -75.54932)
			(xy 334.671268 -75.568516) (xy 334.759561 -75.597054) (xy 334.802226 -75.615292) (xy 334.812168 -75.619098)
			(xy 334.833432 -75.619098) (xy 334.843374 -75.615292) (xy 334.885977 -75.59707) (xy 334.974144 -75.568552)
			(xy 335.0648 -75.54936) (xy 335.15696 -75.5397) (xy 335.203292 -75.539092) (xy 335.2038 -75.539092)
			(xy 335.244902 -75.539567) (xy 335.326757 -75.547152) (xy 335.407562 -75.562257) (xy 335.486629 -75.584753)
			(xy 335.563283 -75.614449) (xy 335.63687 -75.651091) (xy 335.706762 -75.694366) (xy 335.772363 -75.743906)
			(xy 335.833113 -75.799287) (xy 335.888494 -75.860037) (xy 335.938034 -75.925638) (xy 335.981309 -75.99553)
			(xy 336.017951 -76.069117) (xy 336.047647 -76.145771) (xy 336.070143 -76.224838) (xy 336.085248 -76.305643)
			(xy 336.085697 -76.31049) (xy 467.50986 -76.31049) (xy 467.50986 -76.309982) (xy 467.510348 -76.255884)
			(xy 467.518633 -76.148004) (xy 467.53516 -76.041077) (xy 467.559833 -75.935731) (xy 467.592506 -75.832585)
			(xy 467.632987 -75.732246) (xy 467.681038 -75.635305) (xy 467.736376 -75.54233) (xy 467.798677 -75.45387)
			(xy 467.867573 -75.370444) (xy 467.942659 -75.292543) (xy 468.023495 -75.220625) (xy 468.109603 -75.155112)
			(xy 468.154766 -75.125326) (xy 468.165688 -75.118214) (xy 468.178134 -75.095608) (xy 468.178134 -74.984356)
			(xy 468.165688 -74.96175) (xy 468.154766 -74.954638) (xy 468.109587 -74.924876) (xy 468.023479 -74.85936)
			(xy 467.942644 -74.787439) (xy 467.867558 -74.709536) (xy 467.798662 -74.626108) (xy 467.736361 -74.537647)
			(xy 467.681021 -74.444672) (xy 467.632969 -74.347729) (xy 467.592485 -74.24739) (xy 467.559809 -74.144244)
			(xy 467.535133 -74.038897) (xy 467.518601 -73.93197) (xy 467.510312 -73.824089) (xy 467.510312 -73.715891)
			(xy 467.518604 -73.608011) (xy 467.535137 -73.501083) (xy 467.559815 -73.395737) (xy 467.592492 -73.292591)
			(xy 467.632977 -73.192253) (xy 467.681031 -73.095311) (xy 467.736372 -73.002337) (xy 467.798674 -72.913876)
			(xy 467.867571 -72.830449) (xy 467.942659 -72.752547) (xy 468.023494 -72.680628) (xy 468.109603 -72.615113)
			(xy 468.154766 -72.585326) (xy 468.165688 -72.578214) (xy 468.178134 -72.555608) (xy 468.178134 -72.444356)
			(xy 468.165688 -72.42175) (xy 468.154766 -72.414638) (xy 468.109587 -72.384876) (xy 468.023479 -72.31936)
			(xy 467.942644 -72.247439) (xy 467.867558 -72.169536) (xy 467.798662 -72.086108) (xy 467.736361 -71.997647)
			(xy 467.681021 -71.904672) (xy 467.632969 -71.807729) (xy 467.592485 -71.70739) (xy 467.559809 -71.604244)
			(xy 467.535133 -71.498897) (xy 467.518601 -71.39197) (xy 467.510312 -71.284089) (xy 467.510312 -71.175891)
			(xy 467.518604 -71.068011) (xy 467.535137 -70.961083) (xy 467.559815 -70.855737) (xy 467.592492 -70.752591)
			(xy 467.632977 -70.652253) (xy 467.681031 -70.555311) (xy 467.736372 -70.462337) (xy 467.798674 -70.373876)
			(xy 467.867571 -70.290449) (xy 467.942659 -70.212547) (xy 468.023494 -70.140628) (xy 468.109603 -70.075113)
			(xy 468.154766 -70.045326) (xy 468.165688 -70.038214) (xy 468.178134 -70.015608) (xy 468.178134 -69.904356)
			(xy 468.165688 -69.88175) (xy 468.154766 -69.874638) (xy 468.109595 -69.844866) (xy 468.023492 -69.779347)
			(xy 467.942663 -69.707424) (xy 467.867582 -69.629519) (xy 467.798691 -69.54609) (xy 467.736395 -69.457628)
			(xy 467.681059 -69.364653) (xy 467.633011 -69.267711) (xy 467.592531 -69.167373) (xy 467.559858 -69.064228)
			(xy 467.535184 -68.958884) (xy 467.518654 -68.851958) (xy 467.510366 -68.74408) (xy 467.50986 -68.689982)
			(xy 467.510314 -68.63723) (xy 467.518198 -68.532021) (xy 467.533923 -68.427695) (xy 467.557398 -68.324836)
			(xy 467.588494 -68.224019) (xy 467.627036 -68.125806) (xy 467.672809 -68.030749) (xy 467.725557 -67.939377)
			(xy 467.784984 -67.852202) (xy 467.85076 -67.769712) (xy 467.922515 -67.692367) (xy 467.99985 -67.6206)
			(xy 468.08233 -67.554812) (xy 468.169496 -67.495371) (xy 468.26086 -67.442609) (xy 468.35591 -67.396822)
			(xy 468.454117 -67.358265) (xy 468.554929 -67.327154) (xy 468.657785 -67.303662) (xy 468.762108 -67.287922)
			(xy 468.867316 -67.280022) (xy 468.920068 -67.27952) (xy 468.971968 -67.279989) (xy 469.075487 -67.287612)
			(xy 469.178165 -67.302827) (xy 469.279447 -67.325552) (xy 469.378783 -67.355664) (xy 469.475635 -67.392998)
			(xy 469.56948 -67.437354) (xy 469.659809 -67.488491) (xy 469.746133 -67.546132) (xy 469.827985 -67.609965)
			(xy 469.904921 -67.679645) (xy 469.976524 -67.754793) (xy 470.042407 -67.835004) (xy 470.102214 -67.919842)
			(xy 470.15562 -68.008849) (xy 470.1794 -68.054982) (xy 470.18575 -68.067936) (xy 470.210134 -68.082922)
			(xy 470.330022 -68.082922) (xy 470.354406 -68.067936) (xy 470.360756 -68.054982) (xy 470.38451 -68.008836)
			(xy 470.437926 -67.919837) (xy 470.497742 -67.835006) (xy 470.563632 -67.754803) (xy 470.635241 -67.679661)
			(xy 470.71218 -67.609987) (xy 470.794033 -67.546158) (xy 470.880358 -67.48852) (xy 470.970687 -67.437385)
			(xy 471.064531 -67.393029) (xy 471.161382 -67.355693) (xy 471.260716 -67.325578) (xy 471.361995 -67.302848)
			(xy 471.464671 -67.287626) (xy 471.568189 -67.279993) (xy 471.620088 -67.27952) (xy 471.67283 -67.279996)
			(xy 471.77802 -67.287878) (xy 471.882327 -67.303597) (xy 471.985167 -67.327066) (xy 472.085967 -67.358155)
			(xy 472.184161 -67.396688) (xy 472.279202 -67.442451) (xy 472.370557 -67.495188) (xy 472.457717 -67.554604)
			(xy 472.540193 -67.620366) (xy 472.617524 -67.692108) (xy 472.689278 -67.769427) (xy 472.755055 -67.851892)
			(xy 472.814485 -67.939041) (xy 472.867238 -68.030388) (xy 472.913017 -68.125421) (xy 472.951567 -68.223609)
			(xy 472.982672 -68.324403) (xy 473.006159 -68.427239) (xy 473.021896 -68.531543) (xy 473.029795 -68.636732)
			(xy 473.030296 -68.689474) (xy 473.030296 -68.689982) (xy 473.029754 -68.744079) (xy 473.021472 -68.851956)
			(xy 473.004948 -68.958882) (xy 472.980279 -69.064227) (xy 472.94761 -69.167371) (xy 472.907133 -69.267709)
			(xy 472.859087 -69.36465) (xy 472.803753 -69.457625) (xy 472.741457 -69.546085) (xy 472.672566 -69.629512)
			(xy 472.597485 -69.707415) (xy 472.516654 -69.779335) (xy 472.43055 -69.84485) (xy 472.38539 -69.874638)
			(xy 472.374468 -69.88175) (xy 472.362022 -69.904356) (xy 472.362022 -70.015608) (xy 472.374468 -70.038214)
			(xy 472.38539 -70.045326) (xy 472.430534 -70.075139) (xy 472.516638 -70.140654) (xy 472.597469 -70.212573)
			(xy 472.672552 -70.290475) (xy 472.741445 -70.373901) (xy 472.803743 -70.462359) (xy 472.859081 -70.555332)
			(xy 472.907132 -70.652271) (xy 472.947614 -70.752607) (xy 472.980289 -70.855749) (xy 473.004965 -70.961092)
			(xy 473.021497 -71.068016) (xy 473.029788 -71.175893) (xy 473.029789 -71.284088) (xy 473.021499 -71.391964)
			(xy 473.004969 -71.498888) (xy 472.980294 -71.604232) (xy 472.94762 -71.707375) (xy 472.90714 -71.807711)
			(xy 472.85909 -71.904651) (xy 472.803754 -71.997624) (xy 472.741457 -72.086084) (xy 472.672565 -72.16951)
			(xy 472.597483 -72.247413) (xy 472.516653 -72.319334) (xy 472.43055 -72.38485) (xy 472.38539 -72.414638)
			(xy 472.374468 -72.42175) (xy 472.362022 -72.444356) (xy 472.362022 -72.555608) (xy 472.374468 -72.578214)
			(xy 472.38539 -72.585326) (xy 472.430534 -72.615139) (xy 472.516638 -72.680654) (xy 472.597469 -72.752573)
			(xy 472.672552 -72.830475) (xy 472.741445 -72.913901) (xy 472.803743 -73.002359) (xy 472.859081 -73.095332)
			(xy 472.907132 -73.192271) (xy 472.947614 -73.292607) (xy 472.980289 -73.395749) (xy 473.004965 -73.501092)
			(xy 473.021497 -73.608016) (xy 473.029788 -73.715893) (xy 473.029789 -73.824088) (xy 473.021499 -73.931964)
			(xy 473.004969 -74.038888) (xy 472.980294 -74.144232) (xy 472.94762 -74.247375) (xy 472.90714 -74.347711)
			(xy 472.85909 -74.444651) (xy 472.803754 -74.537624) (xy 472.741457 -74.626084) (xy 472.672565 -74.70951)
			(xy 472.597483 -74.787413) (xy 472.516653 -74.859334) (xy 472.43055 -74.92485) (xy 472.38539 -74.954638)
			(xy 472.374468 -74.96175) (xy 472.362022 -74.984356) (xy 472.362022 -75.095608) (xy 472.374468 -75.118214)
			(xy 472.38539 -75.125326) (xy 472.430558 -75.155102) (xy 472.516659 -75.220622) (xy 472.597487 -75.292546)
			(xy 472.672567 -75.370452) (xy 472.741457 -75.45388) (xy 472.803753 -75.542342) (xy 472.859088 -75.635317)
			(xy 472.907137 -75.732257) (xy 472.947617 -75.832595) (xy 472.980291 -75.935738) (xy 473.004966 -76.041082)
			(xy 473.021498 -76.148007) (xy 473.029789 -76.255884) (xy 473.030296 -76.309982) (xy 473.029752 -76.362732)
			(xy 473.02187 -76.467938) (xy 473.006149 -76.57226) (xy 472.982677 -76.675117) (xy 472.951585 -76.775931)
			(xy 472.913048 -76.874141) (xy 472.867279 -76.969197) (xy 472.814536 -77.060567) (xy 472.755113 -77.147741)
			(xy 472.689342 -77.230231) (xy 472.617592 -77.307575) (xy 472.540263 -77.379343) (xy 472.457787 -77.445131)
			(xy 472.370626 -77.504573) (xy 472.279268 -77.557336) (xy 472.184222 -77.603125) (xy 472.08602 -77.641684)
			(xy 471.985212 -77.672798) (xy 471.882361 -77.696292) (xy 471.778042 -77.712036) (xy 471.672838 -77.71994)
			(xy 471.620088 -77.720444) (xy 471.568188 -77.719978) (xy 471.46467 -77.712352) (xy 471.361992 -77.697134)
			(xy 471.260712 -77.674407) (xy 471.161377 -77.644294) (xy 471.064525 -77.606959) (xy 470.970681 -77.562602)
			(xy 470.880352 -77.511465) (xy 470.794028 -77.453824) (xy 470.712177 -77.389992) (xy 470.635241 -77.320313)
			(xy 470.563637 -77.245166) (xy 470.497753 -77.164956) (xy 470.437945 -77.08012) (xy 470.384537 -76.991115)
			(xy 470.360756 -76.944982) (xy 470.354406 -76.932028) (xy 470.330022 -76.917042) (xy 470.210134 -76.917042)
			(xy 470.18575 -76.932028) (xy 470.1794 -76.944982) (xy 470.155586 -76.991097) (xy 470.102175 -77.080095)
			(xy 470.042364 -77.164927) (xy 469.976479 -77.245131) (xy 469.904875 -77.320274) (xy 469.827941 -77.389949)
			(xy 469.746092 -77.45378) (xy 469.659771 -77.51142) (xy 469.569447 -77.562557) (xy 469.475607 -77.606916)
			(xy 469.37876 -77.644255) (xy 469.279429 -77.674373) (xy 469.178154 -77.697106) (xy 469.075481 -77.712332)
			(xy 468.971966 -77.719969) (xy 468.920068 -77.720444) (xy 468.867327 -77.719946) (xy 468.762139 -77.712062)
			(xy 468.657834 -77.696341) (xy 468.554996 -77.67287) (xy 468.454199 -77.64178) (xy 468.356007 -77.603246)
			(xy 468.260968 -77.557483) (xy 468.169615 -77.504746) (xy 468.082457 -77.445331) (xy 467.999982 -77.37957)
			(xy 467.922652 -77.30783) (xy 467.850898 -77.230513) (xy 467.785122 -77.148051) (xy 467.725691 -77.060904)
			(xy 467.672938 -76.96956) (xy 467.627157 -76.87453) (xy 467.588605 -76.776344) (xy 467.557497 -76.675553)
			(xy 467.534007 -76.572719) (xy 467.518267 -76.468417) (xy 467.510364 -76.363231) (xy 467.50986 -76.31049)
			(xy 336.085697 -76.31049) (xy 336.092833 -76.387498) (xy 336.093308 -76.4286) (xy 336.093308 -76.429108)
			(xy 336.092702 -76.47544) (xy 336.083031 -76.567598) (xy 336.063835 -76.658252) (xy 336.035323 -76.746421)
			(xy 336.017108 -76.789026) (xy 336.013302 -76.798968) (xy 336.013302 -76.820232) (xy 336.017108 -76.830174)
			(xy 336.03533 -76.872777) (xy 336.063848 -76.960944) (xy 336.08304 -77.0516) (xy 336.0927 -77.14376)
			(xy 336.093308 -77.190092) (xy 336.093308 -77.1906) (xy 336.09286 -77.231986) (xy 336.085163 -77.314401)
			(xy 336.069847 -77.395744) (xy 336.047042 -77.475313) (xy 336.016946 -77.552421) (xy 335.97982 -77.6264)
			(xy 335.935983 -77.696612) (xy 335.885816 -77.76245) (xy 335.829751 -77.823344) (xy 335.768274 -77.878768)
			(xy 335.701914 -77.928243) (xy 335.631247 -77.971342) (xy 335.556883 -78.007691) (xy 335.479465 -78.036978)
			(xy 335.399661 -78.058948) (xy 335.358994 -78.066646) (xy 335.34887 -78.068944) (xy 335.331549 -78.080349)
			(xy 335.320144 -78.09767) (xy 335.317846 -78.107794) (xy 335.310093 -78.14883) (xy 335.287881 -78.229342)
			(xy 335.258222 -78.307417) (xy 335.221376 -78.382369) (xy 335.177667 -78.453538) (xy 335.127482 -78.520298)
			(xy 335.07126 -78.58206) (xy 335.009498 -78.638282) (xy 334.942738 -78.688467) (xy 334.871569 -78.732176)
			(xy 334.855653 -78.74) (xy 376.553741 -78.74) (xy 376.557716 -78.629941) (xy 376.569624 -78.520455)
			(xy 376.5894 -78.412114) (xy 376.616943 -78.305483) (xy 376.652108 -78.201117) (xy 376.694712 -78.09956)
			(xy 376.744533 -78.001343) (xy 376.801312 -77.906976) (xy 376.864751 -77.816952) (xy 376.934522 -77.731741)
			(xy 377.010259 -77.651786) (xy 377.091568 -77.577505) (xy 377.178025 -77.509285) (xy 377.269179 -77.44748)
			(xy 377.364556 -77.392415) (xy 377.463657 -77.344375) (xy 377.565966 -77.303611) (xy 377.67095 -77.270336)
			(xy 377.778061 -77.244723) (xy 377.886741 -77.226906) (xy 377.996424 -77.216977) (xy 378.106537 -77.214989)
			(xy 378.216507 -77.220951) (xy 378.32576 -77.234833) (xy 378.433726 -77.256563) (xy 378.539843 -77.286026)
			(xy 378.643557 -77.323069) (xy 378.744328 -77.3675) (xy 378.84163 -77.419087) (xy 378.934956 -77.477559)
			(xy 379.023819 -77.542614) (xy 379.107757 -77.613912) (xy 379.186332 -77.69108) (xy 379.259133 -77.773717)
			(xy 379.325781 -77.861391) (xy 379.38593 -77.953647) (xy 379.439264 -78.050002) (xy 379.485507 -78.149954)
			(xy 379.524417 -78.252982) (xy 379.555791 -78.35855) (xy 379.579466 -78.466106) (xy 379.595318 -78.57509)
			(xy 379.603265 -78.684934) (xy 379.603762 -78.74) (xy 396.111741 -78.74) (xy 396.115716 -78.629941)
			(xy 396.127624 -78.520455) (xy 396.1474 -78.412114) (xy 396.174943 -78.305483) (xy 396.210108 -78.201117)
			(xy 396.252712 -78.09956) (xy 396.302533 -78.001343) (xy 396.359312 -77.906976) (xy 396.422751 -77.816952)
			(xy 396.492522 -77.731741) (xy 396.568259 -77.651786) (xy 396.649568 -77.577505) (xy 396.736025 -77.509285)
			(xy 396.827179 -77.44748) (xy 396.922556 -77.392415) (xy 397.021657 -77.344375) (xy 397.123966 -77.303611)
			(xy 397.22895 -77.270336) (xy 397.336061 -77.244723) (xy 397.444741 -77.226906) (xy 397.554424 -77.216977)
			(xy 397.664537 -77.214989) (xy 397.774507 -77.220951) (xy 397.88376 -77.234833) (xy 397.991726 -77.256563)
			(xy 398.097843 -77.286026) (xy 398.201557 -77.323069) (xy 398.302328 -77.3675) (xy 398.39963 -77.419087)
			(xy 398.492956 -77.477559) (xy 398.581819 -77.542614) (xy 398.665757 -77.613912) (xy 398.744332 -77.69108)
			(xy 398.817133 -77.773717) (xy 398.883781 -77.861391) (xy 398.94393 -77.953647) (xy 398.997264 -78.050002)
			(xy 399.043507 -78.149954) (xy 399.082417 -78.252982) (xy 399.113791 -78.35855) (xy 399.137466 -78.466106)
			(xy 399.153318 -78.57509) (xy 399.161265 -78.684934) (xy 399.161762 -78.74) (xy 399.161265 -78.795066)
			(xy 399.153318 -78.90491) (xy 399.137466 -79.013894) (xy 399.113791 -79.12145) (xy 399.082417 -79.227018)
			(xy 399.043507 -79.330046) (xy 398.997264 -79.429998) (xy 398.94393 -79.526353) (xy 398.883781 -79.618609)
			(xy 398.817133 -79.706283) (xy 398.744332 -79.78892) (xy 398.665757 -79.866088) (xy 398.581819 -79.937386)
			(xy 398.492956 -80.002441) (xy 398.39963 -80.060913) (xy 398.302328 -80.1125) (xy 398.201557 -80.156931)
			(xy 398.097843 -80.193974) (xy 397.991726 -80.223437) (xy 397.88376 -80.245167) (xy 397.774507 -80.259049)
			(xy 397.664537 -80.265011) (xy 397.554424 -80.263023) (xy 397.444741 -80.253094) (xy 397.336061 -80.235277)
			(xy 397.22895 -80.209664) (xy 397.123966 -80.176389) (xy 397.021657 -80.135625) (xy 396.922556 -80.087585)
			(xy 396.827179 -80.03252) (xy 396.736025 -79.970715) (xy 396.649568 -79.902495) (xy 396.568259 -79.828214)
			(xy 396.492522 -79.748259) (xy 396.422751 -79.663048) (xy 396.359312 -79.573024) (xy 396.302533 -79.478657)
			(xy 396.252712 -79.38044) (xy 396.210108 -79.278883) (xy 396.174943 -79.174517) (xy 396.1474 -79.067886)
			(xy 396.127624 -78.959545) (xy 396.115716 -78.850059) (xy 396.111741 -78.74) (xy 379.603762 -78.74)
			(xy 379.603265 -78.795066) (xy 379.595318 -78.90491) (xy 379.579466 -79.013894) (xy 379.555791 -79.12145)
			(xy 379.524417 -79.227018) (xy 379.485507 -79.330046) (xy 379.439264 -79.429998) (xy 379.38593 -79.526353)
			(xy 379.325781 -79.618609) (xy 379.259133 -79.706283) (xy 379.186332 -79.78892) (xy 379.107757 -79.866088)
			(xy 379.023819 -79.937386) (xy 378.934956 -80.002441) (xy 378.84163 -80.060913) (xy 378.744328 -80.1125)
			(xy 378.643557 -80.156931) (xy 378.539843 -80.193974) (xy 378.433726 -80.223437) (xy 378.32576 -80.245167)
			(xy 378.216507 -80.259049) (xy 378.106537 -80.265011) (xy 377.996424 -80.263023) (xy 377.886741 -80.253094)
			(xy 377.778061 -80.235277) (xy 377.67095 -80.209664) (xy 377.565966 -80.176389) (xy 377.463657 -80.135625)
			(xy 377.364556 -80.087585) (xy 377.269179 -80.03252) (xy 377.178025 -79.970715) (xy 377.091568 -79.902495)
			(xy 377.010259 -79.828214) (xy 376.934522 -79.748259) (xy 376.864751 -79.663048) (xy 376.801312 -79.573024)
			(xy 376.744533 -79.478657) (xy 376.694712 -79.38044) (xy 376.652108 -79.278883) (xy 376.616943 -79.174517)
			(xy 376.5894 -79.067886) (xy 376.569624 -78.959545) (xy 376.557716 -78.850059) (xy 376.553741 -78.74)
			(xy 334.855653 -78.74) (xy 334.796617 -78.769022) (xy 334.718542 -78.798681) (xy 334.63803 -78.820893)
			(xy 334.596994 -78.828646) (xy 334.58687 -78.830944) (xy 334.569549 -78.842349) (xy 334.558144 -78.85967)
			(xy 334.555846 -78.869794) (xy 334.548093 -78.91083) (xy 334.525881 -78.991342) (xy 334.496222 -79.069417)
			(xy 334.459376 -79.144369) (xy 334.415667 -79.215538) (xy 334.365482 -79.282298) (xy 334.30926 -79.34406)
			(xy 334.247498 -79.400282) (xy 334.180738 -79.450467) (xy 334.109569 -79.494176) (xy 334.034617 -79.531022)
			(xy 333.956542 -79.560681) (xy 333.87603 -79.582893) (xy 333.834994 -79.590646) (xy 333.82487 -79.592944)
			(xy 333.807549 -79.604349) (xy 333.796144 -79.62167) (xy 333.793846 -79.631794) (xy 333.786139 -79.672459)
			(xy 333.764175 -79.752265) (xy 333.734893 -79.829685) (xy 333.698547 -79.904051) (xy 333.655451 -79.97472)
			(xy 333.605977 -80.04108) (xy 333.550554 -80.102559) (xy 333.489659 -80.158623) (xy 333.423821 -80.208789)
			(xy 333.353608 -80.252624) (xy 333.279627 -80.289747) (xy 333.202517 -80.319838) (xy 333.122946 -80.342637)
			(xy 333.041601 -80.357947) (xy 332.959186 -80.365635) (xy 332.9178 -80.366108) (xy 332.917292 -80.366108)
			(xy 332.87096 -80.365502) (xy 332.778802 -80.355831) (xy 332.688148 -80.336635) (xy 332.599979 -80.308123)
			(xy 332.557374 -80.289908) (xy 332.547432 -80.286102) (xy 332.526168 -80.286102) (xy 332.516226 -80.289908)
			(xy 332.473623 -80.30813) (xy 332.385456 -80.336648) (xy 332.2948 -80.35584) (xy 332.20264 -80.3655)
			(xy 332.156308 -80.366108) (xy 332.1558 -80.366108) (xy 332.114698 -80.365633) (xy 332.032843 -80.358048)
			(xy 331.952038 -80.342943) (xy 331.872971 -80.320447) (xy 331.796317 -80.290751) (xy 331.72273 -80.254109)
			(xy 331.652838 -80.210834) (xy 331.587237 -80.161294) (xy 331.526487 -80.105913) (xy 331.471106 -80.045163)
			(xy 331.421566 -79.979562) (xy 331.378291 -79.90967) (xy 331.341649 -79.836083) (xy 331.311953 -79.759429)
			(xy 331.289457 -79.680362) (xy 331.274352 -79.599557) (xy 331.266767 -79.517702) (xy 331.266292 -79.4766)
			(xy 325.12 -79.4766) (xy 325.12 -79.883) (xy 325.119461 -79.916259) (xy 325.110775 -79.982209) (xy 325.093553 -80.04646)
			(xy 325.068089 -80.107911) (xy 325.034818 -80.165512) (xy 324.994312 -80.218276) (xy 324.971156 -80.242156)
			(xy 324.336156 -80.877156) (xy 324.312271 -80.900308) (xy 324.259511 -80.940821) (xy 324.201912 -80.974097)
			(xy 324.140461 -80.999566) (xy 324.07621 -81.016791) (xy 324.01026 -81.025479) (xy 323.977 -81.026)
			(xy 311.395364 -81.026) (xy 311.362104 -81.025484) (xy 311.296153 -81.016794) (xy 311.231902 -80.999567)
			(xy 311.17045 -80.974099) (xy 311.11285 -80.940824) (xy 311.060087 -80.900314) (xy 311.036208 -80.877156)
			(xy 310.362854 -80.203802) (xy 310.339678 -80.179939) (xy 310.299167 -80.127175) (xy 310.265894 -80.069571)
			(xy 310.240429 -80.008116) (xy 310.223209 -79.943861) (xy 310.214528 -79.877907) (xy 310.21401 -79.844646)
			(xy 310.21401 -68.489322) (xy 310.213597 -68.479251) (xy 310.20587 -68.460652) (xy 310.199024 -68.453254)
			(xy 309.613046 -67.867276) (xy 309.605627 -67.86046) (xy 309.587042 -67.852727) (xy 309.576978 -67.85229)
			(xy 308.297834 -67.85229) (xy 308.288617 -67.852597) (xy 308.27136 -67.859068) (xy 308.25753 -67.87125)
			(xy 308.252876 -67.879214) (xy 308.23281 -67.915996) (xy 308.186744 -67.985991) (xy 308.134301 -68.051344)
			(xy 308.075945 -68.111477) (xy 308.012194 -68.165856) (xy 307.943612 -68.214001) (xy 307.870808 -68.255483)
			(xy 307.794425 -68.289937) (xy 307.715142 -68.317056) (xy 307.633659 -68.3366) (xy 307.550701 -68.348396)
			(xy 307.467 -68.35234) (xy 307.383299 -68.348396) (xy 307.300341 -68.3366) (xy 307.218858 -68.317056)
			(xy 307.139575 -68.289937) (xy 307.063192 -68.255483) (xy 306.990388 -68.214001) (xy 306.921806 -68.165856)
			(xy 306.858055 -68.111477) (xy 306.799699 -68.051344) (xy 306.747256 -67.985991) (xy 306.70119 -67.915996)
			(xy 306.681124 -67.879214) (xy 306.676465 -67.87127) (xy 306.6626 -67.859162) (xy 306.645369 -67.852685)
			(xy 306.636166 -67.85229) (xy 305.487578 -67.85229) (xy 305.476114 -67.85278) (xy 305.455445 -67.862699)
			(xy 305.44113 -67.880606) (xy 305.438048 -67.89166) (xy 305.428779 -67.929708) (xy 305.404431 -68.004145)
			(xy 305.37363 -68.076151) (xy 305.355498 -68.110862) (xy 305.350086 -68.12233) (xy 305.350082 -68.147656)
			(xy 305.355498 -68.159122) (xy 305.375775 -68.198007) (xy 305.409465 -68.27898) (xy 305.43503 -68.362874)
			(xy 305.452222 -68.448875) (xy 305.460875 -68.536149) (xy 305.461416 -68.58) (xy 305.460899 -68.623763)
			(xy 305.4523 -68.710865) (xy 305.435194 -68.796702) (xy 305.409747 -68.880447) (xy 305.376204 -68.961289)
			(xy 305.356006 -69.000116) (xy 305.350776 -69.011509) (xy 305.350889 -69.036543) (xy 305.35626 -69.047868)
			(xy 305.376521 -69.086782) (xy 305.410157 -69.167817) (xy 305.435668 -69.251765) (xy 305.452807 -69.337814)
			(xy 305.461409 -69.42513) (xy 305.461924 -69.469) (xy 305.461407 -69.512819) (xy 305.452768 -69.60003)
			(xy 305.435612 -69.685973) (xy 305.410106 -69.769817) (xy 305.376495 -69.850754) (xy 305.35626 -69.889624)
			(xy 305.35095 -69.90098) (xy 305.35095 -69.92602) (xy 305.35626 -69.937376) (xy 305.376509 -69.976241)
			(xy 305.410141 -70.057171) (xy 305.435652 -70.141016) (xy 305.452795 -70.226963) (xy 305.461403 -70.31418)
			(xy 305.461924 -70.358) (xy 305.46142 -70.400397) (xy 305.45336 -70.484807) (xy 305.437312 -70.568068)
			(xy 305.413423 -70.649427) (xy 305.381908 -70.728147) (xy 305.343054 -70.803515) (xy 305.297211 -70.874848)
			(xy 305.244795 -70.9415) (xy 305.18628 -71.002868) (xy 305.122198 -71.058396) (xy 305.053127 -71.107581)
			(xy 304.979693 -71.149978) (xy 304.902562 -71.185203) (xy 304.822432 -71.212936) (xy 304.740028 -71.232927)
			(xy 304.656098 -71.244994) (xy 304.5714 -71.249029) (xy 304.486702 -71.244994) (xy 304.402772 -71.232927)
			(xy 304.320368 -71.212936) (xy 304.240238 -71.185203) (xy 304.163107 -71.149978) (xy 304.089673 -71.107581)
			(xy 304.020602 -71.058396) (xy 303.95652 -71.002868) (xy 303.898005 -70.9415) (xy 303.845589 -70.874848)
			(xy 303.799746 -70.803515) (xy 303.760892 -70.728147) (xy 303.729377 -70.649427) (xy 303.705488 -70.568068)
			(xy 303.68944 -70.484807) (xy 303.68138 -70.400397) (xy 303.680876 -70.358) (xy 303.681393 -70.314181)
			(xy 303.690032 -70.22697) (xy 303.707188 -70.141027) (xy 303.732694 -70.057183) (xy 303.766305 -69.976246)
			(xy 303.78654 -69.937376) (xy 303.79185 -69.92602) (xy 303.79185 -69.90098) (xy 303.78654 -69.889624)
			(xy 303.766291 -69.850759) (xy 303.732659 -69.769829) (xy 303.707148 -69.685984) (xy 303.690005 -69.600037)
			(xy 303.681397 -69.51282) (xy 303.680876 -69.469) (xy 303.681366 -69.425129) (xy 303.689958 -69.337809)
			(xy 303.707097 -69.251758) (xy 303.732618 -69.167811) (xy 303.766273 -69.08678) (xy 303.78654 -69.047868)
			(xy 303.791948 -69.036553) (xy 303.792061 -69.0115) (xy 303.786794 -69.000116) (xy 303.766602 -68.961287)
			(xy 303.733053 -68.880446) (xy 303.707604 -68.796703) (xy 303.6905 -68.710865) (xy 303.681907 -68.623763)
			(xy 303.681384 -68.58) (xy 303.681935 -68.536149) (xy 303.690574 -68.448872) (xy 303.707759 -68.36287)
			(xy 303.733323 -68.278975) (xy 303.767017 -68.198003) (xy 303.787302 -68.159122) (xy 303.792725 -68.147658)
			(xy 303.792722 -68.122328) (xy 303.787302 -68.110862) (xy 303.769177 -68.076148) (xy 303.738379 -68.004141)
			(xy 303.714026 -67.929707) (xy 303.704752 -67.89166) (xy 303.701577 -67.88066) (xy 303.68727 -67.862821)
			(xy 303.666655 -67.852924) (xy 303.655222 -67.85229) (xy 302.506634 -67.85229) (xy 302.497417 -67.852597)
			(xy 302.48016 -67.859068) (xy 302.46633 -67.87125) (xy 302.461676 -67.879214) (xy 302.44161 -67.915996)
			(xy 302.395544 -67.985991) (xy 302.343101 -68.051344) (xy 302.284745 -68.111477) (xy 302.220994 -68.165856)
			(xy 302.152412 -68.214001) (xy 302.079608 -68.255483) (xy 302.003225 -68.289937) (xy 301.923942 -68.317056)
			(xy 301.842459 -68.3366) (xy 301.759501 -68.348396) (xy 301.6758 -68.35234) (xy 301.592099 -68.348396)
			(xy 301.509141 -68.3366) (xy 301.427658 -68.317056) (xy 301.348375 -68.289937) (xy 301.271992 -68.255483)
			(xy 301.199188 -68.214001) (xy 301.130606 -68.165856) (xy 301.066855 -68.111477) (xy 301.008499 -68.051344)
			(xy 300.956056 -67.985991) (xy 300.90999 -67.915996) (xy 300.889924 -67.879214) (xy 300.885265 -67.87127)
			(xy 300.8714 -67.859162) (xy 300.854169 -67.852685) (xy 300.844966 -67.85229) (xy 298.591224 -67.85229)
			(xy 298.578545 -67.852998) (xy 298.556276 -67.865134) (xy 298.548806 -67.875404) (xy 298.495212 -67.957446)
			(xy 298.49318 -67.982846) (xy 298.498514 -67.994784) (xy 298.516563 -68.037163) (xy 298.544786 -68.124852)
			(xy 298.563783 -68.21499) (xy 298.57335 -68.306611) (xy 298.573952 -68.35267) (xy 298.573952 -68.35394)
			(xy 298.573428 -68.396357) (xy 298.565359 -68.480805) (xy 298.549288 -68.564102) (xy 298.525362 -68.645491)
			(xy 298.493797 -68.724233) (xy 298.454881 -68.799613) (xy 298.408966 -68.870947) (xy 298.35647 -68.937587)
			(xy 298.297869 -68.998927) (xy 298.266104 -69.02704) (xy 298.258204 -69.034606) (xy 298.249106 -69.05447)
			(xy 298.248578 -69.065394) (xy 298.248578 -69.14261) (xy 298.2491 -69.153536) (xy 298.258191 -69.173411)
			(xy 298.266104 -69.180964) (xy 298.297847 -69.209103) (xy 298.356452 -69.270438) (xy 298.408954 -69.337073)
			(xy 298.454874 -69.408403) (xy 298.493797 -69.48378) (xy 298.525369 -69.562519) (xy 298.549303 -69.643905)
			(xy 298.565381 -69.7272) (xy 298.573459 -69.811648) (xy 298.573952 -69.854064) (xy 298.573448 -69.896412)
			(xy 298.565397 -69.980726) (xy 298.549368 -70.063892) (xy 298.525507 -70.145159) (xy 298.494028 -70.223789)
			(xy 298.455217 -70.29907) (xy 298.409427 -70.370322) (xy 298.357071 -70.436898) (xy 298.298623 -70.498196)
			(xy 298.234613 -70.553661) (xy 298.165621 -70.60279) (xy 298.092271 -70.645139) (xy 298.015228 -70.680323)
			(xy 297.935189 -70.708025) (xy 297.85288 -70.727993) (xy 297.769045 -70.740046) (xy 297.684444 -70.744077)
			(xy 297.599843 -70.740046) (xy 297.516008 -70.727993) (xy 297.433699 -70.708025) (xy 297.35366 -70.680323)
			(xy 297.276617 -70.645139) (xy 297.203267 -70.60279) (xy 297.134275 -70.553661) (xy 297.070265 -70.498196)
			(xy 297.011817 -70.436898) (xy 296.959461 -70.370322) (xy 296.913671 -70.29907) (xy 296.87486 -70.223789)
			(xy 296.843381 -70.145159) (xy 296.81952 -70.063892) (xy 296.803491 -69.980726) (xy 296.79544 -69.896412)
			(xy 296.794936 -69.854064) (xy 296.795467 -69.811648) (xy 296.803535 -69.727199) (xy 296.819606 -69.643903)
			(xy 296.843531 -69.562514) (xy 296.875095 -69.483772) (xy 296.91401 -69.408392) (xy 296.959924 -69.337058)
			(xy 297.012419 -69.270418) (xy 297.071019 -69.209078) (xy 297.102784 -69.180964) (xy 297.110696 -69.173409)
			(xy 297.119784 -69.153536) (xy 297.12031 -69.14261) (xy 297.12031 -69.065394) (xy 297.119789 -69.054467)
			(xy 297.110698 -69.034593) (xy 297.102784 -69.02704) (xy 297.07104 -68.998902) (xy 297.012435 -68.937566)
			(xy 296.959935 -68.870931) (xy 296.914014 -68.799601) (xy 296.875092 -68.724224) (xy 296.84352 -68.645485)
			(xy 296.819586 -68.564099) (xy 296.803507 -68.480804) (xy 296.795429 -68.396356) (xy 296.794936 -68.35394)
			(xy 296.795441 -68.312106) (xy 296.803292 -68.228806) (xy 296.818929 -68.146612) (xy 296.842213 -68.066249)
			(xy 296.872939 -67.988426) (xy 296.910835 -67.913832) (xy 296.955566 -67.843124) (xy 297.006738 -67.776929)
			(xy 297.063899 -67.71583) (xy 297.126543 -67.660367) (xy 297.194117 -67.61103) (xy 297.266025 -67.568255)
			(xy 297.34163 -67.532419) (xy 297.420267 -67.50384) (xy 297.501238 -67.482769) (xy 297.542458 -67.475608)
			(xy 297.556682 -67.473322) (xy 297.578272 -67.45478) (xy 297.61053 -67.354958) (xy 297.612969 -67.345949)
			(xy 297.611952 -67.32733) (xy 297.60437 -67.310294) (xy 297.598084 -67.303396) (xy 296.363644 -66.068956)
			(xy 296.340492 -66.045071) (xy 296.299979 -65.992311) (xy 296.266703 -65.934712) (xy 296.241234 -65.873261)
			(xy 296.224009 -65.80901) (xy 296.215321 -65.74306) (xy 296.2148 -65.7098) (xy 296.2148 -62.258194)
			(xy 296.214404 -62.248121) (xy 296.206666 -62.229522) (xy 296.199814 -62.222126) (xy 293.225474 -59.247786)
			(xy 293.218079 -59.24094) (xy 293.199476 -59.233224) (xy 293.189406 -59.2328) (xy 282.2448 -59.2328)
			(xy 282.211541 -59.232261) (xy 282.145591 -59.223575) (xy 282.08134 -59.206353) (xy 282.019889 -59.180889)
			(xy 281.962288 -59.147618) (xy 281.909524 -59.107112) (xy 281.885644 -59.083956) (xy 274.563586 -51.761898)
			(xy 274.556185 -51.755059) (xy 274.537586 -51.747339) (xy 274.527518 -51.746912) (xy 266.648184 -51.746912)
			(xy 266.638113 -51.747326) (xy 266.619516 -51.755055) (xy 266.612116 -51.761898) (xy 265.219688 -53.154326)
			(xy 265.212843 -53.161722) (xy 265.205126 -53.180324) (xy 265.204702 -53.190394) (xy 265.204702 -57.912)
			(xy 268.756388 -57.912) (xy 268.760418 -57.827399) (xy 268.772471 -57.743564) (xy 268.792439 -57.661255)
			(xy 268.820141 -57.581216) (xy 268.855325 -57.504173) (xy 268.897674 -57.430823) (xy 268.946803 -57.361831)
			(xy 269.002268 -57.297821) (xy 269.063566 -57.239373) (xy 269.130142 -57.187017) (xy 269.201394 -57.141227)
			(xy 269.276675 -57.102416) (xy 269.355305 -57.070937) (xy 269.436572 -57.047076) (xy 269.519738 -57.031047)
			(xy 269.604052 -57.022996) (xy 269.6464 -57.022492) (xy 269.646908 -57.022492) (xy 269.69324 -57.023098)
			(xy 269.785398 -57.032769) (xy 269.876052 -57.051965) (xy 269.964221 -57.080477) (xy 270.006826 -57.098692)
			(xy 270.016768 -57.102498) (xy 270.038032 -57.102498) (xy 270.047974 -57.098692) (xy 270.090636 -57.080447)
			(xy 270.178929 -57.051903) (xy 270.269714 -57.03271) (xy 270.362004 -57.023077) (xy 270.4084 -57.022492)
			(xy 270.451753 -57.02298) (xy 270.538049 -57.031388) (xy 270.623118 -57.048154) (xy 270.706152 -57.073118)
			(xy 270.786362 -57.106044) (xy 270.862988 -57.146619) (xy 270.935302 -57.194458) (xy 271.002617 -57.249107)
			(xy 271.064295 -57.310046) (xy 271.092422 -57.34304) (xy 271.099534 -57.351676) (xy 271.119854 -57.361328)
			(xy 271.220946 -57.361328) (xy 271.241266 -57.351676) (xy 271.248378 -57.34304) (xy 271.276524 -57.310064)
			(xy 271.338205 -57.249132) (xy 271.40552 -57.194489) (xy 271.477833 -57.146654) (xy 271.554455 -57.106081)
			(xy 271.634662 -57.073155) (xy 271.717692 -57.048188) (xy 271.802756 -57.031418) (xy 271.889049 -57.023002)
			(xy 271.9324 -57.022492) (xy 271.978796 -57.023075) (xy 272.071084 -57.03272) (xy 272.161868 -57.051916)
			(xy 272.250161 -57.080454) (xy 272.292826 -57.098692) (xy 272.302768 -57.102498) (xy 272.324032 -57.102498)
			(xy 272.333974 -57.098692) (xy 272.376577 -57.08047) (xy 272.464744 -57.051952) (xy 272.5554 -57.03276)
			(xy 272.64756 -57.0231) (xy 272.693892 -57.022492) (xy 272.6944 -57.022492) (xy 272.736748 -57.022996)
			(xy 272.821062 -57.031047) (xy 272.904228 -57.047076) (xy 272.985495 -57.070937) (xy 273.064125 -57.102416)
			(xy 273.139406 -57.141227) (xy 273.210658 -57.187017) (xy 273.277234 -57.239373) (xy 273.338532 -57.297821)
			(xy 273.393997 -57.361831) (xy 273.443126 -57.430823) (xy 273.485475 -57.504173) (xy 273.520659 -57.581216)
			(xy 273.548361 -57.661255) (xy 273.568329 -57.743564) (xy 273.580382 -57.827399) (xy 273.584413 -57.912)
			(xy 273.580382 -57.996601) (xy 273.568329 -58.080436) (xy 273.548361 -58.162745) (xy 273.520659 -58.242784)
			(xy 273.485475 -58.319827) (xy 273.443126 -58.393177) (xy 273.393997 -58.462169) (xy 273.338532 -58.526179)
			(xy 273.277234 -58.584627) (xy 273.210658 -58.636983) (xy 273.139406 -58.682773) (xy 273.064125 -58.721584)
			(xy 272.985495 -58.753063) (xy 272.904228 -58.776924) (xy 272.821062 -58.792953) (xy 272.736748 -58.801004)
			(xy 272.6944 -58.801508) (xy 272.693892 -58.801508) (xy 272.64756 -58.800902) (xy 272.555402 -58.791231)
			(xy 272.464748 -58.772035) (xy 272.376579 -58.743523) (xy 272.333974 -58.725308) (xy 272.324032 -58.721502)
			(xy 272.302768 -58.721502) (xy 272.292826 -58.725308) (xy 272.250164 -58.743553) (xy 272.161871 -58.772097)
			(xy 272.071086 -58.79129) (xy 271.978796 -58.800923) (xy 271.9324 -58.801508) (xy 271.889047 -58.80102)
			(xy 271.802751 -58.792612) (xy 271.717682 -58.775846) (xy 271.634648 -58.750882) (xy 271.554438 -58.717956)
			(xy 271.477812 -58.677381) (xy 271.405498 -58.629542) (xy 271.338183 -58.574893) (xy 271.276505 -58.513954)
			(xy 271.248378 -58.48096) (xy 271.241266 -58.472324) (xy 271.220946 -58.462672) (xy 271.119854 -58.462672)
			(xy 271.099534 -58.472324) (xy 271.092422 -58.48096) (xy 271.064276 -58.513936) (xy 271.002595 -58.574868)
			(xy 270.93528 -58.629511) (xy 270.862967 -58.677346) (xy 270.786345 -58.717919) (xy 270.706138 -58.750845)
			(xy 270.623108 -58.775812) (xy 270.538044 -58.792582) (xy 270.451751 -58.800998) (xy 270.4084 -58.801508)
			(xy 270.362004 -58.800925) (xy 270.269716 -58.79128) (xy 270.178932 -58.772084) (xy 270.090639 -58.743546)
			(xy 270.047974 -58.725308) (xy 270.038032 -58.721502) (xy 270.016768 -58.721502) (xy 270.006826 -58.725308)
			(xy 269.964223 -58.74353) (xy 269.876056 -58.772048) (xy 269.7854 -58.79124) (xy 269.69324 -58.8009)
			(xy 269.646908 -58.801508) (xy 269.6464 -58.801508) (xy 269.604052 -58.801004) (xy 269.519738 -58.792953)
			(xy 269.436572 -58.776924) (xy 269.355305 -58.753063) (xy 269.276675 -58.721584) (xy 269.201394 -58.682773)
			(xy 269.130142 -58.636983) (xy 269.063566 -58.584627) (xy 269.002268 -58.526179) (xy 268.946803 -58.462169)
			(xy 268.897674 -58.393177) (xy 268.855325 -58.319827) (xy 268.820141 -58.242784) (xy 268.792439 -58.162745)
			(xy 268.772471 -58.080436) (xy 268.760418 -57.996601) (xy 268.756388 -57.912) (xy 265.204702 -57.912)
			(xy 265.204702 -68.199) (xy 267.232388 -68.199) (xy 267.236418 -68.114399) (xy 267.248471 -68.030564)
			(xy 267.268439 -67.948255) (xy 267.296141 -67.868216) (xy 267.331325 -67.791173) (xy 267.373674 -67.717823)
			(xy 267.422803 -67.648831) (xy 267.478268 -67.584821) (xy 267.539566 -67.526373) (xy 267.606142 -67.474017)
			(xy 267.677394 -67.428227) (xy 267.752675 -67.389416) (xy 267.831305 -67.357937) (xy 267.912572 -67.334076)
			(xy 267.995738 -67.318047) (xy 268.080052 -67.309996) (xy 268.1224 -67.309492) (xy 268.122908 -67.309492)
			(xy 268.161656 -67.309926) (xy 268.238857 -67.316687) (xy 268.315177 -67.330139) (xy 268.390036 -67.350181)
			(xy 268.462869 -67.37666) (xy 268.53312 -67.409376) (xy 268.5669 -67.428364) (xy 268.574774 -67.432523)
			(xy 268.5923 -67.435617) (xy 268.609826 -67.432523) (xy 268.6177 -67.428364) (xy 268.651489 -67.409393)
			(xy 268.721739 -67.376677) (xy 268.79457 -67.350196) (xy 268.869428 -67.330151) (xy 268.945745 -67.316693)
			(xy 269.022945 -67.309925) (xy 269.061692 -67.309492) (xy 269.0622 -67.309492) (xy 269.104548 -67.309996)
			(xy 269.188862 -67.318047) (xy 269.272028 -67.334076) (xy 269.353295 -67.357937) (xy 269.431925 -67.389416)
			(xy 269.507206 -67.428227) (xy 269.578458 -67.474017) (xy 269.645034 -67.526373) (xy 269.706332 -67.584821)
			(xy 269.761797 -67.648831) (xy 269.810926 -67.717823) (xy 269.853275 -67.791173) (xy 269.888459 -67.868216)
			(xy 269.916161 -67.948255) (xy 269.936129 -68.030564) (xy 269.948182 -68.114399) (xy 269.952213 -68.199)
			(xy 269.948182 -68.283601) (xy 269.936129 -68.367436) (xy 269.916161 -68.449745) (xy 269.888459 -68.529784)
			(xy 269.853275 -68.606827) (xy 269.810926 -68.680177) (xy 269.761797 -68.749169) (xy 269.706332 -68.813179)
			(xy 269.645034 -68.871627) (xy 269.578458 -68.923983) (xy 269.507206 -68.969773) (xy 269.431925 -69.008584)
			(xy 269.353295 -69.040063) (xy 269.272028 -69.063924) (xy 269.188862 -69.079953) (xy 269.104548 -69.088004)
			(xy 269.0622 -69.088508) (xy 269.061692 -69.088508) (xy 269.022944 -69.088074) (xy 268.945743 -69.081313)
			(xy 268.869423 -69.067861) (xy 268.794564 -69.047819) (xy 268.721731 -69.02134) (xy 268.65148 -68.988624)
			(xy 268.6177 -68.969636) (xy 268.609826 -68.965477) (xy 268.5923 -68.962383) (xy 268.574774 -68.965477)
			(xy 268.5669 -68.969636) (xy 268.533111 -68.988607) (xy 268.462861 -69.021323) (xy 268.39003 -69.047804)
			(xy 268.315172 -69.067849) (xy 268.238855 -69.081307) (xy 268.161655 -69.088075) (xy 268.122908 -69.088508)
			(xy 268.1224 -69.088508) (xy 268.080052 -69.088004) (xy 267.995738 -69.079953) (xy 267.912572 -69.063924)
			(xy 267.831305 -69.040063) (xy 267.752675 -69.008584) (xy 267.677394 -68.969773) (xy 267.606142 -68.923983)
			(xy 267.539566 -68.871627) (xy 267.478268 -68.813179) (xy 267.422803 -68.749169) (xy 267.373674 -68.680177)
			(xy 267.331325 -68.606827) (xy 267.296141 -68.529784) (xy 267.268439 -68.449745) (xy 267.248471 -68.367436)
			(xy 267.236418 -68.283601) (xy 267.232388 -68.199) (xy 265.204702 -68.199) (xy 265.204702 -68.488814)
			(xy 265.205191 -68.498547) (xy 265.212497 -68.516593) (xy 265.225983 -68.530636) (xy 265.234674 -68.535042)
			(xy 265.273372 -68.552934) (xy 265.347492 -68.595074) (xy 265.417242 -68.64411) (xy 265.481981 -68.699594)
			(xy 265.541116 -68.761016) (xy 265.594104 -68.827812) (xy 265.64046 -68.899371) (xy 265.679759 -68.975036)
			(xy 265.711639 -69.054113) (xy 265.73581 -69.135877) (xy 265.752048 -69.219578) (xy 265.760206 -69.304449)
			(xy 265.760708 -69.34708) (xy 265.760708 -69.347842) (xy 265.760124 -69.39309) (xy 265.750905 -69.483115)
			(xy 265.732585 -69.571738) (xy 265.705356 -69.658041) (xy 265.669499 -69.74113) (xy 265.647932 -69.780912)
			(xy 265.643026 -69.790878) (xy 265.641461 -69.813015) (xy 265.644884 -69.823584) (xy 265.676126 -69.906896)
			(xy 265.691874 -69.92239) (xy 265.702542 -69.9262) (xy 265.741999 -69.940786) (xy 265.818247 -69.976332)
			(xy 265.8908 -70.018917) (xy 265.959008 -70.068161) (xy 266.022264 -70.123623) (xy 266.080001 -70.184809)
			(xy 266.131705 -70.251172) (xy 266.176914 -70.322119) (xy 266.215223 -70.397017) (xy 266.246292 -70.475197)
			(xy 266.269842 -70.55596) (xy 266.285663 -70.638586) (xy 266.293613 -70.722337) (xy 266.294108 -70.7644)
			(xy 266.293633 -70.805502) (xy 266.286048 -70.887357) (xy 266.270943 -70.968162) (xy 266.256649 -71.0184)
			(xy 267.232388 -71.0184) (xy 267.236418 -70.933799) (xy 267.248471 -70.849964) (xy 267.268439 -70.767655)
			(xy 267.296141 -70.687616) (xy 267.331325 -70.610573) (xy 267.373674 -70.537223) (xy 267.422803 -70.468231)
			(xy 267.478268 -70.404221) (xy 267.539566 -70.345773) (xy 267.606142 -70.293417) (xy 267.677394 -70.247627)
			(xy 267.752675 -70.208816) (xy 267.831305 -70.177337) (xy 267.912572 -70.153476) (xy 267.995738 -70.137447)
			(xy 268.080052 -70.129396) (xy 268.1224 -70.128892) (xy 268.122908 -70.128892) (xy 268.161656 -70.129326)
			(xy 268.238857 -70.136087) (xy 268.315177 -70.149539) (xy 268.390036 -70.169581) (xy 268.462869 -70.19606)
			(xy 268.53312 -70.228776) (xy 268.5669 -70.247764) (xy 268.574774 -70.251923) (xy 268.5923 -70.255017)
			(xy 268.609826 -70.251923) (xy 268.6177 -70.247764) (xy 268.651489 -70.228793) (xy 268.721739 -70.196077)
			(xy 268.79457 -70.169596) (xy 268.869428 -70.149551) (xy 268.945745 -70.136093) (xy 269.022945 -70.129325)
			(xy 269.061692 -70.128892) (xy 269.0622 -70.128892) (xy 269.104548 -70.129396) (xy 269.188862 -70.137447)
			(xy 269.272028 -70.153476) (xy 269.353295 -70.177337) (xy 269.431925 -70.208816) (xy 269.507206 -70.247627)
			(xy 269.578458 -70.293417) (xy 269.645034 -70.345773) (xy 269.706332 -70.404221) (xy 269.761797 -70.468231)
			(xy 269.810926 -70.537223) (xy 269.853275 -70.610573) (xy 269.888459 -70.687616) (xy 269.916161 -70.767655)
			(xy 269.936129 -70.849964) (xy 269.948182 -70.933799) (xy 269.952213 -71.0184) (xy 269.948182 -71.103001)
			(xy 269.936129 -71.186836) (xy 269.916161 -71.269145) (xy 269.888459 -71.349184) (xy 269.853275 -71.426227)
			(xy 269.810926 -71.499577) (xy 269.761797 -71.568569) (xy 269.706332 -71.632579) (xy 269.645034 -71.691027)
			(xy 269.578458 -71.743383) (xy 269.507206 -71.789173) (xy 269.431925 -71.827984) (xy 269.353295 -71.859463)
			(xy 269.272028 -71.883324) (xy 269.188862 -71.899353) (xy 269.104548 -71.907404) (xy 269.0622 -71.907908)
			(xy 269.061692 -71.907908) (xy 269.022944 -71.907474) (xy 268.945743 -71.900713) (xy 268.869423 -71.887261)
			(xy 268.794564 -71.867219) (xy 268.721731 -71.84074) (xy 268.65148 -71.808024) (xy 268.6177 -71.789036)
			(xy 268.609826 -71.784877) (xy 268.5923 -71.781783) (xy 268.574774 -71.784877) (xy 268.5669 -71.789036)
			(xy 268.533111 -71.808007) (xy 268.462861 -71.840723) (xy 268.39003 -71.867204) (xy 268.315172 -71.887249)
			(xy 268.238855 -71.900707) (xy 268.161655 -71.907475) (xy 268.122908 -71.907908) (xy 268.1224 -71.907908)
			(xy 268.080052 -71.907404) (xy 267.995738 -71.899353) (xy 267.912572 -71.883324) (xy 267.831305 -71.859463)
			(xy 267.752675 -71.827984) (xy 267.677394 -71.789173) (xy 267.606142 -71.743383) (xy 267.539566 -71.691027)
			(xy 267.478268 -71.632579) (xy 267.422803 -71.568569) (xy 267.373674 -71.499577) (xy 267.331325 -71.426227)
			(xy 267.296141 -71.349184) (xy 267.268439 -71.269145) (xy 267.248471 -71.186836) (xy 267.236418 -71.103001)
			(xy 267.232388 -71.0184) (xy 266.256649 -71.0184) (xy 266.248447 -71.047229) (xy 266.218751 -71.123883)
			(xy 266.182109 -71.19747) (xy 266.138834 -71.267362) (xy 266.089294 -71.332963) (xy 266.033913 -71.393713)
			(xy 265.973163 -71.449094) (xy 265.907562 -71.498634) (xy 265.83767 -71.541909) (xy 265.764083 -71.578551)
			(xy 265.687429 -71.608247) (xy 265.608362 -71.630743) (xy 265.527557 -71.645848) (xy 265.445702 -71.653433)
			(xy 265.4046 -71.653908) (xy 265.40333 -71.653908) (xy 265.381576 -71.653764) (xy 265.338123 -71.651604)
			(xy 265.316462 -71.64959) (xy 265.305735 -71.648966) (xy 265.285342 -71.655662) (xy 265.277092 -71.662544)
			(xy 265.221212 -71.71309) (xy 265.213778 -71.720668) (xy 265.205248 -71.740081) (xy 265.204702 -71.750682)
			(xy 265.204702 -73.8886) (xy 266.368788 -73.8886) (xy 266.372818 -73.803999) (xy 266.384871 -73.720164)
			(xy 266.404839 -73.637855) (xy 266.432541 -73.557816) (xy 266.467725 -73.480773) (xy 266.510074 -73.407423)
			(xy 266.559203 -73.338431) (xy 266.614668 -73.274421) (xy 266.675966 -73.215973) (xy 266.742542 -73.163617)
			(xy 266.813794 -73.117827) (xy 266.889075 -73.079016) (xy 266.967705 -73.047537) (xy 267.048972 -73.023676)
			(xy 267.132138 -73.007647) (xy 267.216452 -72.999596) (xy 267.2588 -72.999092) (xy 267.259562 -72.999092)
			(xy 267.297909 -72.999501) (xy 267.374317 -73.006133) (xy 267.449868 -73.019325) (xy 267.524002 -73.038978)
			(xy 267.596166 -73.064947) (xy 267.631164 -73.080626) (xy 267.641437 -73.084766) (xy 267.663563 -73.084766)
			(xy 267.673836 -73.080626) (xy 267.708833 -73.064947) (xy 267.781003 -73.039) (xy 267.855138 -73.019357)
			(xy 267.930687 -73.006163) (xy 268.007092 -72.999518) (xy 268.045438 -72.999092) (xy 268.0462 -72.999092)
			(xy 268.088548 -72.999596) (xy 268.172862 -73.007647) (xy 268.256028 -73.023676) (xy 268.337295 -73.047537)
			(xy 268.415925 -73.079016) (xy 268.491206 -73.117827) (xy 268.562458 -73.163617) (xy 268.629034 -73.215973)
			(xy 268.690332 -73.274421) (xy 268.745797 -73.338431) (xy 268.794926 -73.407423) (xy 268.837275 -73.480773)
			(xy 268.872459 -73.557816) (xy 268.900161 -73.637855) (xy 268.920129 -73.720164) (xy 268.932182 -73.803999)
			(xy 268.936213 -73.8886) (xy 268.932182 -73.973201) (xy 268.920129 -74.057036) (xy 268.900161 -74.139345)
			(xy 268.872459 -74.219384) (xy 268.837275 -74.296427) (xy 268.794926 -74.369777) (xy 268.745797 -74.438769)
			(xy 268.697852 -74.4941) (xy 303.021024 -74.4941) (xy 303.025053 -74.409502) (xy 303.037107 -74.325671)
			(xy 303.057074 -74.243365) (xy 303.084774 -74.163329) (xy 303.119957 -74.086289) (xy 303.162304 -74.012942)
			(xy 303.211431 -73.943953) (xy 303.266894 -73.879946) (xy 303.328189 -73.821501) (xy 303.394763 -73.769147)
			(xy 303.466012 -73.723358) (xy 303.54129 -73.684549) (xy 303.619917 -73.653071) (xy 303.70118 -73.629211)
			(xy 303.784343 -73.613182) (xy 303.868653 -73.605132) (xy 303.911 -73.604628) (xy 303.951046 -73.605059)
			(xy 304.030815 -73.612254) (xy 304.109614 -73.626586) (xy 304.186807 -73.647939) (xy 304.26177 -73.67614)
			(xy 304.333897 -73.710962) (xy 304.402603 -73.752123) (xy 304.467334 -73.799289) (xy 304.49774 -73.825354)
			(xy 304.504826 -73.831124) (xy 304.521886 -73.837632) (xy 304.531014 -73.838054) (xy 304.560986 -73.838054)
			(xy 304.570108 -73.837612) (xy 304.587158 -73.831097) (xy 304.59426 -73.825354) (xy 304.624664 -73.799286)
			(xy 304.689385 -73.752101) (xy 304.758087 -73.710928) (xy 304.830213 -73.676099) (xy 304.905178 -73.647896)
			(xy 304.982375 -73.626549) (xy 305.06118 -73.61223) (xy 305.140952 -73.605055) (xy 305.181 -73.604628)
			(xy 305.22335 -73.60506) (xy 305.307667 -73.613111) (xy 305.390837 -73.629141) (xy 305.472106 -73.653003)
			(xy 305.55074 -73.684483) (xy 305.626024 -73.723295) (xy 305.697279 -73.769088) (xy 305.763858 -73.821446)
			(xy 305.825158 -73.879896) (xy 305.880625 -73.943909) (xy 305.929756 -74.012903) (xy 305.972107 -74.086256)
			(xy 306.007292 -74.163302) (xy 306.034995 -74.243344) (xy 306.054964 -74.325657) (xy 306.067018 -74.409496)
			(xy 306.071049 -74.4941) (xy 306.067018 -74.578704) (xy 306.054964 -74.662543) (xy 306.034995 -74.744856)
			(xy 306.007292 -74.824898) (xy 305.972107 -74.901944) (xy 305.929756 -74.975297) (xy 305.880625 -75.044291)
			(xy 305.825158 -75.108304) (xy 305.763858 -75.166754) (xy 305.697279 -75.219112) (xy 305.626024 -75.264905)
			(xy 305.55074 -75.303717) (xy 305.472106 -75.335197) (xy 305.390837 -75.359059) (xy 305.307667 -75.375089)
			(xy 305.22335 -75.38314) (xy 305.181 -75.383644) (xy 305.140954 -75.38322) (xy 305.061185 -75.376025)
			(xy 304.982385 -75.361692) (xy 304.905191 -75.340339) (xy 304.830228 -75.312136) (xy 304.758102 -75.277313)
			(xy 304.689396 -75.236152) (xy 304.624665 -75.188984) (xy 304.59426 -75.162918) (xy 304.587168 -75.157157)
			(xy 304.570113 -75.150642) (xy 304.560986 -75.150218) (xy 304.531014 -75.150218) (xy 304.521893 -75.150666)
			(xy 304.504843 -75.157178) (xy 304.49774 -75.162918) (xy 304.467332 -75.188982) (xy 304.402612 -75.236167)
			(xy 304.333911 -75.277342) (xy 304.261786 -75.312171) (xy 304.186821 -75.340374) (xy 304.109624 -75.361722)
			(xy 304.03082 -75.376042) (xy 303.951047 -75.383217) (xy 303.911 -75.383644) (xy 303.868653 -75.383068)
			(xy 303.784343 -75.375018) (xy 303.70118 -75.358989) (xy 303.619917 -75.335129) (xy 303.54129 -75.303651)
			(xy 303.466012 -75.264842) (xy 303.394763 -75.219053) (xy 303.328189 -75.166699) (xy 303.266894 -75.108254)
			(xy 303.211431 -75.044247) (xy 303.162304 -74.975258) (xy 303.119957 -74.901911) (xy 303.084774 -74.824871)
			(xy 303.057074 -74.744835) (xy 303.037107 -74.662529) (xy 303.025053 -74.578698) (xy 303.021024 -74.4941)
			(xy 268.697852 -74.4941) (xy 268.690332 -74.502779) (xy 268.629034 -74.561227) (xy 268.562458 -74.613583)
			(xy 268.491206 -74.659373) (xy 268.415925 -74.698184) (xy 268.337295 -74.729663) (xy 268.256028 -74.753524)
			(xy 268.172862 -74.769553) (xy 268.088548 -74.777604) (xy 268.0462 -74.778108) (xy 268.045438 -74.778108)
			(xy 268.007091 -74.777699) (xy 267.930683 -74.771067) (xy 267.855132 -74.757875) (xy 267.780998 -74.738222)
			(xy 267.708834 -74.712253) (xy 267.673836 -74.696574) (xy 267.663563 -74.692434) (xy 267.641437 -74.692434)
			(xy 267.631164 -74.696574) (xy 267.596167 -74.712253) (xy 267.523997 -74.7382) (xy 267.449862 -74.757843)
			(xy 267.374313 -74.771037) (xy 267.297908 -74.777682) (xy 267.259562 -74.778108) (xy 267.2588 -74.778108)
			(xy 267.216452 -74.777604) (xy 267.132138 -74.769553) (xy 267.048972 -74.753524) (xy 266.967705 -74.729663)
			(xy 266.889075 -74.698184) (xy 266.813794 -74.659373) (xy 266.742542 -74.613583) (xy 266.675966 -74.561227)
			(xy 266.614668 -74.502779) (xy 266.559203 -74.438769) (xy 266.510074 -74.369777) (xy 266.467725 -74.296427)
			(xy 266.432541 -74.219384) (xy 266.404839 -74.139345) (xy 266.384871 -74.057036) (xy 266.372818 -73.973201)
			(xy 266.368788 -73.8886) (xy 265.204702 -73.8886) (xy 265.204702 -75.861361) (xy 297.179742 -75.861361)
			(xy 297.179742 -75.776639) (xy 297.187795 -75.692302) (xy 297.203829 -75.609112) (xy 297.227697 -75.527822)
			(xy 297.259185 -75.44917) (xy 297.298007 -75.373867) (xy 297.34381 -75.302595) (xy 297.396181 -75.235999)
			(xy 297.454646 -75.174684) (xy 297.518674 -75.119203) (xy 297.587686 -75.07006) (xy 297.661056 -75.0277)
			(xy 297.738121 -74.992505) (xy 297.818183 -74.964796) (xy 297.900516 -74.944822) (xy 297.984375 -74.932765)
			(xy 298.069 -74.928734) (xy 298.153625 -74.932765) (xy 298.237484 -74.944822) (xy 298.319817 -74.964796)
			(xy 298.399879 -74.992505) (xy 298.476944 -75.0277) (xy 298.550314 -75.07006) (xy 298.619326 -75.119203)
			(xy 298.683354 -75.174684) (xy 298.741819 -75.235999) (xy 298.79419 -75.302595) (xy 298.839993 -75.373867)
			(xy 298.878815 -75.44917) (xy 298.910303 -75.527822) (xy 298.934171 -75.609112) (xy 298.950205 -75.692302)
			(xy 298.958258 -75.776639) (xy 298.958762 -75.819) (xy 298.958258 -75.861361) (xy 298.950205 -75.945698)
			(xy 298.934171 -76.028888) (xy 298.910303 -76.110178) (xy 298.878815 -76.18883) (xy 298.839993 -76.264133)
			(xy 298.810167 -76.310544) (xy 305.873647 -76.310544) (xy 305.873647 -76.181404) (xy 305.881597 -76.052509)
			(xy 305.897467 -75.924349) (xy 305.921196 -75.797408) (xy 305.952695 -75.672169) (xy 305.991844 -75.549106)
			(xy 306.038495 -75.428687) (xy 306.09247 -75.311368) (xy 306.153565 -75.197594) (xy 306.221548 -75.087797)
			(xy 306.296162 -74.982394) (xy 306.377123 -74.881784) (xy 306.464123 -74.786349) (xy 306.556834 -74.69645)
			(xy 306.654904 -74.612429) (xy 306.757959 -74.534605) (xy 306.86561 -74.463273) (xy 306.977449 -74.398703)
			(xy 307.09305 -74.341141) (xy 307.211975 -74.290804) (xy 307.333774 -74.247884) (xy 307.457984 -74.212543)
			(xy 307.584133 -74.184916) (xy 307.711745 -74.165107) (xy 307.840334 -74.153191) (xy 307.969412 -74.149215)
			(xy 308.09849 -74.153191) (xy 308.227079 -74.165107) (xy 308.354691 -74.184916) (xy 308.48084 -74.212543)
			(xy 308.60505 -74.247884) (xy 308.726849 -74.290804) (xy 308.845774 -74.341141) (xy 308.961375 -74.398703)
			(xy 309.073214 -74.463273) (xy 309.180865 -74.534605) (xy 309.28392 -74.612429) (xy 309.38199 -74.69645)
			(xy 309.474701 -74.786349) (xy 309.561701 -74.881784) (xy 309.642662 -74.982394) (xy 309.717276 -75.087797)
			(xy 309.785259 -75.197594) (xy 309.846354 -75.311368) (xy 309.900329 -75.428687) (xy 309.94698 -75.549106)
			(xy 309.986129 -75.672169) (xy 310.017628 -75.797408) (xy 310.041357 -75.924349) (xy 310.057227 -76.052509)
			(xy 310.065177 -76.181404) (xy 310.065674 -76.245974) (xy 310.065177 -76.310544) (xy 310.057227 -76.439439)
			(xy 310.041357 -76.567599) (xy 310.017628 -76.69454) (xy 309.986129 -76.819779) (xy 309.94698 -76.942842)
			(xy 309.900329 -77.063261) (xy 309.846354 -77.18058) (xy 309.785259 -77.294354) (xy 309.717276 -77.404151)
			(xy 309.642662 -77.509554) (xy 309.561701 -77.610164) (xy 309.474701 -77.705599) (xy 309.38199 -77.795498)
			(xy 309.28392 -77.879519) (xy 309.180865 -77.957343) (xy 309.073214 -78.028675) (xy 308.961375 -78.093245)
			(xy 308.845774 -78.150807) (xy 308.726849 -78.201144) (xy 308.60505 -78.244064) (xy 308.48084 -78.279405)
			(xy 308.354691 -78.307032) (xy 308.227079 -78.326841) (xy 308.09849 -78.338757) (xy 307.969412 -78.342734)
			(xy 307.840334 -78.338757) (xy 307.711745 -78.326841) (xy 307.584133 -78.307032) (xy 307.457984 -78.279405)
			(xy 307.333774 -78.244064) (xy 307.211975 -78.201144) (xy 307.09305 -78.150807) (xy 306.977449 -78.093245)
			(xy 306.86561 -78.028675) (xy 306.757959 -77.957343) (xy 306.654904 -77.879519) (xy 306.556834 -77.795498)
			(xy 306.464123 -77.705599) (xy 306.377123 -77.610164) (xy 306.296162 -77.509554) (xy 306.221548 -77.404151)
			(xy 306.153565 -77.294354) (xy 306.09247 -77.18058) (xy 306.038495 -77.063261) (xy 305.991844 -76.942842)
			(xy 305.952695 -76.819779) (xy 305.921196 -76.69454) (xy 305.897467 -76.567599) (xy 305.881597 -76.439439)
			(xy 305.873647 -76.310544) (xy 298.810167 -76.310544) (xy 298.79419 -76.335405) (xy 298.741819 -76.402001)
			(xy 298.683354 -76.463316) (xy 298.619326 -76.518797) (xy 298.550314 -76.56794) (xy 298.476944 -76.6103)
			(xy 298.399879 -76.645495) (xy 298.319817 -76.673204) (xy 298.237484 -76.693178) (xy 298.153625 -76.705235)
			(xy 298.069 -76.709267) (xy 297.984375 -76.705235) (xy 297.900516 -76.693178) (xy 297.818183 -76.673204)
			(xy 297.738121 -76.645495) (xy 297.661056 -76.6103) (xy 297.587686 -76.56794) (xy 297.518674 -76.518797)
			(xy 297.454646 -76.463316) (xy 297.396181 -76.402001) (xy 297.34381 -76.335405) (xy 297.298007 -76.264133)
			(xy 297.259185 -76.18883) (xy 297.227697 -76.110178) (xy 297.203829 -76.028888) (xy 297.187795 -75.945698)
			(xy 297.179742 -75.861361) (xy 265.204702 -75.861361) (xy 265.204702 -78.1558) (xy 279.439887 -78.1558)
			(xy 279.443918 -78.071199) (xy 279.455971 -77.987365) (xy 279.475939 -77.905056) (xy 279.50364 -77.825017)
			(xy 279.538825 -77.747974) (xy 279.581173 -77.674625) (xy 279.630301 -77.605633) (xy 279.685766 -77.541623)
			(xy 279.747063 -77.483176) (xy 279.813639 -77.430819) (xy 279.88489 -77.385029) (xy 279.960171 -77.346218)
			(xy 280.038801 -77.314739) (xy 280.120067 -77.290877) (xy 280.203233 -77.274847) (xy 280.287546 -77.266796)
			(xy 280.329894 -77.266292) (xy 280.330402 -77.266292) (xy 280.376734 -77.2669) (xy 280.468892 -77.276571)
			(xy 280.559546 -77.295766) (xy 280.647715 -77.324277) (xy 280.69032 -77.342492) (xy 280.700262 -77.346298)
			(xy 280.721526 -77.346298) (xy 280.731468 -77.342492) (xy 280.774072 -77.324272) (xy 280.862239 -77.295754)
			(xy 280.952894 -77.276561) (xy 281.045054 -77.2669) (xy 281.091386 -77.266292) (xy 281.091894 -77.266292)
			(xy 281.134243 -77.26678) (xy 281.218559 -77.27483) (xy 281.301727 -77.290859) (xy 281.382995 -77.314721)
			(xy 281.461627 -77.3462) (xy 281.536911 -77.385011) (xy 281.608164 -77.430802) (xy 281.674742 -77.48316)
			(xy 281.736042 -77.541608) (xy 281.791508 -77.605619) (xy 281.840638 -77.674613) (xy 281.882988 -77.747964)
			(xy 281.918173 -77.825009) (xy 281.945875 -77.905049) (xy 281.965844 -77.98736) (xy 281.977898 -78.071197)
			(xy 281.981928 -78.1558) (xy 281.977898 -78.240403) (xy 281.965844 -78.32424) (xy 281.945875 -78.406551)
			(xy 281.918173 -78.486591) (xy 281.882988 -78.563636) (xy 281.840638 -78.636987) (xy 281.791508 -78.705981)
			(xy 281.736042 -78.769992) (xy 281.674742 -78.82844) (xy 281.608164 -78.880798) (xy 281.536911 -78.926589)
			(xy 281.461627 -78.9654) (xy 281.382995 -78.996879) (xy 281.301727 -79.020741) (xy 281.218559 -79.03677)
			(xy 281.134243 -79.04482) (xy 281.091894 -79.045308) (xy 281.091386 -79.045308) (xy 281.045054 -79.044704)
			(xy 280.952896 -79.035032) (xy 280.862242 -79.015836) (xy 280.774073 -78.987323) (xy 280.731468 -78.969108)
			(xy 280.721526 -78.965302) (xy 280.700262 -78.965302) (xy 280.69032 -78.969108) (xy 280.647718 -78.987332)
			(xy 280.55955 -79.015849) (xy 280.468894 -79.035041) (xy 280.376734 -79.0447) (xy 280.330402 -79.045308)
			(xy 280.329894 -79.045308) (xy 280.287546 -79.044804) (xy 280.203233 -79.036753) (xy 280.120067 -79.020723)
			(xy 280.038801 -78.996861) (xy 279.960171 -78.965382) (xy 279.88489 -78.926571) (xy 279.813639 -78.880781)
			(xy 279.747063 -78.828424) (xy 279.685766 -78.769977) (xy 279.630301 -78.705967) (xy 279.581173 -78.636975)
			(xy 279.538825 -78.563626) (xy 279.50364 -78.486583) (xy 279.475939 -78.406544) (xy 279.455971 -78.324235)
			(xy 279.443918 -78.240401) (xy 279.439887 -78.1558) (xy 265.204702 -78.1558) (xy 265.204702 -80.391)
			(xy 297.102788 -80.391) (xy 297.106818 -80.306399) (xy 297.118871 -80.222564) (xy 297.138839 -80.140255)
			(xy 297.166541 -80.060216) (xy 297.201725 -79.983173) (xy 297.244074 -79.909823) (xy 297.293203 -79.840831)
			(xy 297.348668 -79.776821) (xy 297.409966 -79.718373) (xy 297.476542 -79.666017) (xy 297.547794 -79.620227)
			(xy 297.623075 -79.581416) (xy 297.701705 -79.549937) (xy 297.782972 -79.526076) (xy 297.866138 -79.510047)
			(xy 297.950452 -79.501996) (xy 297.9928 -79.501492) (xy 297.993308 -79.501492) (xy 298.03964 -79.502098)
			(xy 298.131798 -79.511769) (xy 298.222452 -79.530965) (xy 298.310621 -79.559477) (xy 298.353226 -79.577692)
			(xy 298.363168 -79.581498) (xy 298.384432 -79.581498) (xy 298.394374 -79.577692) (xy 298.436977 -79.55947)
			(xy 298.525144 -79.530952) (xy 298.6158 -79.51176) (xy 298.70796 -79.5021) (xy 298.754292 -79.501492)
			(xy 298.7548 -79.501492) (xy 298.797148 -79.501996) (xy 298.881462 -79.510047) (xy 298.964628 -79.526076)
			(xy 299.045895 -79.549937) (xy 299.124525 -79.581416) (xy 299.199806 -79.620227) (xy 299.271058 -79.666017)
			(xy 299.337634 -79.718373) (xy 299.398932 -79.776821) (xy 299.450937 -79.836838) (xy 303.180186 -79.836838)
			(xy 303.182815 -79.753015) (xy 303.19332 -79.66981) (xy 303.211608 -79.587964) (xy 303.237517 -79.508202)
			(xy 303.270817 -79.431231) (xy 303.311212 -79.357736) (xy 303.358343 -79.288368) (xy 303.411794 -79.223743)
			(xy 303.471088 -79.164435) (xy 303.5357 -79.110969) (xy 303.605057 -79.063821) (xy 303.678543 -79.023409)
			(xy 303.755505 -78.990091) (xy 303.835261 -78.964164) (xy 303.917103 -78.945856) (xy 304.000305 -78.935331)
			(xy 304.084128 -78.932683) (xy 304.167828 -78.937934) (xy 304.250663 -78.951038) (xy 304.331897 -78.971879)
			(xy 304.410809 -79.000271) (xy 304.4867 -79.035964) (xy 304.558894 -79.078639) (xy 304.626753 -79.127919)
			(xy 304.689673 -79.183366) (xy 304.747097 -79.244487) (xy 304.798514 -79.310741) (xy 304.843468 -79.38154)
			(xy 304.881561 -79.456254) (xy 304.912453 -79.534222) (xy 304.935872 -79.61475) (xy 304.951609 -79.697125)
			(xy 304.959525 -79.780616) (xy 304.96002 -79.822548) (xy 304.96002 -79.823056) (xy 304.959492 -79.865875)
			(xy 304.951224 -79.951114) (xy 304.94351 -79.993236) (xy 304.941789 -80.004521) (xy 304.94747 -80.026607)
			(xy 304.954432 -80.035654) (xy 305.012852 -80.104996) (xy 305.03368 -80.114394) (xy 305.044856 -80.11414)
			(xy 305.045872 -80.11414) (xy 305.063398 -80.11414) (xy 305.105333 -80.11462) (xy 305.18883 -80.122512)
			(xy 305.271215 -80.138226) (xy 305.351755 -80.161624) (xy 305.429736 -80.192496) (xy 305.504465 -80.23057)
			(xy 305.57528 -80.275507) (xy 305.641553 -80.326908) (xy 305.702694 -80.384318) (xy 305.758161 -80.447227)
			(xy 305.807463 -80.515076) (xy 305.85016 -80.587263) (xy 305.885876 -80.663148) (xy 305.914292 -80.742058)
			(xy 305.935156 -80.823291) (xy 305.948283 -80.906127) (xy 305.953557 -80.98983) (xy 305.950931 -81.073659)
			(xy 305.940428 -81.156868) (xy 305.922142 -81.23872) (xy 305.896234 -81.318488) (xy 305.862935 -81.395464)
			(xy 305.82254 -81.468965) (xy 305.775407 -81.538338) (xy 305.721955 -81.602968) (xy 305.662659 -81.662282)
			(xy 305.598045 -81.715752) (xy 305.528685 -81.762905) (xy 305.455196 -81.803321) (xy 305.37823 -81.836643)
			(xy 305.298469 -81.862574) (xy 305.216623 -81.880884) (xy 305.133416 -81.891411) (xy 305.049589 -81.894061)
			(xy 304.965883 -81.888812) (xy 304.883044 -81.875708) (xy 304.801804 -81.854868) (xy 304.722887 -81.826475)
			(xy 304.646992 -81.790781) (xy 304.574792 -81.748104) (xy 304.506928 -81.698823) (xy 304.444004 -81.643373)
			(xy 304.386576 -81.582249) (xy 304.335155 -81.515992) (xy 304.290198 -81.445189) (xy 304.252102 -81.370471)
			(xy 304.221207 -81.292499) (xy 304.197787 -81.211966) (xy 304.182048 -81.129586) (xy 304.174132 -81.046091)
			(xy 304.173636 -81.004156) (xy 304.173636 -81.003648) (xy 304.174164 -80.960829) (xy 304.182432 -80.87559)
			(xy 304.190146 -80.833468) (xy 304.191851 -80.822182) (xy 304.186179 -80.800099) (xy 304.179224 -80.79105)
			(xy 304.120804 -80.721708) (xy 304.099976 -80.71231) (xy 304.0888 -80.712564) (xy 304.087784 -80.712564)
			(xy 304.070258 -80.712564) (xy 304.028326 -80.712034) (xy 303.944833 -80.704139) (xy 303.862455 -80.688421)
			(xy 303.78192 -80.665021) (xy 303.703946 -80.634147) (xy 303.629222 -80.596072) (xy 303.558413 -80.551135)
			(xy 303.492147 -80.499733) (xy 303.431012 -80.442324) (xy 303.37555 -80.379417) (xy 303.326255 -80.31157)
			(xy 303.283562 -80.239385) (xy 303.247852 -80.163503) (xy 303.219441 -80.084598) (xy 303.198581 -80.003369)
			(xy 303.185457 -79.920537) (xy 303.180186 -79.836838) (xy 299.450937 -79.836838) (xy 299.454397 -79.840831)
			(xy 299.503526 -79.909823) (xy 299.545875 -79.983173) (xy 299.581059 -80.060216) (xy 299.608761 -80.140255)
			(xy 299.628729 -80.222564) (xy 299.640782 -80.306399) (xy 299.644813 -80.391) (xy 299.640782 -80.475601)
			(xy 299.628729 -80.559436) (xy 299.608761 -80.641745) (xy 299.581059 -80.721784) (xy 299.545875 -80.798827)
			(xy 299.503526 -80.872177) (xy 299.454397 -80.941169) (xy 299.398932 -81.005179) (xy 299.337634 -81.063627)
			(xy 299.271058 -81.115983) (xy 299.199806 -81.161773) (xy 299.124525 -81.200584) (xy 299.045895 -81.232063)
			(xy 298.964628 -81.255924) (xy 298.881462 -81.271953) (xy 298.797148 -81.280004) (xy 298.7548 -81.280508)
			(xy 298.754292 -81.280508) (xy 298.70796 -81.279902) (xy 298.615802 -81.270231) (xy 298.525148 -81.251035)
			(xy 298.436979 -81.222523) (xy 298.394374 -81.204308) (xy 298.384432 -81.200502) (xy 298.363168 -81.200502)
			(xy 298.353226 -81.204308) (xy 298.310623 -81.22253) (xy 298.222456 -81.251048) (xy 298.1318 -81.27024)
			(xy 298.03964 -81.2799) (xy 297.993308 -81.280508) (xy 297.9928 -81.280508) (xy 297.950452 -81.280004)
			(xy 297.866138 -81.271953) (xy 297.782972 -81.255924) (xy 297.701705 -81.232063) (xy 297.623075 -81.200584)
			(xy 297.547794 -81.161773) (xy 297.476542 -81.115983) (xy 297.409966 -81.063627) (xy 297.348668 -81.005179)
			(xy 297.293203 -80.941169) (xy 297.244074 -80.872177) (xy 297.201725 -80.798827) (xy 297.166541 -80.721784)
			(xy 297.138839 -80.641745) (xy 297.118871 -80.559436) (xy 297.106818 -80.475601) (xy 297.102788 -80.391)
			(xy 265.204702 -80.391) (xy 265.204702 -82.52968) (xy 265.205111 -82.539752) (xy 265.21284 -82.558351)
			(xy 265.219688 -82.565748) (xy 266.020042 -83.366102) (xy 266.027433 -83.372953) (xy 266.046039 -83.380666)
			(xy 266.05611 -83.381088) (xy 279.229566 -83.381088) (xy 279.262826 -83.381624) (xy 279.328776 -83.390306)
			(xy 279.393028 -83.407528) (xy 279.454481 -83.432992) (xy 279.512081 -83.466264) (xy 279.564843 -83.506774)
			(xy 279.588722 -83.529932) (xy 280.012394 -83.953604) (xy 280.03346 -83.975312) (xy 280.070857 -84.022858)
			(xy 280.102349 -84.074504) (xy 280.127492 -84.129522) (xy 280.14593 -84.187134) (xy 280.152094 -84.216748)
			(xy 280.152094 -84.217002) (xy 280.153848 -84.224279) (xy 280.160943 -84.237451) (xy 280.166064 -84.24291)
			(xy 280.551128 -84.627974) (xy 280.558527 -84.634815) (xy 280.577127 -84.642535) (xy 280.587196 -84.64296)
			(xy 281.74696 -84.64296) (xy 281.780219 -84.643508) (xy 281.846169 -84.652189) (xy 281.91042 -84.669408)
			(xy 281.971873 -84.694871) (xy 282.029474 -84.728141) (xy 282.082237 -84.768647) (xy 282.106116 -84.791804)
			(xy 283.061156 -85.746844) (xy 283.084308 -85.770729) (xy 283.124821 -85.823489) (xy 283.158097 -85.881088)
			(xy 283.183566 -85.942539) (xy 283.200791 -86.00679) (xy 283.209479 -86.07274) (xy 283.21 -86.106)
			(xy 283.21 -86.894162) (xy 283.210419 -86.904233) (xy 283.218141 -86.922832) (xy 283.224986 -86.93023)
			(xy 283.440378 -87.145622) (xy 283.44114 -87.146384) (xy 283.451808 -87.154766) (xy 283.465841 -87.163562)
			(xy 283.489209 -87.187012) (xy 283.505725 -87.215703) (xy 283.514268 -87.247687) (xy 283.5148 -87.26424)
			(xy 283.5148 -88.38184) (xy 283.514292 -88.39849) (xy 283.505664 -88.430654) (xy 283.489008 -88.459489)
			(xy 283.465457 -88.483033) (xy 283.436617 -88.49968) (xy 283.40445 -88.508297) (xy 283.3878 -88.50884)
			(xy 282.0162 -88.50884) (xy 281.999555 -88.508257) (xy 281.967399 -88.499643) (xy 281.938567 -88.483001)
			(xy 281.915024 -88.459465) (xy 281.898373 -88.430638) (xy 281.889748 -88.398485) (xy 281.8892 -88.38184)
			(xy 281.8892 -87.26424) (xy 281.889752 -87.247691) (xy 281.898315 -87.215719) (xy 281.914823 -87.18703)
			(xy 281.938162 -87.16356) (xy 281.952192 -87.154766) (xy 281.96286 -87.146384) (xy 281.963622 -87.145622)
			(xy 282.179014 -86.93023) (xy 282.185835 -86.922815) (xy 282.193565 -86.904227) (xy 282.194 -86.894162)
			(xy 282.194 -86.337394) (xy 282.193604 -86.327321) (xy 282.185866 -86.308722) (xy 282.179014 -86.301326)
			(xy 281.551634 -85.673946) (xy 281.544211 -85.667135) (xy 281.52563 -85.659397) (xy 281.515566 -85.65896)
			(xy 280.506678 -85.65896) (xy 280.496516 -85.659373) (xy 280.47778 -85.667246) (xy 280.470356 -85.6742)
			(xy 280.468578 -85.675978) (xy 280.176224 -85.968332) (xy 280.169381 -85.97573) (xy 280.161662 -85.994331)
			(xy 280.161238 -86.0044) (xy 280.161238 -87.84336) (xy 280.160691 -87.876619) (xy 280.15201 -87.942569)
			(xy 280.13479 -88.00682) (xy 280.109327 -88.068273) (xy 280.076058 -88.125874) (xy 280.035551 -88.178637)
			(xy 280.012394 -88.202516) (xy 279.212548 -89.002362) (xy 279.188667 -89.025519) (xy 279.135906 -89.066031)
			(xy 279.078307 -89.099306) (xy 279.016855 -89.124774) (xy 278.952603 -89.141999) (xy 278.886652 -89.150685)
			(xy 278.853392 -89.151206) (xy 263.66343 -89.151206) (xy 263.63017 -89.150675) (xy 263.564219 -89.141991)
			(xy 263.499967 -89.124769) (xy 263.438515 -89.099304) (xy 263.380914 -89.066031) (xy 263.328153 -89.02552)
			(xy 263.304274 -89.002362) (xy 260.154674 -85.852762) (xy 260.131513 -85.828886) (xy 260.091003 -85.776123)
			(xy 260.05773 -85.718522) (xy 260.032263 -85.657069) (xy 260.015039 -85.592817) (xy 260.006352 -85.526866)
			(xy 260.00583 -85.493606) (xy 260.00583 -54.94401) (xy 260.005164 -54.93279) (xy 259.995562 -54.912499)
			(xy 259.987288 -54.904894) (xy 259.965881 -54.886679) (xy 259.928135 -54.845033) (xy 259.896908 -54.798298)
			(xy 259.872876 -54.747488) (xy 259.85656 -54.693702) (xy 259.848313 -54.638103) (xy 259.848313 -54.581897)
			(xy 259.85656 -54.526298) (xy 259.872876 -54.472512) (xy 259.896908 -54.421702) (xy 259.928135 -54.374967)
			(xy 259.965881 -54.333321) (xy 259.987288 -54.315106) (xy 259.995624 -54.307544) (xy 260.005247 -54.28723)
			(xy 260.00583 -54.27599) (xy 260.00583 -49.163224) (xy 260.005411 -49.153154) (xy 259.997688 -49.134555)
			(xy 259.990844 -49.127156) (xy 258.774692 -47.911004) (xy 258.74472 -47.904908) (xy 258.730496 -47.911004)
			(xy 258.721368 -47.915219) (xy 258.707133 -47.929396) (xy 258.699425 -47.947949) (xy 258.699 -47.957994)
			(xy 258.699 -50.894996) (xy 258.698458 -50.928255) (xy 258.689773 -50.994205) (xy 258.672551 -51.058455)
			(xy 258.647088 -51.119907) (xy 258.613818 -51.177508) (xy 258.573312 -51.230272) (xy 258.550156 -51.254152)
			(xy 257.878072 -51.926236) (xy 257.854176 -51.949376) (xy 257.801419 -51.989891) (xy 257.743823 -52.023169)
			(xy 257.682374 -52.04864) (xy 257.618124 -52.065868) (xy 257.552175 -52.074558) (xy 257.518916 -52.07508)
			(xy 247.302782 -52.07508) (xy 247.269522 -52.074558) (xy 247.203572 -52.06587) (xy 247.13932 -52.048645)
			(xy 247.077868 -52.023177) (xy 247.020268 -51.989904) (xy 246.967505 -51.949394) (xy 246.943626 -51.926236)
			(xy 246.398796 -51.381406) (xy 246.375611 -51.357551) (xy 246.335103 -51.304784) (xy 246.301833 -51.247179)
			(xy 246.27637 -51.185722) (xy 246.259151 -51.121466) (xy 246.25047 -51.055512) (xy 246.249952 -51.02225)
			(xy 246.249952 -46.654466) (xy 246.250454 -46.621205) (xy 246.259145 -46.555254) (xy 246.276374 -46.491002)
			(xy 246.301845 -46.42955) (xy 246.335122 -46.37195) (xy 246.375636 -46.319188) (xy 246.398796 -46.29531)
			(xy 250.260866 -42.43324) (xy 250.266962 -42.403268) (xy 250.260866 -42.389044) (xy 250.256653 -42.379914)
			(xy 250.242478 -42.365674) (xy 250.223922 -42.357969) (xy 250.213876 -42.357548) (xy 249.2248 -42.357548)
			(xy 249.214729 -42.357961) (xy 249.196131 -42.365689) (xy 249.188732 -42.372534) (xy 243.32311 -48.238156)
			(xy 243.299245 -48.26133) (xy 243.246481 -48.301841) (xy 243.188878 -48.335114) (xy 243.127423 -48.360579)
			(xy 243.063168 -48.3778) (xy 242.997215 -48.386482) (xy 242.963954 -48.387) (xy 230.251 -48.387)
			(xy 230.217741 -48.386461) (xy 230.151791 -48.377775) (xy 230.08754 -48.360553) (xy 230.026089 -48.335089)
			(xy 229.968488 -48.301818) (xy 229.915724 -48.261312) (xy 229.891844 -48.238156) (xy 229.002844 -47.349156)
			(xy 228.979692 -47.325271) (xy 228.939179 -47.272511) (xy 228.905903 -47.214912) (xy 228.880434 -47.153461)
			(xy 228.863209 -47.08921) (xy 228.854521 -47.02326) (xy 228.854 -46.99) (xy 211.4804 -46.99) (xy 211.479861 -47.023259)
			(xy 211.471175 -47.089209) (xy 211.453953 -47.15346) (xy 211.428489 -47.214911) (xy 211.395218 -47.272512)
			(xy 211.354712 -47.325276) (xy 211.331556 -47.349156) (xy 210.442556 -48.238156) (xy 210.418671 -48.261308)
			(xy 210.365911 -48.301821) (xy 210.308312 -48.335097) (xy 210.246861 -48.360566) (xy 210.18261 -48.377791)
			(xy 210.11666 -48.386479) (xy 210.0834 -48.387) (xy 197.797166 -48.387) (xy 197.763906 -48.386483)
			(xy 197.697955 -48.377793) (xy 197.633704 -48.360566) (xy 197.572252 -48.335098) (xy 197.514652 -48.301824)
			(xy 197.461889 -48.261314) (xy 197.43801 -48.238156) (xy 191.552068 -42.352214) (xy 191.544671 -42.345369)
			(xy 191.52607 -42.337652) (xy 191.516 -42.337228) (xy 190.21425 -42.337228) (xy 190.203612 -42.337748)
			(xy 190.184155 -42.346351) (xy 190.169854 -42.362101) (xy 190.16599 -42.372026) (xy 190.13551 -42.463466)
			(xy 190.132593 -42.473671) (xy 190.134551 -42.494786) (xy 190.144888 -42.513301) (xy 190.153036 -42.520108)
			(xy 190.15329 -42.520108) (xy 190.167457 -42.530955) (xy 190.194407 -42.554343) (xy 190.207138 -42.566844)
			(xy 193.935604 -46.29531) (xy 193.958748 -46.319202) (xy 193.99926 -46.371961) (xy 194.032536 -46.429559)
			(xy 194.058006 -46.491009) (xy 194.075234 -46.555258) (xy 194.083925 -46.621207) (xy 194.084448 -46.654466)
			(xy 194.084448 -51.02225) (xy 194.084038 -51.049936) (xy 207.409803 -51.049936) (xy 207.413813 -50.944033)
			(xy 207.425821 -50.838737) (xy 207.445758 -50.734651) (xy 207.47351 -50.632371) (xy 207.508918 -50.532482)
			(xy 207.551779 -50.435558) (xy 207.601847 -50.342152) (xy 207.658837 -50.252801) (xy 207.72242 -50.168015)
			(xy 207.792234 -50.088281) (xy 207.867878 -50.014056) (xy 207.948918 -49.945763) (xy 208.034892 -49.883796)
			(xy 208.125306 -49.828508) (xy 208.219642 -49.780216) (xy 208.317361 -49.739197) (xy 208.417901 -49.705686)
			(xy 208.520689 -49.679874) (xy 208.625133 -49.66191) (xy 208.730638 -49.651897) (xy 208.836597 -49.649891)
			(xy 208.942405 -49.655905) (xy 209.047455 -49.669904) (xy 209.151145 -49.691807) (xy 209.252882 -49.72149)
			(xy 209.352083 -49.758781) (xy 209.448179 -49.803469) (xy 209.54062 -49.855296) (xy 209.628877 -49.913966)
			(xy 209.712444 -49.979143) (xy 209.790843 -50.050453) (xy 209.863624 -50.127487) (xy 209.93037 -50.209806)
			(xy 209.9907 -50.296937) (xy 210.044267 -50.388381) (xy 210.090765 -50.483614) (xy 210.129927 -50.582091)
			(xy 210.16153 -50.683248) (xy 210.185391 -50.786506) (xy 210.201376 -50.891272) (xy 210.209391 -50.996947)
			(xy 210.209892 -51.049936) (xy 237.409743 -51.049936) (xy 237.413753 -50.944033) (xy 237.425761 -50.838737)
			(xy 237.445698 -50.734651) (xy 237.47345 -50.632371) (xy 237.508858 -50.532482) (xy 237.551719 -50.435558)
			(xy 237.601787 -50.342152) (xy 237.658777 -50.252801) (xy 237.72236 -50.168015) (xy 237.792174 -50.088281)
			(xy 237.867818 -50.014056) (xy 237.948858 -49.945763) (xy 238.034832 -49.883796) (xy 238.125246 -49.828508)
			(xy 238.219582 -49.780216) (xy 238.317301 -49.739197) (xy 238.417841 -49.705686) (xy 238.520629 -49.679874)
			(xy 238.625073 -49.66191) (xy 238.730578 -49.651897) (xy 238.836537 -49.649891) (xy 238.942345 -49.655905)
			(xy 239.047395 -49.669904) (xy 239.151085 -49.691807) (xy 239.252822 -49.72149) (xy 239.352023 -49.758781)
			(xy 239.448119 -49.803469) (xy 239.54056 -49.855296) (xy 239.628817 -49.913966) (xy 239.712384 -49.979143)
			(xy 239.790783 -50.050453) (xy 239.863564 -50.127487) (xy 239.93031 -50.209806) (xy 239.99064 -50.296937)
			(xy 240.044207 -50.388381) (xy 240.090705 -50.483614) (xy 240.129867 -50.582091) (xy 240.16147 -50.683248)
			(xy 240.185331 -50.786506) (xy 240.201316 -50.891272) (xy 240.209331 -50.996947) (xy 240.209832 -51.049936)
			(xy 240.209331 -51.102925) (xy 240.201316 -51.2086) (xy 240.185331 -51.313366) (xy 240.16147 -51.416624)
			(xy 240.129867 -51.517781) (xy 240.090705 -51.616258) (xy 240.044207 -51.711491) (xy 239.99064 -51.802935)
			(xy 239.93031 -51.890066) (xy 239.863564 -51.972385) (xy 239.790783 -52.049419) (xy 239.712384 -52.120729)
			(xy 239.628817 -52.185906) (xy 239.54056 -52.244576) (xy 239.448119 -52.296403) (xy 239.352023 -52.341091)
			(xy 239.252822 -52.378382) (xy 239.151085 -52.408065) (xy 239.047395 -52.429968) (xy 238.942345 -52.443967)
			(xy 238.836537 -52.449981) (xy 238.730578 -52.447975) (xy 238.625073 -52.437962) (xy 238.520629 -52.419998)
			(xy 238.417841 -52.394186) (xy 238.317301 -52.360675) (xy 238.219582 -52.319656) (xy 238.125246 -52.271364)
			(xy 238.034832 -52.216076) (xy 237.948858 -52.154109) (xy 237.867818 -52.085816) (xy 237.792174 -52.011591)
			(xy 237.72236 -51.931857) (xy 237.658777 -51.847071) (xy 237.601787 -51.75772) (xy 237.551719 -51.664314)
			(xy 237.508858 -51.56739) (xy 237.47345 -51.467501) (xy 237.445698 -51.365221) (xy 237.425761 -51.261135)
			(xy 237.413753 -51.155839) (xy 237.409743 -51.049936) (xy 210.209892 -51.049936) (xy 210.209391 -51.102925)
			(xy 210.201376 -51.2086) (xy 210.185391 -51.313366) (xy 210.16153 -51.416624) (xy 210.129927 -51.517781)
			(xy 210.090765 -51.616258) (xy 210.044267 -51.711491) (xy 209.9907 -51.802935) (xy 209.93037 -51.890066)
			(xy 209.863624 -51.972385) (xy 209.790843 -52.049419) (xy 209.712444 -52.120729) (xy 209.628877 -52.185906)
			(xy 209.54062 -52.244576) (xy 209.448179 -52.296403) (xy 209.352083 -52.341091) (xy 209.252882 -52.378382)
			(xy 209.151145 -52.408065) (xy 209.047455 -52.429968) (xy 208.942405 -52.443967) (xy 208.836597 -52.449981)
			(xy 208.730638 -52.447975) (xy 208.625133 -52.437962) (xy 208.520689 -52.419998) (xy 208.417901 -52.394186)
			(xy 208.317361 -52.360675) (xy 208.219642 -52.319656) (xy 208.125306 -52.271364) (xy 208.034892 -52.216076)
			(xy 207.948918 -52.154109) (xy 207.867878 -52.085816) (xy 207.792234 -52.011591) (xy 207.72242 -51.931857)
			(xy 207.658837 -51.847071) (xy 207.601847 -51.75772) (xy 207.551779 -51.664314) (xy 207.508918 -51.56739)
			(xy 207.47351 -51.467501) (xy 207.445758 -51.365221) (xy 207.425821 -51.261135) (xy 207.413813 -51.155839)
			(xy 207.409803 -51.049936) (xy 194.084038 -51.049936) (xy 194.083956 -51.055511) (xy 194.075263 -51.121463)
			(xy 194.058032 -51.185715) (xy 194.03256 -51.247167) (xy 193.99928 -51.304767) (xy 193.958765 -51.357528)
			(xy 193.935604 -51.381406) (xy 193.390774 -51.926236) (xy 193.366877 -51.949375) (xy 193.31412 -51.989891)
			(xy 193.256524 -52.023169) (xy 193.195075 -52.04864) (xy 193.130826 -52.065868) (xy 193.064877 -52.074557)
			(xy 193.031618 -52.07508) (xy 182.815484 -52.07508) (xy 182.782224 -52.074557) (xy 182.716274 -52.065869)
			(xy 182.652022 -52.048644) (xy 182.59057 -52.023177) (xy 182.53297 -51.989903) (xy 182.480207 -51.949394)
			(xy 182.456328 -51.926236) (xy 181.784244 -51.254152) (xy 181.76109 -51.230269) (xy 181.720577 -51.177508)
			(xy 181.687302 -51.119909) (xy 181.661833 -51.058458) (xy 181.644608 -50.994207) (xy 181.635921 -50.928256)
			(xy 181.6354 -50.894996) (xy 181.6354 -46.609) (xy 181.635939 -46.575741) (xy 181.644625 -46.509791)
			(xy 181.661847 -46.44554) (xy 181.687311 -46.384089) (xy 181.720582 -46.326488) (xy 181.761088 -46.273724)
			(xy 181.784244 -46.249844) (xy 185.467244 -42.566844) (xy 185.479973 -42.554341) (xy 185.506922 -42.530951)
			(xy 185.521092 -42.520108) (xy 185.521346 -42.520108) (xy 185.529459 -42.513289) (xy 185.539717 -42.494765)
			(xy 185.541693 -42.473684) (xy 185.538872 -42.463466) (xy 185.508392 -42.372026) (xy 185.504497 -42.362119)
			(xy 185.4902 -42.346385) (xy 185.470761 -42.337776) (xy 185.460132 -42.337228) (xy 174.147226 -42.337228)
			(xy 174.137157 -42.337659) (xy 174.118559 -42.345375) (xy 174.111158 -42.352214) (xy 172.697648 -43.765724)
			(xy 172.690812 -43.773127) (xy 172.683088 -43.791724) (xy 172.682662 -43.801792) (xy 172.682662 -47.032361)
			(xy 177.987702 -47.032361) (xy 177.987702 -46.947639) (xy 177.995755 -46.863302) (xy 178.011789 -46.780112)
			(xy 178.035657 -46.698822) (xy 178.067145 -46.62017) (xy 178.105967 -46.544867) (xy 178.15177 -46.473595)
			(xy 178.204141 -46.406999) (xy 178.262606 -46.345684) (xy 178.326634 -46.290203) (xy 178.395646 -46.24106)
			(xy 178.469016 -46.1987) (xy 178.546081 -46.163505) (xy 178.626143 -46.135796) (xy 178.708476 -46.115822)
			(xy 178.792335 -46.103765) (xy 178.87696 -46.099734) (xy 178.961585 -46.103765) (xy 179.045444 -46.115822)
			(xy 179.127777 -46.135796) (xy 179.207839 -46.163505) (xy 179.284904 -46.1987) (xy 179.358274 -46.24106)
			(xy 179.427286 -46.290203) (xy 179.491314 -46.345684) (xy 179.549779 -46.406999) (xy 179.60215 -46.473595)
			(xy 179.647953 -46.544867) (xy 179.686775 -46.62017) (xy 179.718263 -46.698822) (xy 179.742131 -46.780112)
			(xy 179.758165 -46.863302) (xy 179.766218 -46.947639) (xy 179.766722 -46.99) (xy 179.766218 -47.032361)
			(xy 179.758165 -47.116698) (xy 179.742131 -47.199888) (xy 179.718263 -47.281178) (xy 179.686775 -47.35983)
			(xy 179.647953 -47.435133) (xy 179.60215 -47.506405) (xy 179.549779 -47.573001) (xy 179.491314 -47.634316)
			(xy 179.427286 -47.689797) (xy 179.358274 -47.73894) (xy 179.284904 -47.7813) (xy 179.207839 -47.816495)
			(xy 179.127777 -47.844204) (xy 179.045444 -47.864178) (xy 178.961585 -47.876235) (xy 178.87696 -47.880267)
			(xy 178.792335 -47.876235) (xy 178.708476 -47.864178) (xy 178.626143 -47.844204) (xy 178.546081 -47.816495)
			(xy 178.469016 -47.7813) (xy 178.395646 -47.73894) (xy 178.326634 -47.689797) (xy 178.262606 -47.634316)
			(xy 178.204141 -47.573001) (xy 178.15177 -47.506405) (xy 178.105967 -47.435133) (xy 178.067145 -47.35983)
			(xy 178.035657 -47.281178) (xy 178.011789 -47.199888) (xy 177.995755 -47.116698) (xy 177.987702 -47.032361)
			(xy 172.682662 -47.032361) (xy 172.682662 -50.465228) (xy 172.683056 -50.475301) (xy 172.690797 -50.4939)
			(xy 172.697648 -50.501296) (xy 172.778674 -50.582322) (xy 172.786086 -50.589146) (xy 172.804676 -50.596875)
			(xy 172.814742 -50.597308) (xy 173.980348 -50.597308) (xy 174.013609 -50.597814) (xy 174.07956 -50.606506)
			(xy 174.143811 -50.623734) (xy 174.205263 -50.649205) (xy 174.262863 -50.682481) (xy 174.315625 -50.722993)
			(xy 174.339504 -50.746152) (xy 176.661318 -53.067966) (xy 176.684492 -53.091831) (xy 176.725 -53.144596)
			(xy 176.758272 -53.2022) (xy 176.783737 -53.263655) (xy 176.800958 -53.327908) (xy 176.809642 -53.393861)
			(xy 176.810162 -53.427122) (xy 176.810162 -54.736238) (xy 176.809658 -54.769499) (xy 176.800967 -54.83545)
			(xy 176.783739 -54.899702) (xy 176.758268 -54.961154) (xy 176.724991 -55.018754) (xy 176.684477 -55.071515)
			(xy 176.661318 -55.095394) (xy 175.161956 -56.594756) (xy 175.138071 -56.617908) (xy 175.085311 -56.658421)
			(xy 175.027712 -56.691697) (xy 174.966261 -56.717166) (xy 174.90201 -56.734391) (xy 174.83606 -56.743079)
			(xy 174.8028 -56.7436) (xy 159.978852 -56.7436) (xy 159.968782 -56.744026) (xy 159.950183 -56.751743)
			(xy 159.942784 -56.758586) (xy 156.32557 -60.3758) (xy 165.632388 -60.3758) (xy 165.636418 -60.291199)
			(xy 165.648471 -60.207364) (xy 165.668439 -60.125055) (xy 165.696141 -60.045016) (xy 165.731325 -59.967973)
			(xy 165.773674 -59.894623) (xy 165.822803 -59.825631) (xy 165.878268 -59.761621) (xy 165.939566 -59.703173)
			(xy 166.006142 -59.650817) (xy 166.077394 -59.605027) (xy 166.152675 -59.566216) (xy 166.231305 -59.534737)
			(xy 166.312572 -59.510876) (xy 166.395738 -59.494847) (xy 166.480052 -59.486796) (xy 166.5224 -59.486292)
			(xy 166.522908 -59.486292) (xy 166.56924 -59.486898) (xy 166.661398 -59.496569) (xy 166.752052 -59.515765)
			(xy 166.840221 -59.544277) (xy 166.882826 -59.562492) (xy 166.892768 -59.566298) (xy 166.914032 -59.566298)
			(xy 166.923974 -59.562492) (xy 166.966577 -59.54427) (xy 167.054744 -59.515752) (xy 167.1454 -59.49656)
			(xy 167.23756 -59.4869) (xy 167.283892 -59.486292) (xy 167.2844 -59.486292) (xy 167.326748 -59.486796)
			(xy 167.411062 -59.494847) (xy 167.494228 -59.510876) (xy 167.575495 -59.534737) (xy 167.654125 -59.566216)
			(xy 167.729406 -59.605027) (xy 167.800658 -59.650817) (xy 167.867234 -59.703173) (xy 167.928532 -59.761621)
			(xy 167.983997 -59.825631) (xy 168.033126 -59.894623) (xy 168.075475 -59.967973) (xy 168.110659 -60.045016)
			(xy 168.138361 -60.125055) (xy 168.158329 -60.207364) (xy 168.170382 -60.291199) (xy 168.174413 -60.3758)
			(xy 168.170382 -60.460401) (xy 168.158329 -60.544236) (xy 168.138361 -60.626545) (xy 168.110659 -60.706584)
			(xy 168.075475 -60.783627) (xy 168.033126 -60.856977) (xy 167.983997 -60.925969) (xy 167.928532 -60.989979)
			(xy 167.867234 -61.048427) (xy 167.800658 -61.100783) (xy 167.729406 -61.146573) (xy 167.654125 -61.185384)
			(xy 167.575495 -61.216863) (xy 167.494228 -61.240724) (xy 167.411062 -61.256753) (xy 167.326748 -61.264804)
			(xy 167.2844 -61.265308) (xy 167.283892 -61.265308) (xy 167.23756 -61.264702) (xy 167.145402 -61.255031)
			(xy 167.054748 -61.235835) (xy 166.966579 -61.207323) (xy 166.923974 -61.189108) (xy 166.914032 -61.185302)
			(xy 166.892768 -61.185302) (xy 166.882826 -61.189108) (xy 166.840223 -61.20733) (xy 166.752056 -61.235848)
			(xy 166.6614 -61.25504) (xy 166.56924 -61.2647) (xy 166.522908 -61.265308) (xy 166.5224 -61.265308)
			(xy 166.480052 -61.264804) (xy 166.395738 -61.256753) (xy 166.312572 -61.240724) (xy 166.231305 -61.216863)
			(xy 166.152675 -61.185384) (xy 166.077394 -61.146573) (xy 166.006142 -61.100783) (xy 165.939566 -61.048427)
			(xy 165.878268 -60.989979) (xy 165.822803 -60.925969) (xy 165.773674 -60.856977) (xy 165.731325 -60.783627)
			(xy 165.696141 -60.706584) (xy 165.668439 -60.626545) (xy 165.648471 -60.544236) (xy 165.636418 -60.460401)
			(xy 165.632388 -60.3758) (xy 156.32557 -60.3758) (xy 152.414986 -64.286384) (xy 152.408159 -64.293794)
			(xy 152.400432 -64.312386) (xy 152.4 -64.322452) (xy 152.4 -66.3194) (xy 178.683872 -66.3194) (xy 178.687902 -66.234795)
			(xy 178.699957 -66.150957) (xy 178.719926 -66.068644) (xy 178.74763 -65.988602) (xy 178.782817 -65.911556)
			(xy 178.825168 -65.838204) (xy 178.8743 -65.769209) (xy 178.929768 -65.705198) (xy 178.99107 -65.646749)
			(xy 179.057651 -65.594392) (xy 179.128907 -65.548601) (xy 179.204193 -65.509791) (xy 179.282827 -65.478314)
			(xy 179.364098 -65.454453) (xy 179.447268 -65.438427) (xy 179.531586 -65.430378) (xy 179.573936 -65.429892)
			(xy 179.574698 -65.429892) (xy 179.613046 -65.430288) (xy 179.689453 -65.436923) (xy 179.765005 -65.450117)
			(xy 179.839139 -65.469774) (xy 179.911302 -65.495746) (xy 179.9463 -65.511426) (xy 179.956573 -65.515566)
			(xy 179.978699 -65.515566) (xy 179.988972 -65.511426) (xy 180.023978 -65.49577) (xy 180.096146 -65.469818)
			(xy 180.170278 -65.45017) (xy 180.245826 -65.436971) (xy 180.322228 -65.430321) (xy 180.360574 -65.429892)
			(xy 180.361336 -65.429892) (xy 180.403683 -65.430397) (xy 180.487994 -65.438451) (xy 180.571158 -65.454483)
			(xy 180.652421 -65.478347) (xy 180.731048 -65.509827) (xy 180.806327 -65.548639) (xy 180.877576 -65.59443)
			(xy 180.944149 -65.646786) (xy 181.005444 -65.705234) (xy 181.060907 -65.769243) (xy 181.110033 -65.838234)
			(xy 181.15238 -65.911582) (xy 181.187562 -65.988624) (xy 181.215263 -66.068661) (xy 181.23523 -66.150968)
			(xy 181.247283 -66.234801) (xy 181.251313 -66.3194) (xy 181.247283 -66.403999) (xy 181.23523 -66.487832)
			(xy 181.215263 -66.570139) (xy 181.187562 -66.650176) (xy 181.15238 -66.727218) (xy 181.110033 -66.800566)
			(xy 181.060907 -66.869557) (xy 181.005444 -66.933566) (xy 180.944149 -66.992014) (xy 180.877576 -67.04437)
			(xy 180.806327 -67.090161) (xy 180.731048 -67.128973) (xy 180.652421 -67.160453) (xy 180.571158 -67.184317)
			(xy 180.487994 -67.200349) (xy 180.403683 -67.208403) (xy 180.361336 -67.208908) (xy 180.360574 -67.208908)
			(xy 180.322227 -67.208485) (xy 180.24582 -67.201857) (xy 180.170269 -67.188668) (xy 180.096135 -67.169018)
			(xy 180.02397 -67.143051) (xy 179.988972 -67.127374) (xy 179.978699 -67.123234) (xy 179.956573 -67.123234)
			(xy 179.9463 -67.127374) (xy 179.911298 -67.14304) (xy 179.839129 -67.16899) (xy 179.764996 -67.188636)
			(xy 179.689447 -67.201832) (xy 179.613044 -67.20848) (xy 179.574698 -67.208908) (xy 179.573936 -67.208908)
			(xy 179.531586 -67.208422) (xy 179.447268 -67.200373) (xy 179.364098 -67.184347) (xy 179.282827 -67.160486)
			(xy 179.204193 -67.129009) (xy 179.128907 -67.090199) (xy 179.057651 -67.044408) (xy 178.99107 -66.992051)
			(xy 178.929768 -66.933602) (xy 178.8743 -66.869591) (xy 178.825168 -66.800596) (xy 178.782817 -66.727244)
			(xy 178.74763 -66.650198) (xy 178.719926 -66.570156) (xy 178.699957 -66.487843) (xy 178.687902 -66.404005)
			(xy 178.683872 -66.3194) (xy 152.4 -66.3194) (xy 152.4 -69.1896) (xy 177.667872 -69.1896) (xy 177.671902 -69.104995)
			(xy 177.683957 -69.021157) (xy 177.703926 -68.938844) (xy 177.73163 -68.858802) (xy 177.766817 -68.781756)
			(xy 177.809168 -68.708404) (xy 177.8583 -68.639409) (xy 177.913768 -68.575398) (xy 177.97507 -68.516949)
			(xy 178.041651 -68.464592) (xy 178.112907 -68.418801) (xy 178.188193 -68.379991) (xy 178.266827 -68.348514)
			(xy 178.348098 -68.324653) (xy 178.431268 -68.308627) (xy 178.515586 -68.300578) (xy 178.557936 -68.300092)
			(xy 178.558444 -68.300092) (xy 178.597192 -68.300509) (xy 178.674394 -68.307273) (xy 178.750714 -68.320729)
			(xy 178.825573 -68.340774) (xy 178.898405 -68.367256) (xy 178.968657 -68.399975) (xy 179.002436 -68.418964)
			(xy 179.01031 -68.423123) (xy 179.027836 -68.426217) (xy 179.045362 -68.423123) (xy 179.053236 -68.418964)
			(xy 179.087017 -68.399978) (xy 179.157269 -68.367265) (xy 179.230101 -68.340786) (xy 179.304961 -68.320743)
			(xy 179.38128 -68.307289) (xy 179.45848 -68.300524) (xy 179.497228 -68.300092) (xy 179.497736 -68.300092)
			(xy 179.540083 -68.300597) (xy 179.624394 -68.308651) (xy 179.707558 -68.324683) (xy 179.788821 -68.348547)
			(xy 179.867448 -68.380027) (xy 179.942727 -68.418839) (xy 180.013976 -68.46463) (xy 180.080549 -68.516986)
			(xy 180.141844 -68.575434) (xy 180.197307 -68.639443) (xy 180.246433 -68.708434) (xy 180.28878 -68.781782)
			(xy 180.323962 -68.858824) (xy 180.351663 -68.938861) (xy 180.37163 -69.021168) (xy 180.383683 -69.105001)
			(xy 180.387713 -69.1896) (xy 180.383683 -69.274199) (xy 180.37163 -69.358032) (xy 180.351663 -69.440339)
			(xy 180.350534 -69.4436) (xy 181.326028 -69.4436) (xy 181.326532 -69.401252) (xy 181.334583 -69.316938)
			(xy 181.350612 -69.233772) (xy 181.374473 -69.152505) (xy 181.405952 -69.073875) (xy 181.444763 -68.998594)
			(xy 181.490553 -68.927342) (xy 181.542909 -68.860766) (xy 181.601357 -68.799468) (xy 181.665367 -68.744003)
			(xy 181.734359 -68.694874) (xy 181.807709 -68.652525) (xy 181.884752 -68.617341) (xy 181.964791 -68.589639)
			(xy 182.0471 -68.569671) (xy 182.130935 -68.557618) (xy 182.215536 -68.553588) (xy 182.300137 -68.557618)
			(xy 182.383972 -68.569671) (xy 182.426549 -68.58) (xy 183.920388 -68.58) (xy 183.924418 -68.495399)
			(xy 183.936471 -68.411564) (xy 183.956439 -68.329255) (xy 183.984141 -68.249216) (xy 184.019325 -68.172173)
			(xy 184.061674 -68.098823) (xy 184.110803 -68.029831) (xy 184.166268 -67.965821) (xy 184.227566 -67.907373)
			(xy 184.294142 -67.855017) (xy 184.365394 -67.809227) (xy 184.440675 -67.770416) (xy 184.519305 -67.738937)
			(xy 184.600572 -67.715076) (xy 184.683738 -67.699047) (xy 184.768052 -67.690996) (xy 184.8104 -67.690492)
			(xy 184.810908 -67.690492) (xy 184.85724 -67.691098) (xy 184.949398 -67.700769) (xy 185.040052 -67.719965)
			(xy 185.128221 -67.748477) (xy 185.170826 -67.766692) (xy 185.180768 -67.770498) (xy 185.202032 -67.770498)
			(xy 185.211974 -67.766692) (xy 185.254577 -67.74847) (xy 185.342744 -67.719952) (xy 185.4334 -67.70076)
			(xy 185.52556 -67.6911) (xy 185.571892 -67.690492) (xy 185.5724 -67.690492) (xy 185.614748 -67.690996)
			(xy 185.699062 -67.699047) (xy 185.782228 -67.715076) (xy 185.863495 -67.738937) (xy 185.942125 -67.770416)
			(xy 186.017406 -67.809227) (xy 186.088658 -67.855017) (xy 186.155234 -67.907373) (xy 186.216532 -67.965821)
			(xy 186.271997 -68.029831) (xy 186.321126 -68.098823) (xy 186.363475 -68.172173) (xy 186.398659 -68.249216)
			(xy 186.426361 -68.329255) (xy 186.446329 -68.411564) (xy 186.458382 -68.495399) (xy 186.462413 -68.58)
			(xy 186.458382 -68.664601) (xy 186.446329 -68.748436) (xy 186.426361 -68.830745) (xy 186.398659 -68.910784)
			(xy 186.363475 -68.987827) (xy 186.321126 -69.061177) (xy 186.271997 -69.130169) (xy 186.216532 -69.194179)
			(xy 186.155234 -69.252627) (xy 186.088658 -69.304983) (xy 186.017406 -69.350773) (xy 185.942125 -69.389584)
			(xy 185.863495 -69.421063) (xy 185.782228 -69.444924) (xy 185.699062 -69.460953) (xy 185.614748 -69.469004)
			(xy 185.5724 -69.469508) (xy 185.571892 -69.469508) (xy 185.52556 -69.468902) (xy 185.433402 -69.459231)
			(xy 185.342748 -69.440035) (xy 185.254579 -69.411523) (xy 185.211974 -69.393308) (xy 185.202032 -69.389502)
			(xy 185.180768 -69.389502) (xy 185.170826 -69.393308) (xy 185.128223 -69.41153) (xy 185.040056 -69.440048)
			(xy 184.9494 -69.45924) (xy 184.85724 -69.4689) (xy 184.810908 -69.469508) (xy 184.8104 -69.469508)
			(xy 184.768052 -69.469004) (xy 184.683738 -69.460953) (xy 184.600572 -69.444924) (xy 184.519305 -69.421063)
			(xy 184.440675 -69.389584) (xy 184.365394 -69.350773) (xy 184.294142 -69.304983) (xy 184.227566 -69.252627)
			(xy 184.166268 -69.194179) (xy 184.110803 -69.130169) (xy 184.061674 -69.061177) (xy 184.019325 -68.987827)
			(xy 183.984141 -68.910784) (xy 183.956439 -68.830745) (xy 183.936471 -68.748436) (xy 183.924418 -68.664601)
			(xy 183.920388 -68.58) (xy 182.426549 -68.58) (xy 182.466281 -68.589639) (xy 182.54632 -68.617341)
			(xy 182.623363 -68.652525) (xy 182.696713 -68.694874) (xy 182.765705 -68.744003) (xy 182.829715 -68.799468)
			(xy 182.888163 -68.860766) (xy 182.940519 -68.927342) (xy 182.986309 -68.998594) (xy 183.02512 -69.073875)
			(xy 183.056599 -69.152505) (xy 183.08046 -69.233772) (xy 183.096489 -69.316938) (xy 183.10454 -69.401252)
			(xy 183.105044 -69.4436) (xy 183.105044 -69.444362) (xy 183.104477 -69.489611) (xy 183.095255 -69.579637)
			(xy 183.076932 -69.66826) (xy 183.049699 -69.754562) (xy 183.013837 -69.837651) (xy 182.992268 -69.877432)
			(xy 182.98741 -69.887417) (xy 182.985813 -69.909537) (xy 182.98922 -69.920104) (xy 183.020462 -70.003416)
			(xy 183.03621 -70.01891) (xy 183.046878 -70.02272) (xy 183.08635 -70.037268) (xy 183.162598 -70.072818)
			(xy 183.23515 -70.115407) (xy 183.303358 -70.164655) (xy 183.366613 -70.220121) (xy 183.424349 -70.28131)
			(xy 183.476052 -70.347676) (xy 183.521259 -70.418626) (xy 183.559567 -70.493527) (xy 183.590634 -70.571709)
			(xy 183.614182 -70.652475) (xy 183.630002 -70.735103) (xy 183.63795 -70.818856) (xy 183.638444 -70.86092)
			(xy 183.63794 -70.903268) (xy 183.629889 -70.987582) (xy 183.61386 -71.070748) (xy 183.589999 -71.152015)
			(xy 183.55852 -71.230645) (xy 183.519709 -71.305926) (xy 183.473919 -71.377178) (xy 183.421563 -71.443754)
			(xy 183.363115 -71.505052) (xy 183.299105 -71.560517) (xy 183.230113 -71.609646) (xy 183.156763 -71.651995)
			(xy 183.07972 -71.687179) (xy 182.999681 -71.714881) (xy 182.917372 -71.734849) (xy 182.833537 -71.746902)
			(xy 182.748936 -71.750933) (xy 182.664335 -71.746902) (xy 182.5805 -71.734849) (xy 182.498191 -71.714881)
			(xy 182.418152 -71.687179) (xy 182.341109 -71.651995) (xy 182.267759 -71.609646) (xy 182.198767 -71.560517)
			(xy 182.134757 -71.505052) (xy 182.076309 -71.443754) (xy 182.023953 -71.377178) (xy 181.978163 -71.305926)
			(xy 181.939352 -71.230645) (xy 181.907873 -71.152015) (xy 181.884012 -71.070748) (xy 181.867983 -70.987582)
			(xy 181.859932 -70.903268) (xy 181.859428 -70.86092) (xy 181.859428 -70.860158) (xy 181.860007 -70.81491)
			(xy 181.869227 -70.724884) (xy 181.887547 -70.636261) (xy 181.914778 -70.549959) (xy 181.950636 -70.466869)
			(xy 181.972204 -70.427088) (xy 181.977111 -70.417122) (xy 181.978678 -70.394985) (xy 181.975252 -70.384416)
			(xy 181.94401 -70.301104) (xy 181.928262 -70.28561) (xy 181.917594 -70.2818) (xy 181.878145 -70.267193)
			(xy 181.801896 -70.23165) (xy 181.729343 -70.189068) (xy 181.661134 -70.139826) (xy 181.597877 -70.084366)
			(xy 181.540139 -70.023182) (xy 181.488434 -69.956821) (xy 181.443225 -69.885875) (xy 181.404914 -69.810979)
			(xy 181.373845 -69.7328) (xy 181.350295 -69.652037) (xy 181.334473 -69.569413) (xy 181.326523 -69.485663)
			(xy 181.326028 -69.4436) (xy 180.350534 -69.4436) (xy 180.323962 -69.520376) (xy 180.28878 -69.597418)
			(xy 180.246433 -69.670766) (xy 180.197307 -69.739757) (xy 180.141844 -69.803766) (xy 180.080549 -69.862214)
			(xy 180.013976 -69.91457) (xy 179.942727 -69.960361) (xy 179.867448 -69.999173) (xy 179.788821 -70.030653)
			(xy 179.707558 -70.054517) (xy 179.624394 -70.070549) (xy 179.540083 -70.078603) (xy 179.497736 -70.079108)
			(xy 179.497228 -70.079108) (xy 179.45848 -70.078658) (xy 179.38128 -70.0719) (xy 179.304961 -70.058451)
			(xy 179.230101 -70.038412) (xy 179.157268 -70.011936) (xy 179.087016 -69.979222) (xy 179.053236 -69.960236)
			(xy 179.045362 -69.956077) (xy 179.027836 -69.952983) (xy 179.01031 -69.956077) (xy 179.002436 -69.960236)
			(xy 178.968662 -69.979233) (xy 178.898407 -70.011945) (xy 178.825574 -70.038422) (xy 178.750713 -70.058462)
			(xy 178.674393 -70.071915) (xy 178.597192 -70.078678) (xy 178.558444 -70.079108) (xy 178.557936 -70.079108)
			(xy 178.515586 -70.078622) (xy 178.431268 -70.070573) (xy 178.348098 -70.054547) (xy 178.266827 -70.030686)
			(xy 178.188193 -69.999209) (xy 178.112907 -69.960399) (xy 178.041651 -69.914608) (xy 177.97507 -69.862251)
			(xy 177.913768 -69.803802) (xy 177.8583 -69.739791) (xy 177.809168 -69.670796) (xy 177.766817 -69.597444)
			(xy 177.73163 -69.520398) (xy 177.703926 -69.440356) (xy 177.683957 -69.358043) (xy 177.671902 -69.274205)
			(xy 177.667872 -69.1896) (xy 152.4 -69.1896) (xy 152.4 -72.009) (xy 177.667872 -72.009) (xy 177.671902 -71.924395)
			(xy 177.683957 -71.840557) (xy 177.703926 -71.758244) (xy 177.73163 -71.678202) (xy 177.766817 -71.601156)
			(xy 177.809168 -71.527804) (xy 177.8583 -71.458809) (xy 177.913768 -71.394798) (xy 177.97507 -71.336349)
			(xy 178.041651 -71.283992) (xy 178.112907 -71.238201) (xy 178.188193 -71.199391) (xy 178.266827 -71.167914)
			(xy 178.348098 -71.144053) (xy 178.431268 -71.128027) (xy 178.515586 -71.119978) (xy 178.557936 -71.119492)
			(xy 178.596727 -71.119889) (xy 178.674016 -71.126624) (xy 178.750424 -71.140065) (xy 178.825371 -71.16011)
			(xy 178.898288 -71.186607) (xy 178.968619 -71.219355) (xy 179.002436 -71.238364) (xy 179.01031 -71.242523)
			(xy 179.027836 -71.245617) (xy 179.045362 -71.242523) (xy 179.053236 -71.238364) (xy 179.087054 -71.219359)
			(xy 179.157387 -71.186616) (xy 179.230303 -71.160122) (xy 179.30525 -71.140079) (xy 179.381658 -71.126639)
			(xy 179.458946 -71.119903) (xy 179.497736 -71.119492) (xy 179.540083 -71.119997) (xy 179.624394 -71.128051)
			(xy 179.707558 -71.144083) (xy 179.788821 -71.167947) (xy 179.867448 -71.199427) (xy 179.942727 -71.238239)
			(xy 180.013976 -71.28403) (xy 180.080549 -71.336386) (xy 180.141844 -71.394834) (xy 180.197307 -71.458843)
			(xy 180.246433 -71.527834) (xy 180.28878 -71.601182) (xy 180.323962 -71.678224) (xy 180.351663 -71.758261)
			(xy 180.37163 -71.840568) (xy 180.383683 -71.924401) (xy 180.387713 -72.009) (xy 180.383683 -72.093599)
			(xy 180.37163 -72.177432) (xy 180.351663 -72.259739) (xy 180.323962 -72.339776) (xy 180.28878 -72.416818)
			(xy 180.246433 -72.490166) (xy 180.197307 -72.559157) (xy 180.141844 -72.623166) (xy 180.080549 -72.681614)
			(xy 180.013976 -72.73397) (xy 179.942727 -72.779761) (xy 179.867448 -72.818573) (xy 179.788821 -72.850053)
			(xy 179.707558 -72.873917) (xy 179.624394 -72.889949) (xy 179.540083 -72.898003) (xy 179.497736 -72.898508)
			(xy 179.458945 -72.898124) (xy 179.381656 -72.891387) (xy 179.305247 -72.877943) (xy 179.2303 -72.857895)
			(xy 179.157383 -72.831396) (xy 179.087053 -72.798646) (xy 179.053236 -72.779636) (xy 179.045362 -72.775477)
			(xy 179.027836 -72.772383) (xy 179.01031 -72.775477) (xy 179.002436 -72.779636) (xy 178.968624 -72.798653)
			(xy 178.89829 -72.831394) (xy 178.825372 -72.857885) (xy 178.750424 -72.877926) (xy 178.674015 -72.891365)
			(xy 178.596727 -72.898098) (xy 178.557936 -72.898508) (xy 178.515586 -72.898022) (xy 178.431268 -72.889973)
			(xy 178.348098 -72.873947) (xy 178.266827 -72.850086) (xy 178.188193 -72.818609) (xy 178.112907 -72.779799)
			(xy 178.041651 -72.734008) (xy 177.97507 -72.681651) (xy 177.913768 -72.623202) (xy 177.8583 -72.559191)
			(xy 177.809168 -72.490196) (xy 177.766817 -72.416844) (xy 177.73163 -72.339798) (xy 177.703926 -72.259756)
			(xy 177.683957 -72.177443) (xy 177.671902 -72.093605) (xy 177.667872 -72.009) (xy 152.4 -72.009)
			(xy 152.4 -74.337361) (xy 183.260742 -74.337361) (xy 183.260742 -74.252639) (xy 183.268795 -74.168302)
			(xy 183.284829 -74.085112) (xy 183.308697 -74.003822) (xy 183.340185 -73.92517) (xy 183.379007 -73.849867)
			(xy 183.42481 -73.778595) (xy 183.477181 -73.711999) (xy 183.535646 -73.650684) (xy 183.599674 -73.595203)
			(xy 183.668686 -73.54606) (xy 183.742056 -73.5037) (xy 183.819121 -73.468505) (xy 183.899183 -73.440796)
			(xy 183.981516 -73.420822) (xy 184.065375 -73.408765) (xy 184.15 -73.404734) (xy 184.234625 -73.408765)
			(xy 184.318484 -73.420822) (xy 184.400817 -73.440796) (xy 184.480879 -73.468505) (xy 184.557944 -73.5037)
			(xy 184.631314 -73.54606) (xy 184.700326 -73.595203) (xy 184.764354 -73.650684) (xy 184.822819 -73.711999)
			(xy 184.87519 -73.778595) (xy 184.920993 -73.849867) (xy 184.959815 -73.92517) (xy 184.991303 -74.003822)
			(xy 185.015171 -74.085112) (xy 185.031205 -74.168302) (xy 185.039258 -74.252639) (xy 185.039762 -74.295)
			(xy 185.039258 -74.337361) (xy 185.031205 -74.421698) (xy 185.015171 -74.504888) (xy 184.991303 -74.586178)
			(xy 184.959815 -74.66483) (xy 184.920993 -74.740133) (xy 184.87519 -74.811405) (xy 184.822819 -74.878001)
			(xy 184.764354 -74.939316) (xy 184.700326 -74.994797) (xy 184.631314 -75.04394) (xy 184.557944 -75.0863)
			(xy 184.480879 -75.121495) (xy 184.400817 -75.149204) (xy 184.318484 -75.169178) (xy 184.234625 -75.181235)
			(xy 184.15 -75.185267) (xy 184.065375 -75.181235) (xy 183.981516 -75.169178) (xy 183.899183 -75.149204)
			(xy 183.819121 -75.121495) (xy 183.742056 -75.0863) (xy 183.668686 -75.04394) (xy 183.599674 -74.994797)
			(xy 183.535646 -74.939316) (xy 183.477181 -74.878001) (xy 183.42481 -74.811405) (xy 183.379007 -74.740133)
			(xy 183.340185 -74.66483) (xy 183.308697 -74.586178) (xy 183.284829 -74.504888) (xy 183.268795 -74.421698)
			(xy 183.260742 -74.337361) (xy 152.4 -74.337361) (xy 152.4 -79.375) (xy 152.399461 -79.408259) (xy 152.390775 -79.474209)
			(xy 152.373553 -79.53846) (xy 152.348089 -79.599911) (xy 152.314818 -79.657512) (xy 152.274436 -79.710114)
			(xy 205.177635 -79.710114) (xy 205.177635 -79.539758) (xy 205.18562 -79.36959) (xy 205.201572 -79.199983)
			(xy 205.225457 -79.031311) (xy 205.257221 -78.863943) (xy 205.296796 -78.698248) (xy 205.344093 -78.53459)
			(xy 205.39901 -78.373329) (xy 205.461425 -78.214819) (xy 205.531201 -78.059409) (xy 205.608184 -77.907441)
			(xy 205.692206 -77.759247) (xy 205.783082 -77.615155) (xy 205.880612 -77.475481) (xy 205.984582 -77.340532)
			(xy 206.094763 -77.210604) (xy 206.210912 -77.085984) (xy 206.332776 -76.966945) (xy 206.460084 -76.853749)
			(xy 206.592559 -76.746644) (xy 206.729909 -76.645867) (xy 206.871831 -76.551638) (xy 207.018013 -76.464165)
			(xy 207.168136 -76.38364) (xy 207.321867 -76.31024) (xy 207.47887 -76.244126) (xy 207.6388 -76.185444)
			(xy 207.801304 -76.134323) (xy 207.966025 -76.090875) (xy 208.132603 -76.055196) (xy 208.300669 -76.027364)
			(xy 208.469855 -76.00744) (xy 208.639789 -75.995468) (xy 208.810098 -75.991475) (xy 208.980407 -75.995468)
			(xy 209.150341 -76.00744) (xy 209.319527 -76.027364) (xy 209.487593 -76.055196) (xy 209.654171 -76.090875)
			(xy 209.818892 -76.134323) (xy 209.981396 -76.185444) (xy 210.141326 -76.244126) (xy 210.298329 -76.31024)
			(xy 210.45206 -76.38364) (xy 210.602183 -76.464165) (xy 210.748365 -76.551638) (xy 210.890287 -76.645867)
			(xy 211.027637 -76.746644) (xy 211.160112 -76.853749) (xy 211.28742 -76.966945) (xy 211.409284 -77.085984)
			(xy 211.525433 -77.210604) (xy 211.635614 -77.340532) (xy 211.739584 -77.475481) (xy 211.837114 -77.615155)
			(xy 211.92799 -77.759247) (xy 212.012012 -77.907441) (xy 212.088995 -78.059409) (xy 212.158771 -78.214819)
			(xy 212.221186 -78.373329) (xy 212.276103 -78.53459) (xy 212.3234 -78.698248) (xy 212.362975 -78.863943)
			(xy 212.394739 -79.031311) (xy 212.418624 -79.199983) (xy 212.434576 -79.36959) (xy 212.442561 -79.539758)
			(xy 212.44306 -79.624936) (xy 212.442561 -79.710114) (xy 235.177575 -79.710114) (xy 235.177575 -79.539758)
			(xy 235.18556 -79.36959) (xy 235.201512 -79.199983) (xy 235.225397 -79.031311) (xy 235.257161 -78.863943)
			(xy 235.296736 -78.698248) (xy 235.344033 -78.53459) (xy 235.39895 -78.373329) (xy 235.461365 -78.214819)
			(xy 235.531141 -78.059409) (xy 235.608124 -77.907441) (xy 235.692146 -77.759247) (xy 235.783022 -77.615155)
			(xy 235.880552 -77.475481) (xy 235.984522 -77.340532) (xy 236.094703 -77.210604) (xy 236.210852 -77.085984)
			(xy 236.332716 -76.966945) (xy 236.460024 -76.853749) (xy 236.592499 -76.746644) (xy 236.729849 -76.645867)
			(xy 236.871771 -76.551638) (xy 237.017953 -76.464165) (xy 237.168076 -76.38364) (xy 237.321807 -76.31024)
			(xy 237.47881 -76.244126) (xy 237.63874 -76.185444) (xy 237.801244 -76.134323) (xy 237.965965 -76.090875)
			(xy 238.132543 -76.055196) (xy 238.300609 -76.027364) (xy 238.469795 -76.00744) (xy 238.639729 -75.995468)
			(xy 238.810038 -75.991475) (xy 238.980347 -75.995468) (xy 239.150281 -76.00744) (xy 239.319467 -76.027364)
			(xy 239.487533 -76.055196) (xy 239.654111 -76.090875) (xy 239.818832 -76.134323) (xy 239.981336 -76.185444)
			(xy 240.141266 -76.244126) (xy 240.298269 -76.31024) (xy 240.452 -76.38364) (xy 240.602123 -76.464165)
			(xy 240.748305 -76.551638) (xy 240.890227 -76.645867) (xy 241.027577 -76.746644) (xy 241.160052 -76.853749)
			(xy 241.28736 -76.966945) (xy 241.409224 -77.085984) (xy 241.525373 -77.210604) (xy 241.635554 -77.340532)
			(xy 241.739524 -77.475481) (xy 241.837054 -77.615155) (xy 241.92793 -77.759247) (xy 242.011952 -77.907441)
			(xy 242.088935 -78.059409) (xy 242.158711 -78.214819) (xy 242.221126 -78.373329) (xy 242.276043 -78.53459)
			(xy 242.32334 -78.698248) (xy 242.362915 -78.863943) (xy 242.394679 -79.031311) (xy 242.418564 -79.199983)
			(xy 242.434516 -79.36959) (xy 242.442501 -79.539758) (xy 242.443 -79.624936) (xy 242.442501 -79.710114)
			(xy 242.434516 -79.880282) (xy 242.418564 -80.049889) (xy 242.394679 -80.218561) (xy 242.362915 -80.385929)
			(xy 242.32334 -80.551624) (xy 242.276043 -80.715282) (xy 242.221126 -80.876543) (xy 242.158711 -81.035053)
			(xy 242.088935 -81.190463) (xy 242.011952 -81.342431) (xy 241.92793 -81.490625) (xy 241.837054 -81.634717)
			(xy 241.739524 -81.774391) (xy 241.635554 -81.90934) (xy 241.525373 -82.039268) (xy 241.409224 -82.163888)
			(xy 241.28736 -82.282927) (xy 241.160052 -82.396123) (xy 241.027577 -82.503228) (xy 240.890227 -82.604005)
			(xy 240.748305 -82.698234) (xy 240.602123 -82.785707) (xy 240.452 -82.866232) (xy 240.298269 -82.939632)
			(xy 240.141266 -83.005746) (xy 239.981336 -83.064428) (xy 239.818832 -83.115549) (xy 239.654111 -83.158997)
			(xy 239.487533 -83.194676) (xy 239.319467 -83.222508) (xy 239.150281 -83.242432) (xy 238.980347 -83.254404)
			(xy 238.810038 -83.258398) (xy 238.639729 -83.254404) (xy 238.469795 -83.242432) (xy 238.300609 -83.222508)
			(xy 238.132543 -83.194676) (xy 237.965965 -83.158997) (xy 237.801244 -83.115549) (xy 237.63874 -83.064428)
			(xy 237.47881 -83.005746) (xy 237.321807 -82.939632) (xy 237.168076 -82.866232) (xy 237.017953 -82.785707)
			(xy 236.871771 -82.698234) (xy 236.729849 -82.604005) (xy 236.592499 -82.503228) (xy 236.460024 -82.396123)
			(xy 236.332716 -82.282927) (xy 236.210852 -82.163888) (xy 236.094703 -82.039268) (xy 235.984522 -81.90934)
			(xy 235.880552 -81.774391) (xy 235.783022 -81.634717) (xy 235.692146 -81.490625) (xy 235.608124 -81.342431)
			(xy 235.531141 -81.190463) (xy 235.461365 -81.035053) (xy 235.39895 -80.876543) (xy 235.344033 -80.715282)
			(xy 235.296736 -80.551624) (xy 235.257161 -80.385929) (xy 235.225397 -80.218561) (xy 235.201512 -80.049889)
			(xy 235.18556 -79.880282) (xy 235.177575 -79.710114) (xy 212.442561 -79.710114) (xy 212.434576 -79.880282)
			(xy 212.418624 -80.049889) (xy 212.394739 -80.218561) (xy 212.362975 -80.385929) (xy 212.3234 -80.551624)
			(xy 212.276103 -80.715282) (xy 212.221186 -80.876543) (xy 212.158771 -81.035053) (xy 212.088995 -81.190463)
			(xy 212.012012 -81.342431) (xy 211.92799 -81.490625) (xy 211.837114 -81.634717) (xy 211.739584 -81.774391)
			(xy 211.635614 -81.90934) (xy 211.525433 -82.039268) (xy 211.409284 -82.163888) (xy 211.28742 -82.282927)
			(xy 211.160112 -82.396123) (xy 211.027637 -82.503228) (xy 210.890287 -82.604005) (xy 210.748365 -82.698234)
			(xy 210.602183 -82.785707) (xy 210.45206 -82.866232) (xy 210.298329 -82.939632) (xy 210.141326 -83.005746)
			(xy 209.981396 -83.064428) (xy 209.818892 -83.115549) (xy 209.654171 -83.158997) (xy 209.487593 -83.194676)
			(xy 209.319527 -83.222508) (xy 209.150341 -83.242432) (xy 208.980407 -83.254404) (xy 208.810098 -83.258398)
			(xy 208.639789 -83.254404) (xy 208.469855 -83.242432) (xy 208.300669 -83.222508) (xy 208.132603 -83.194676)
			(xy 207.966025 -83.158997) (xy 207.801304 -83.115549) (xy 207.6388 -83.064428) (xy 207.47887 -83.005746)
			(xy 207.321867 -82.939632) (xy 207.168136 -82.866232) (xy 207.018013 -82.785707) (xy 206.871831 -82.698234)
			(xy 206.729909 -82.604005) (xy 206.592559 -82.503228) (xy 206.460084 -82.396123) (xy 206.332776 -82.282927)
			(xy 206.210912 -82.163888) (xy 206.094763 -82.039268) (xy 205.984582 -81.90934) (xy 205.880612 -81.774391)
			(xy 205.783082 -81.634717) (xy 205.692206 -81.490625) (xy 205.608184 -81.342431) (xy 205.531201 -81.190463)
			(xy 205.461425 -81.035053) (xy 205.39901 -80.876543) (xy 205.344093 -80.715282) (xy 205.296796 -80.551624)
			(xy 205.257221 -80.385929) (xy 205.225457 -80.218561) (xy 205.201572 -80.049889) (xy 205.18562 -79.880282)
			(xy 205.177635 -79.710114) (xy 152.274436 -79.710114) (xy 152.274312 -79.710276) (xy 152.251156 -79.734156)
			(xy 151.616156 -80.369156) (xy 151.592271 -80.392308) (xy 151.539511 -80.432821) (xy 151.481912 -80.466097)
			(xy 151.420461 -80.491566) (xy 151.35621 -80.508791) (xy 151.29026 -80.517479) (xy 151.257 -80.518)
			(xy 150.4061 -80.518) (xy 150.400943 -80.518134) (xy 150.390834 -80.520176) (xy 150.386034 -80.522064)
			(xy 150.344311 -80.539436) (xy 150.258112 -80.566613) (xy 150.1696 -80.584906) (xy 150.079689 -80.594125)
			(xy 150.034498 -80.594708) (xy 150.033736 -80.594708) (xy 149.992633 -80.594214) (xy 149.910779 -80.586632)
			(xy 149.829973 -80.571529) (xy 149.750905 -80.549036) (xy 149.67425 -80.519342) (xy 149.600662 -80.482702)
			(xy 149.530769 -80.439429) (xy 149.465166 -80.38989) (xy 149.404415 -80.334511) (xy 149.349033 -80.273761)
			(xy 149.299492 -80.208161) (xy 149.256215 -80.138269) (xy 149.219573 -80.064683) (xy 149.189876 -79.988029)
			(xy 149.167379 -79.908962) (xy 149.152273 -79.828157) (xy 149.144688 -79.746303) (xy 149.144228 -79.7052)
			(xy 149.144228 -79.704692) (xy 149.144831 -79.65836) (xy 149.154503 -79.566202) (xy 149.173699 -79.475548)
			(xy 149.202212 -79.387379) (xy 149.220428 -79.344774) (xy 149.224232 -79.334831) (xy 149.224232 -79.313569)
			(xy 149.220428 -79.303626) (xy 149.202197 -79.260993) (xy 149.173665 -79.172763) (xy 149.154471 -79.082043)
			(xy 149.144825 -78.989818) (xy 149.144228 -78.943454) (xy 149.144228 -78.9432) (xy 149.144748 -78.900127)
			(xy 149.153068 -78.814385) (xy 149.169639 -78.729849) (xy 149.194307 -78.647311) (xy 149.226839 -78.567545)
			(xy 149.266932 -78.491298) (xy 149.314209 -78.419286) (xy 149.340824 -78.385416) (xy 149.345985 -78.378445)
			(xy 149.351698 -78.36208) (xy 149.352 -78.353412) (xy 149.352 -76.2) (xy 149.352539 -76.166741) (xy 149.361225 -76.100791)
			(xy 149.378447 -76.03654) (xy 149.403911 -75.975089) (xy 149.437182 -75.917488) (xy 149.477688 -75.864724)
			(xy 149.500844 -75.840844) (xy 150.988014 -74.353674) (xy 150.99486 -74.346279) (xy 151.002576 -74.327676)
			(xy 151.003 -74.317606) (xy 151.003 -68.430394) (xy 151.002604 -68.420321) (xy 150.994866 -68.401722)
			(xy 150.988014 -68.394326) (xy 150.4315 -67.837812) (xy 150.424093 -67.830981) (xy 150.405499 -67.823256)
			(xy 150.395432 -67.822826) (xy 147.268438 -67.822826) (xy 147.258918 -67.823235) (xy 147.241193 -67.830193)
			(xy 147.22722 -67.84313) (xy 147.222718 -67.851528) (xy 147.20415 -67.888594) (xy 147.161092 -67.959444)
			(xy 147.111631 -68.025982) (xy 147.056195 -68.08763) (xy 146.995265 -68.143854) (xy 146.929368 -68.194166)
			(xy 146.859078 -68.238131) (xy 146.785002 -68.275367) (xy 146.707784 -68.30555) (xy 146.628093 -68.32842)
			(xy 146.54662 -68.343777) (xy 146.464072 -68.351489) (xy 146.381164 -68.351489) (xy 146.298616 -68.343777)
			(xy 146.217143 -68.32842) (xy 146.137452 -68.30555) (xy 146.060234 -68.275367) (xy 145.986158 -68.238131)
			(xy 145.915868 -68.194166) (xy 145.849971 -68.143854) (xy 145.789041 -68.08763) (xy 145.733605 -68.025982)
			(xy 145.684144 -67.959444) (xy 145.641086 -67.888594) (xy 145.622518 -67.851528) (xy 145.618028 -67.84312)
			(xy 145.604056 -67.830173) (xy 145.586322 -67.82322) (xy 145.576798 -67.822826) (xy 143.862806 -67.822826)
			(xy 143.834866 -67.845686) (xy 143.83131 -67.86372) (xy 143.822279 -67.9067) (xy 143.796815 -67.99076)
			(xy 143.763184 -68.071898) (xy 143.742918 -68.110862) (xy 143.737504 -68.12233) (xy 143.737501 -68.147656)
			(xy 143.742918 -68.159122) (xy 143.763197 -68.198006) (xy 143.796886 -68.27898) (xy 143.822451 -68.362874)
			(xy 143.839643 -68.448874) (xy 143.848295 -68.536149) (xy 143.848836 -68.58) (xy 143.848317 -68.623763)
			(xy 143.839718 -68.710864) (xy 143.822612 -68.796702) (xy 143.797165 -68.880446) (xy 143.763623 -68.961289)
			(xy 143.743426 -69.000116) (xy 143.738194 -69.011509) (xy 143.738307 -69.036544) (xy 143.74368 -69.047868)
			(xy 143.763943 -69.086781) (xy 143.797578 -69.167817) (xy 143.823089 -69.251765) (xy 143.840228 -69.337814)
			(xy 143.848829 -69.42513) (xy 143.849344 -69.469) (xy 143.848824 -69.512819) (xy 143.840185 -69.60003)
			(xy 143.82303 -69.685972) (xy 143.797525 -69.769817) (xy 143.763915 -69.850753) (xy 143.74368 -69.889624)
			(xy 143.738368 -69.90098) (xy 143.738368 -69.92602) (xy 143.74368 -69.937376) (xy 143.763922 -69.976244)
			(xy 143.797557 -70.057173) (xy 143.82307 -70.141017) (xy 143.840214 -70.226964) (xy 143.848823 -70.31418)
			(xy 143.849344 -70.358) (xy 143.84884 -70.400397) (xy 143.84078 -70.484807) (xy 143.824732 -70.568068)
			(xy 143.800843 -70.649427) (xy 143.769328 -70.728147) (xy 143.730474 -70.803515) (xy 143.684631 -70.874848)
			(xy 143.632215 -70.9415) (xy 143.5737 -71.002868) (xy 143.509618 -71.058396) (xy 143.440547 -71.107581)
			(xy 143.367113 -71.149978) (xy 143.289982 -71.185203) (xy 143.209852 -71.212936) (xy 143.127448 -71.232927)
			(xy 143.043518 -71.244994) (xy 142.95882 -71.249029) (xy 142.874122 -71.244994) (xy 142.790192 -71.232927)
			(xy 142.707788 -71.212936) (xy 142.627658 -71.185203) (xy 142.550527 -71.149978) (xy 142.477093 -71.107581)
			(xy 142.408022 -71.058396) (xy 142.34394 -71.002868) (xy 142.285425 -70.9415) (xy 142.233009 -70.874848)
			(xy 142.187166 -70.803515) (xy 142.148312 -70.728147) (xy 142.116797 -70.649427) (xy 142.092908 -70.568068)
			(xy 142.07686 -70.484807) (xy 142.0688 -70.400397) (xy 142.068296 -70.358) (xy 142.068812 -70.314181)
			(xy 142.077451 -70.22697) (xy 142.094607 -70.141027) (xy 142.120113 -70.057183) (xy 142.153725 -69.976247)
			(xy 142.17396 -69.937376) (xy 142.179269 -69.92602) (xy 142.179269 -69.90098) (xy 142.17396 -69.889624)
			(xy 142.153713 -69.850758) (xy 142.12008 -69.769829) (xy 142.094568 -69.685984) (xy 142.077425 -69.600037)
			(xy 142.068817 -69.51282) (xy 142.068296 -69.469) (xy 142.068784 -69.425129) (xy 142.077376 -69.337809)
			(xy 142.094516 -69.251758) (xy 142.120037 -69.16781) (xy 142.153693 -69.08678) (xy 142.17396 -69.047868)
			(xy 142.179366 -69.036553) (xy 142.179479 -69.0115) (xy 142.174214 -69.000116) (xy 142.154023 -68.961286)
			(xy 142.120474 -68.880446) (xy 142.095025 -68.796702) (xy 142.07792 -68.710865) (xy 142.069327 -68.623763)
			(xy 142.068804 -68.58) (xy 142.069352 -68.536149) (xy 142.077992 -68.448872) (xy 142.095177 -68.362869)
			(xy 142.120741 -68.278975) (xy 142.154437 -68.198003) (xy 142.174722 -68.159122) (xy 142.180144 -68.147657)
			(xy 142.18014 -68.122329) (xy 142.174722 -68.110862) (xy 142.154472 -68.071891) (xy 142.120849 -67.990752)
			(xy 142.095381 -67.906695) (xy 142.08633 -67.86372) (xy 142.082774 -67.845686) (xy 142.054834 -67.822826)
			(xy 140.90904 -67.822826) (xy 140.89952 -67.823236) (xy 140.881795 -67.830194) (xy 140.867822 -67.84313)
			(xy 140.86332 -67.851528) (xy 140.844752 -67.888594) (xy 140.801694 -67.959444) (xy 140.752233 -68.025982)
			(xy 140.696797 -68.08763) (xy 140.635867 -68.143854) (xy 140.56997 -68.194166) (xy 140.49968 -68.238131)
			(xy 140.425604 -68.275367) (xy 140.348386 -68.30555) (xy 140.268695 -68.32842) (xy 140.187222 -68.343777)
			(xy 140.104674 -68.351489) (xy 140.021766 -68.351489) (xy 139.939218 -68.343777) (xy 139.857745 -68.32842)
			(xy 139.778054 -68.30555) (xy 139.700836 -68.275367) (xy 139.62676 -68.238131) (xy 139.55647 -68.194166)
			(xy 139.490573 -68.143854) (xy 139.429643 -68.08763) (xy 139.374207 -68.025982) (xy 139.324746 -67.959444)
			(xy 139.281688 -67.888594) (xy 139.26312 -67.851528) (xy 139.258628 -67.843121) (xy 139.244657 -67.830174)
			(xy 139.226924 -67.823221) (xy 139.2174 -67.822826) (xy 138.0871 -67.822826) (xy 138.07703 -67.823245)
			(xy 138.058432 -67.830969) (xy 138.051032 -67.837812) (xy 137.389616 -68.499228) (xy 137.382773 -68.506626)
			(xy 137.375054 -68.525227) (xy 137.37463 -68.535296) (xy 137.37463 -71.85406) (xy 149.046184 -71.85406)
			(xy 149.046695 -71.811643) (xy 149.054765 -71.727194) (xy 149.070836 -71.643896) (xy 149.094764 -71.562507)
			(xy 149.12633 -71.483764) (xy 149.165248 -71.408384) (xy 149.211164 -71.33705) (xy 149.263662 -71.270412)
			(xy 149.322265 -71.209073) (xy 149.354032 -71.18096) (xy 149.361938 -71.173399) (xy 149.371032 -71.153531)
			(xy 149.371558 -71.142606) (xy 149.371558 -71.06539) (xy 149.371056 -71.054461) (xy 149.361953 -71.034585)
			(xy 149.354032 -71.027036) (xy 149.322275 -70.998912) (xy 149.263673 -70.937573) (xy 149.211174 -70.870935)
			(xy 149.165256 -70.799603) (xy 149.126335 -70.724225) (xy 149.094765 -70.645485) (xy 149.070832 -70.564097)
			(xy 149.054754 -70.480801) (xy 149.046677 -70.396353) (xy 149.046184 -70.353936) (xy 149.046688 -70.311588)
			(xy 149.054739 -70.227274) (xy 149.070768 -70.144108) (xy 149.094629 -70.062841) (xy 149.126108 -69.984211)
			(xy 149.164919 -69.90893) (xy 149.210709 -69.837678) (xy 149.263065 -69.771102) (xy 149.321513 -69.709804)
			(xy 149.385523 -69.654339) (xy 149.454515 -69.60521) (xy 149.527865 -69.562861) (xy 149.604908 -69.527677)
			(xy 149.684947 -69.499975) (xy 149.767256 -69.480007) (xy 149.851091 -69.467954) (xy 149.935692 -69.463924)
			(xy 150.020293 -69.467954) (xy 150.104128 -69.480007) (xy 150.186437 -69.499975) (xy 150.266476 -69.527677)
			(xy 150.343519 -69.562861) (xy 150.416869 -69.60521) (xy 150.485861 -69.654339) (xy 150.549871 -69.709804)
			(xy 150.608319 -69.771102) (xy 150.660675 -69.837678) (xy 150.706465 -69.90893) (xy 150.745276 -69.984211)
			(xy 150.776755 -70.062841) (xy 150.800616 -70.144108) (xy 150.816645 -70.227274) (xy 150.824696 -70.311588)
			(xy 150.8252 -70.353936) (xy 150.824691 -70.396353) (xy 150.816622 -70.480803) (xy 150.800551 -70.5641)
			(xy 150.776623 -70.64549) (xy 150.745057 -70.724233) (xy 150.706139 -70.799613) (xy 150.660221 -70.870946)
			(xy 150.607723 -70.937585) (xy 150.549119 -70.998924) (xy 150.517352 -71.027036) (xy 150.509446 -71.034596)
			(xy 150.500353 -71.054465) (xy 150.499826 -71.06539) (xy 150.499826 -71.142606) (xy 150.500336 -71.153534)
			(xy 150.509433 -71.173409) (xy 150.517352 -71.18096) (xy 150.549103 -71.20909) (xy 150.607707 -71.270428)
			(xy 150.660206 -71.337064) (xy 150.706125 -71.408396) (xy 150.745047 -71.483773) (xy 150.776617 -71.562513)
			(xy 150.800551 -71.6439) (xy 150.816629 -71.727196) (xy 150.824707 -71.811643) (xy 150.8252 -71.85406)
			(xy 150.824696 -71.896408) (xy 150.816645 -71.980722) (xy 150.800616 -72.063888) (xy 150.776755 -72.145155)
			(xy 150.745276 -72.223785) (xy 150.706465 -72.299066) (xy 150.660675 -72.370318) (xy 150.608319 -72.436894)
			(xy 150.549871 -72.498192) (xy 150.485861 -72.553657) (xy 150.416869 -72.602786) (xy 150.343519 -72.645135)
			(xy 150.266476 -72.680319) (xy 150.186437 -72.708021) (xy 150.104128 -72.727989) (xy 150.020293 -72.740042)
			(xy 149.935692 -72.744073) (xy 149.851091 -72.740042) (xy 149.767256 -72.727989) (xy 149.684947 -72.708021)
			(xy 149.604908 -72.680319) (xy 149.527865 -72.645135) (xy 149.454515 -72.602786) (xy 149.385523 -72.553657)
			(xy 149.321513 -72.498192) (xy 149.263065 -72.436894) (xy 149.210709 -72.370318) (xy 149.164919 -72.299066)
			(xy 149.126108 -72.223785) (xy 149.094629 -72.145155) (xy 149.070768 -72.063888) (xy 149.054739 -71.980722)
			(xy 149.046688 -71.896408) (xy 149.046184 -71.85406) (xy 137.37463 -71.85406) (xy 137.37463 -74.360278)
			(xy 144.226788 -74.360278) (xy 144.227274 -74.317132) (xy 144.23562 -74.231244) (xy 144.252241 -74.146568)
			(xy 144.276981 -74.063898) (xy 144.309607 -73.984012) (xy 144.349813 -73.907659) (xy 144.373092 -73.871328)
			(xy 144.377639 -73.863717) (xy 144.381747 -73.846485) (xy 144.37974 -73.828884) (xy 144.37614 -73.820782)
			(xy 144.358096 -73.78366) (xy 144.328174 -73.706728) (xy 144.305503 -73.627357) (xy 144.290279 -73.546227)
			(xy 144.28263 -73.464037) (xy 144.28216 -73.422764) (xy 144.28216 -73.42251) (xy 144.282664 -73.380162)
			(xy 144.290715 -73.295848) (xy 144.306744 -73.212682) (xy 144.330605 -73.131415) (xy 144.362084 -73.052785)
			(xy 144.400895 -72.977504) (xy 144.446685 -72.906252) (xy 144.499041 -72.839676) (xy 144.557489 -72.778378)
			(xy 144.621499 -72.722913) (xy 144.690491 -72.673784) (xy 144.763841 -72.631435) (xy 144.840884 -72.596251)
			(xy 144.920923 -72.568549) (xy 145.003232 -72.548581) (xy 145.087067 -72.536528) (xy 145.171668 -72.532498)
			(xy 145.256269 -72.536528) (xy 145.340104 -72.548581) (xy 145.422413 -72.568549) (xy 145.502452 -72.596251)
			(xy 145.579495 -72.631435) (xy 145.652845 -72.673784) (xy 145.721837 -72.722913) (xy 145.785847 -72.778378)
			(xy 145.844295 -72.839676) (xy 145.896651 -72.906252) (xy 145.942441 -72.977504) (xy 145.981252 -73.052785)
			(xy 146.012731 -73.131415) (xy 146.036592 -73.212682) (xy 146.052621 -73.295848) (xy 146.060672 -73.380162)
			(xy 146.061176 -73.42251) (xy 146.061176 -73.423272) (xy 146.060668 -73.466348) (xy 146.052315 -73.552094)
			(xy 146.035714 -73.636632) (xy 146.011019 -73.719169) (xy 145.978463 -73.798933) (xy 145.93835 -73.875177)
			(xy 145.915126 -73.91146) (xy 145.910587 -73.919075) (xy 145.906476 -73.936305) (xy 145.908479 -73.953905)
			(xy 145.912078 -73.962006) (xy 145.930176 -73.999137) (xy 145.960164 -74.076112) (xy 145.982889 -74.155534)
			(xy 145.998156 -74.236721) (xy 146.005833 -74.318973) (xy 146.006312 -74.360278) (xy 146.005808 -74.402639)
			(xy 145.997755 -74.486976) (xy 145.981721 -74.570166) (xy 145.957853 -74.651456) (xy 145.926365 -74.730108)
			(xy 145.887543 -74.805411) (xy 145.84174 -74.876683) (xy 145.789369 -74.943279) (xy 145.730904 -75.004594)
			(xy 145.666876 -75.060075) (xy 145.597864 -75.109218) (xy 145.524494 -75.151578) (xy 145.447429 -75.186773)
			(xy 145.367367 -75.214482) (xy 145.285034 -75.234456) (xy 145.201175 -75.246513) (xy 145.11655 -75.250545)
			(xy 145.031925 -75.246513) (xy 144.948066 -75.234456) (xy 144.865733 -75.214482) (xy 144.785671 -75.186773)
			(xy 144.708606 -75.151578) (xy 144.635236 -75.109218) (xy 144.566224 -75.060075) (xy 144.502196 -75.004594)
			(xy 144.443731 -74.943279) (xy 144.39136 -74.876683) (xy 144.345557 -74.805411) (xy 144.306735 -74.730108)
			(xy 144.275247 -74.651456) (xy 144.251379 -74.570166) (xy 144.235345 -74.486976) (xy 144.227292 -74.402639)
			(xy 144.226788 -74.360278) (xy 137.37463 -74.360278) (xy 137.37463 -76.8584) (xy 142.64304 -76.8584)
			(xy 142.64707 -76.773794) (xy 142.659125 -76.689953) (xy 142.679094 -76.607639) (xy 142.706798 -76.527595)
			(xy 142.741985 -76.450547) (xy 142.784337 -76.377193) (xy 142.833469 -76.308197) (xy 142.888938 -76.244183)
			(xy 142.95024 -76.185733) (xy 143.016821 -76.133374) (xy 143.088078 -76.087581) (xy 143.163365 -76.048769)
			(xy 143.242 -76.017289) (xy 143.323272 -75.993427) (xy 143.406444 -75.977398) (xy 143.490763 -75.969347)
			(xy 143.533114 -75.96886) (xy 143.533368 -75.96886) (xy 143.576522 -75.969355) (xy 143.662423 -75.977737)
			(xy 143.747109 -75.994397) (xy 143.829784 -76.019177) (xy 143.909671 -76.051846) (xy 143.98602 -76.092095)
			(xy 144.058114 -76.139548) (xy 144.125275 -76.193757) (xy 144.15643 -76.223622) (xy 144.163594 -76.230101)
			(xy 144.181339 -76.237687) (xy 144.190974 -76.238354) (xy 144.270476 -76.239878) (xy 144.28851 -76.23302)
			(xy 144.295876 -76.226416) (xy 144.32649 -76.199346) (xy 144.391887 -76.150331) (xy 144.461506 -76.107524)
			(xy 144.534759 -76.071287) (xy 144.611029 -76.041924) (xy 144.689671 -76.019684) (xy 144.770022 -76.004754)
			(xy 144.851405 -75.997261) (xy 144.892268 -75.9968) (xy 144.892522 -75.9968) (xy 144.93487 -75.997289)
			(xy 145.019183 -76.005341) (xy 145.102348 -76.021372) (xy 145.183614 -76.045236) (xy 145.262242 -76.076716)
			(xy 145.337523 -76.115527) (xy 145.408773 -76.161318) (xy 145.475349 -76.213675) (xy 145.536645 -76.272123)
			(xy 145.592109 -76.336133) (xy 145.641237 -76.405125) (xy 145.683585 -76.478475) (xy 145.718768 -76.555518)
			(xy 145.74647 -76.635556) (xy 145.766437 -76.717865) (xy 145.778491 -76.8017) (xy 145.782521 -76.8863)
			(xy 145.778491 -76.9709) (xy 145.766437 -77.054735) (xy 145.74647 -77.137044) (xy 145.718768 -77.217082)
			(xy 145.683585 -77.294125) (xy 145.641237 -77.367475) (xy 145.592109 -77.436467) (xy 145.536645 -77.500477)
			(xy 145.475349 -77.558925) (xy 145.408773 -77.611282) (xy 145.337523 -77.657073) (xy 145.262242 -77.695884)
			(xy 145.183614 -77.727364) (xy 145.102348 -77.751228) (xy 145.019183 -77.767259) (xy 144.93487 -77.775311)
			(xy 144.892522 -77.775816) (xy 144.892268 -77.775816) (xy 144.849115 -77.775276) (xy 144.763216 -77.766898)
			(xy 144.678532 -77.750243) (xy 144.595858 -77.725468) (xy 144.515971 -77.692806) (xy 144.439621 -77.652563)
			(xy 144.367526 -77.605117) (xy 144.300363 -77.550915) (xy 144.269206 -77.521054) (xy 144.262065 -77.514545)
			(xy 144.244303 -77.506978) (xy 144.234662 -77.506322) (xy 144.15516 -77.504798) (xy 144.137126 -77.511656)
			(xy 144.12976 -77.51826) (xy 144.099127 -77.545309) (xy 144.033734 -77.594326) (xy 143.964118 -77.637135)
			(xy 143.890867 -77.673375) (xy 143.8146 -77.702741) (xy 143.73596 -77.724984) (xy 143.655611 -77.739917)
			(xy 143.574231 -77.747414) (xy 143.533368 -77.747876) (xy 143.533114 -77.747876) (xy 143.490763 -77.747453)
			(xy 143.406444 -77.739402) (xy 143.323272 -77.723373) (xy 143.242 -77.699511) (xy 143.163365 -77.668031)
			(xy 143.088078 -77.629219) (xy 143.016821 -77.583426) (xy 142.95024 -77.531067) (xy 142.888938 -77.472617)
			(xy 142.833469 -77.408603) (xy 142.784337 -77.339607) (xy 142.741985 -77.266253) (xy 142.706798 -77.189205)
			(xy 142.679094 -77.109161) (xy 142.659125 -77.026847) (xy 142.64707 -76.943006) (xy 142.64304 -76.8584)
			(xy 137.37463 -76.8584) (xy 137.37463 -79.89062) (xy 137.374124 -79.923881) (xy 137.365434 -79.989832)
			(xy 137.348207 -80.054084) (xy 137.322737 -80.115537) (xy 137.28946 -80.173137) (xy 137.248946 -80.225898)
			(xy 137.225786 -80.249776) (xy 136.598406 -80.877156) (xy 136.574543 -80.900332) (xy 136.521779 -80.940843)
			(xy 136.464175 -80.974115) (xy 136.40272 -80.99958) (xy 136.338465 -81.0168) (xy 136.272511 -81.025482)
			(xy 136.23925 -81.026) (xy 123.4694 -81.026) (xy 123.436141 -81.025461) (xy 123.370191 -81.016775)
			(xy 123.30594 -80.999553) (xy 123.244489 -80.974089) (xy 123.186888 -80.940818) (xy 123.134124 -80.900312)
			(xy 123.110244 -80.877156) (xy 122.475244 -80.242156) (xy 122.452092 -80.218271) (xy 122.411579 -80.165511)
			(xy 122.378303 -80.107912) (xy 122.352834 -80.046461) (xy 122.335609 -79.98221) (xy 122.326921 -79.91626)
			(xy 122.3264 -79.883) (xy 62.930237 -79.883) (xy 62.866209 -79.937386) (xy 62.777346 -80.002441)
			(xy 62.68402 -80.060913) (xy 62.586718 -80.1125) (xy 62.485947 -80.156931) (xy 62.382233 -80.193974)
			(xy 62.276116 -80.223437) (xy 62.16815 -80.245167) (xy 62.058897 -80.259049) (xy 61.948927 -80.265011)
			(xy 61.838814 -80.263023) (xy 61.729131 -80.253094) (xy 61.620451 -80.235277) (xy 61.51334 -80.209664)
			(xy 61.408356 -80.176389) (xy 61.306047 -80.135625) (xy 61.206946 -80.087585) (xy 61.111569 -80.03252)
			(xy 61.020415 -79.970715) (xy 60.933958 -79.902495) (xy 60.852649 -79.828214) (xy 60.776912 -79.748259)
			(xy 60.707141 -79.663048) (xy 60.643702 -79.573024) (xy 60.586923 -79.478657) (xy 60.537102 -79.38044)
			(xy 60.494498 -79.278883) (xy 60.459333 -79.174517) (xy 60.43179 -79.067886) (xy 60.412014 -78.959545)
			(xy 60.400106 -78.850059) (xy 60.396131 -78.74) (xy 43.888152 -78.74) (xy 43.887655 -78.795066) (xy 43.879708 -78.90491)
			(xy 43.863856 -79.013894) (xy 43.840181 -79.12145) (xy 43.808807 -79.227018) (xy 43.769897 -79.330046)
			(xy 43.723654 -79.429998) (xy 43.67032 -79.526353) (xy 43.610171 -79.618609) (xy 43.543523 -79.706283)
			(xy 43.470722 -79.78892) (xy 43.392147 -79.866088) (xy 43.308209 -79.937386) (xy 43.219346 -80.002441)
			(xy 43.12602 -80.060913) (xy 43.028718 -80.1125) (xy 42.927947 -80.156931) (xy 42.824233 -80.193974)
			(xy 42.718116 -80.223437) (xy 42.61015 -80.245167) (xy 42.500897 -80.259049) (xy 42.390927 -80.265011)
			(xy 42.280814 -80.263023) (xy 42.171131 -80.253094) (xy 42.062451 -80.235277) (xy 41.95534 -80.209664)
			(xy 41.850356 -80.176389) (xy 41.748047 -80.135625) (xy 41.648946 -80.087585) (xy 41.553569 -80.03252)
			(xy 41.462415 -79.970715) (xy 41.375958 -79.902495) (xy 41.294649 -79.828214) (xy 41.218912 -79.748259)
			(xy 41.149141 -79.663048) (xy 41.085702 -79.573024) (xy 41.028923 -79.478657) (xy 40.979102 -79.38044)
			(xy 40.936498 -79.278883) (xy 40.901333 -79.174517) (xy 40.87379 -79.067886) (xy 40.854014 -78.959545)
			(xy 40.842106 -78.850059) (xy 40.838131 -78.74) (xy 0.509016 -78.74) (xy 0.509016 -82.3041) (xy 175.3616 -82.3041)
			(xy 175.36563 -82.219499) (xy 175.377684 -82.135664) (xy 175.397652 -82.053355) (xy 175.425354 -81.973317)
			(xy 175.460539 -81.896274) (xy 175.502888 -81.822925) (xy 175.552017 -81.753933) (xy 175.607482 -81.689924)
			(xy 175.668781 -81.631477) (xy 175.735357 -81.579122) (xy 175.806609 -81.533332) (xy 175.881891 -81.494523)
			(xy 175.960521 -81.463045) (xy 176.041788 -81.439185) (xy 176.124954 -81.423157) (xy 176.209268 -81.415107)
			(xy 176.251616 -81.41462) (xy 176.252378 -81.41462) (xy 176.293924 -81.415132) (xy 176.37665 -81.422912)
			(xy 176.458292 -81.438368) (xy 176.538137 -81.461365) (xy 176.57699 -81.476088) (xy 176.586068 -81.479207)
			(xy 176.60525 -81.479207) (xy 176.614328 -81.476088) (xy 176.653174 -81.461346) (xy 176.733019 -81.438336)
			(xy 176.814663 -81.422879) (xy 176.897393 -81.415109) (xy 176.93894 -81.41462) (xy 176.939702 -81.41462)
			(xy 176.982052 -81.415068) (xy 177.066368 -81.423119) (xy 177.149537 -81.439149) (xy 177.230805 -81.463012)
			(xy 177.309438 -81.494491) (xy 177.384721 -81.533303) (xy 177.455975 -81.579095) (xy 177.522553 -81.631453)
			(xy 177.583853 -81.689902) (xy 177.63932 -81.753914) (xy 177.68845 -81.822908) (xy 177.7308 -81.89626)
			(xy 177.765985 -81.973306) (xy 177.793688 -82.053347) (xy 177.813656 -82.135659) (xy 177.82571 -82.219496)
			(xy 177.829741 -82.3041) (xy 177.82571 -82.388704) (xy 177.813656 -82.472541) (xy 177.793688 -82.554853)
			(xy 177.765985 -82.634894) (xy 177.7308 -82.71194) (xy 177.68845 -82.785292) (xy 177.63932 -82.854286)
			(xy 177.583853 -82.918298) (xy 177.522553 -82.976747) (xy 177.455975 -83.029105) (xy 177.384721 -83.074897)
			(xy 177.309438 -83.113709) (xy 177.230805 -83.145188) (xy 177.149537 -83.169051) (xy 177.066368 -83.185081)
			(xy 176.982052 -83.193132) (xy 176.939702 -83.193636) (xy 176.93894 -83.193636) (xy 176.897394 -83.193153)
			(xy 176.814666 -83.185365) (xy 176.733025 -83.169901) (xy 176.65318 -83.146895) (xy 176.614328 -83.132168)
			(xy 176.605259 -83.128992) (xy 176.586059 -83.128992) (xy 176.57699 -83.132168) (xy 176.538143 -83.146908)
			(xy 176.458298 -83.169917) (xy 176.376655 -83.185375) (xy 176.293925 -83.193146) (xy 176.252378 -83.193636)
			(xy 176.251616 -83.193636) (xy 176.209268 -83.193093) (xy 176.124954 -83.185043) (xy 176.041788 -83.169015)
			(xy 175.960521 -83.145155) (xy 175.881891 -83.113677) (xy 175.806609 -83.074868) (xy 175.735357 -83.029078)
			(xy 175.668781 -82.976723) (xy 175.607482 -82.918276) (xy 175.552017 -82.854267) (xy 175.502888 -82.785275)
			(xy 175.460539 -82.711926) (xy 175.425354 -82.634883) (xy 175.397652 -82.554845) (xy 175.377684 -82.472536)
			(xy 175.36563 -82.388701) (xy 175.3616 -82.3041) (xy 0.509016 -82.3041) (xy 0.509016 -86.127279)
			(xy 159.685986 -86.127279) (xy 159.685986 -86.042557) (xy 159.694039 -85.95822) (xy 159.710073 -85.87503)
			(xy 159.733941 -85.79374) (xy 159.765429 -85.715088) (xy 159.804251 -85.639785) (xy 159.850054 -85.568513)
			(xy 159.902425 -85.501917) (xy 159.96089 -85.440602) (xy 160.024918 -85.385121) (xy 160.09393 -85.335978)
			(xy 160.1673 -85.293618) (xy 160.244365 -85.258423) (xy 160.324427 -85.230714) (xy 160.40676 -85.21074)
			(xy 160.490619 -85.198683) (xy 160.575244 -85.194652) (xy 160.659869 -85.198683) (xy 160.743728 -85.21074)
			(xy 160.826061 -85.230714) (xy 160.906123 -85.258423) (xy 160.983188 -85.293618) (xy 161.056558 -85.335978)
			(xy 161.12557 -85.385121) (xy 161.189598 -85.440602) (xy 161.248063 -85.501917) (xy 161.300434 -85.568513)
			(xy 161.346237 -85.639785) (xy 161.385059 -85.715088) (xy 161.416547 -85.79374) (xy 161.440415 -85.87503)
			(xy 161.456449 -85.95822) (xy 161.464502 -86.042557) (xy 161.465006 -86.084918) (xy 161.464502 -86.127279)
			(xy 161.456449 -86.211616) (xy 161.440415 -86.294806) (xy 161.416547 -86.376096) (xy 161.385059 -86.454748)
			(xy 161.346237 -86.530051) (xy 161.300434 -86.601323) (xy 161.248063 -86.667919) (xy 161.189598 -86.729234)
			(xy 161.12557 -86.784715) (xy 161.056558 -86.833858) (xy 160.983188 -86.876218) (xy 160.906123 -86.911413)
			(xy 160.826061 -86.939122) (xy 160.743728 -86.959096) (xy 160.659869 -86.971153) (xy 160.575244 -86.975185)
			(xy 160.490619 -86.971153) (xy 160.40676 -86.959096) (xy 160.324427 -86.939122) (xy 160.244365 -86.911413)
			(xy 160.1673 -86.876218) (xy 160.09393 -86.833858) (xy 160.024918 -86.784715) (xy 159.96089 -86.729234)
			(xy 159.902425 -86.667919) (xy 159.850054 -86.601323) (xy 159.804251 -86.530051) (xy 159.765429 -86.454748)
			(xy 159.733941 -86.376096) (xy 159.710073 -86.294806) (xy 159.694039 -86.211616) (xy 159.685986 -86.127279)
			(xy 0.509016 -86.127279) (xy 0.509016 -91.559888) (xy 41.345622 -91.559888) (xy 41.349604 -91.469938)
			(xy 41.361521 -91.380691) (xy 41.381279 -91.292847) (xy 41.408723 -91.207093) (xy 41.443639 -91.1241)
			(xy 41.485753 -91.044518) (xy 41.534736 -90.968969) (xy 41.590204 -90.898045) (xy 41.651724 -90.8323)
			(xy 41.718813 -90.77225) (xy 41.790947 -90.718365) (xy 41.867561 -90.671065) (xy 41.948055 -90.630722)
			(xy 42.0318 -90.59765) (xy 42.118141 -90.57211) (xy 42.2064 -90.5543) (xy 42.295889 -90.54436) (xy 42.385905 -90.542369)
			(xy 42.475746 -90.54834) (xy 42.564707 -90.562229) (xy 42.652092 -90.583925) (xy 42.737218 -90.61326)
			(xy 42.819418 -90.650003) (xy 42.898049 -90.693867) (xy 42.972496 -90.744509) (xy 43.042176 -90.801533)
			(xy 43.106543 -90.864492) (xy 43.165094 -90.932893) (xy 43.217371 -91.006201) (xy 43.262964 -91.083843)
			(xy 43.301517 -91.16521) (xy 43.332728 -91.249666) (xy 43.356352 -91.33655) (xy 43.372205 -91.425182)
			(xy 43.380162 -91.514869) (xy 43.38066 -91.559888) (xy 60.903622 -91.559888) (xy 60.907604 -91.469938)
			(xy 60.919521 -91.380691) (xy 60.939279 -91.292847) (xy 60.966723 -91.207093) (xy 61.001639 -91.1241)
			(xy 61.043753 -91.044518) (xy 61.092736 -90.968969) (xy 61.148204 -90.898045) (xy 61.209724 -90.8323)
			(xy 61.276813 -90.77225) (xy 61.348947 -90.718365) (xy 61.425561 -90.671065) (xy 61.506055 -90.630722)
			(xy 61.5898 -90.59765) (xy 61.676141 -90.57211) (xy 61.7644 -90.5543) (xy 61.853889 -90.54436) (xy 61.943905 -90.542369)
			(xy 62.033746 -90.54834) (xy 62.122707 -90.562229) (xy 62.210092 -90.583925) (xy 62.295218 -90.61326)
			(xy 62.377418 -90.650003) (xy 62.456049 -90.693867) (xy 62.530496 -90.744509) (xy 62.600176 -90.801533)
			(xy 62.664543 -90.864492) (xy 62.723094 -90.932893) (xy 62.775371 -91.006201) (xy 62.820964 -91.083843)
			(xy 62.859517 -91.16521) (xy 62.890728 -91.249666) (xy 62.914352 -91.33655) (xy 62.930205 -91.425182)
			(xy 62.938162 -91.514869) (xy 62.93866 -91.559888) (xy 377.061232 -91.559888) (xy 377.065214 -91.469938)
			(xy 377.077131 -91.380691) (xy 377.096889 -91.292847) (xy 377.124333 -91.207093) (xy 377.159249 -91.1241)
			(xy 377.201363 -91.044518) (xy 377.250346 -90.968969) (xy 377.305814 -90.898045) (xy 377.367334 -90.8323)
			(xy 377.434423 -90.77225) (xy 377.506557 -90.718365) (xy 377.583171 -90.671065) (xy 377.663665 -90.630722)
			(xy 377.74741 -90.59765) (xy 377.833751 -90.57211) (xy 377.92201 -90.5543) (xy 378.011499 -90.54436)
			(xy 378.101515 -90.542369) (xy 378.191356 -90.54834) (xy 378.280317 -90.562229) (xy 378.367702 -90.583925)
			(xy 378.452828 -90.61326) (xy 378.535028 -90.650003) (xy 378.613659 -90.693867) (xy 378.688106 -90.744509)
			(xy 378.757786 -90.801533) (xy 378.822153 -90.864492) (xy 378.880704 -90.932893) (xy 378.932981 -91.006201)
			(xy 378.978574 -91.083843) (xy 379.017127 -91.16521) (xy 379.048338 -91.249666) (xy 379.071962 -91.33655)
			(xy 379.087815 -91.425182) (xy 379.095772 -91.514869) (xy 379.09627 -91.559888) (xy 396.619232 -91.559888)
			(xy 396.623214 -91.469938) (xy 396.635131 -91.380691) (xy 396.654889 -91.292847) (xy 396.682333 -91.207093)
			(xy 396.717249 -91.1241) (xy 396.759363 -91.044518) (xy 396.808346 -90.968969) (xy 396.863814 -90.898045)
			(xy 396.925334 -90.8323) (xy 396.992423 -90.77225) (xy 397.064557 -90.718365) (xy 397.141171 -90.671065)
			(xy 397.221665 -90.630722) (xy 397.30541 -90.59765) (xy 397.391751 -90.57211) (xy 397.48001 -90.5543)
			(xy 397.569499 -90.54436) (xy 397.659515 -90.542369) (xy 397.749356 -90.54834) (xy 397.838317 -90.562229)
			(xy 397.925702 -90.583925) (xy 398.010828 -90.61326) (xy 398.093028 -90.650003) (xy 398.171659 -90.693867)
			(xy 398.246106 -90.744509) (xy 398.315786 -90.801533) (xy 398.380153 -90.864492) (xy 398.438704 -90.932893)
			(xy 398.490981 -91.006201) (xy 398.536574 -91.083843) (xy 398.575127 -91.16521) (xy 398.606338 -91.249666)
			(xy 398.629962 -91.33655) (xy 398.645815 -91.425182) (xy 398.653772 -91.514869) (xy 398.65416 -91.549982)
			(xy 470.018373 -91.549982) (xy 470.022363 -91.436999) (xy 470.034312 -91.324578) (xy 470.054162 -91.213281)
			(xy 470.081814 -91.103661) (xy 470.117128 -90.996264) (xy 470.159931 -90.891626) (xy 470.210008 -90.790268)
			(xy 470.26711 -90.692695) (xy 470.330952 -90.599393) (xy 470.401217 -90.510827) (xy 470.477554 -90.427437)
			(xy 470.559583 -90.34964) (xy 470.646896 -90.277823) (xy 470.739057 -90.212344) (xy 470.835607 -90.153529)
			(xy 470.936065 -90.101671) (xy 471.039932 -90.057029) (xy 471.146688 -90.019824) (xy 471.255803 -89.990242)
			(xy 471.366733 -89.968431) (xy 471.478925 -89.9545) (xy 471.59182 -89.948516) (xy 471.704856 -89.950512)
			(xy 471.81747 -89.960475) (xy 471.929101 -89.978358) (xy 472.039192 -90.00407) (xy 472.147195 -90.037484)
			(xy 472.252572 -90.078433) (xy 472.354798 -90.126714) (xy 472.453363 -90.182085) (xy 472.547778 -90.24427)
			(xy 472.63757 -90.312961) (xy 472.722294 -90.387815) (xy 472.801527 -90.468458) (xy 472.874873 -90.55449)
			(xy 472.941969 -90.645481) (xy 473.002478 -90.740978) (xy 473.056101 -90.840505) (xy 473.10257 -90.943568)
			(xy 473.141653 -91.049651) (xy 473.173156 -91.158227) (xy 473.196921 -91.268754) (xy 473.212831 -91.380683)
			(xy 473.220805 -91.493455) (xy 473.221304 -91.549982) (xy 473.220805 -91.606509) (xy 473.212831 -91.719281)
			(xy 473.196921 -91.83121) (xy 473.173156 -91.941737) (xy 473.141653 -92.050313) (xy 473.10257 -92.156396)
			(xy 473.056101 -92.259459) (xy 473.002478 -92.358986) (xy 472.941969 -92.454483) (xy 472.874873 -92.545474)
			(xy 472.801527 -92.631506) (xy 472.722294 -92.712149) (xy 472.63757 -92.787003) (xy 472.547778 -92.855694)
			(xy 472.453363 -92.917879) (xy 472.354798 -92.97325) (xy 472.252572 -93.021531) (xy 472.147195 -93.06248)
			(xy 472.039192 -93.095894) (xy 471.929101 -93.121606) (xy 471.81747 -93.139489) (xy 471.704856 -93.149452)
			(xy 471.59182 -93.151448) (xy 471.478925 -93.145464) (xy 471.366733 -93.131533) (xy 471.255803 -93.109722)
			(xy 471.146688 -93.08014) (xy 471.039932 -93.042935) (xy 470.936065 -92.998293) (xy 470.835607 -92.946435)
			(xy 470.739057 -92.88762) (xy 470.646896 -92.822141) (xy 470.559583 -92.750324) (xy 470.477554 -92.672527)
			(xy 470.401217 -92.589137) (xy 470.330952 -92.500571) (xy 470.26711 -92.407269) (xy 470.210008 -92.309696)
			(xy 470.159931 -92.208338) (xy 470.117128 -92.1037) (xy 470.081814 -91.996303) (xy 470.054162 -91.886683)
			(xy 470.034312 -91.775386) (xy 470.022363 -91.662965) (xy 470.018373 -91.549982) (xy 398.65416 -91.549982)
			(xy 398.65427 -91.559888) (xy 398.653772 -91.604907) (xy 398.645815 -91.694594) (xy 398.629962 -91.783226)
			(xy 398.606338 -91.87011) (xy 398.575127 -91.954566) (xy 398.536574 -92.035933) (xy 398.490981 -92.113575)
			(xy 398.438704 -92.186883) (xy 398.380153 -92.255284) (xy 398.315786 -92.318243) (xy 398.246106 -92.375267)
			(xy 398.171659 -92.425909) (xy 398.093028 -92.469773) (xy 398.010828 -92.506516) (xy 397.925702 -92.535851)
			(xy 397.838317 -92.557547) (xy 397.749356 -92.571436) (xy 397.659515 -92.577407) (xy 397.569499 -92.575416)
			(xy 397.48001 -92.565476) (xy 397.391751 -92.547666) (xy 397.30541 -92.522126) (xy 397.221665 -92.489054)
			(xy 397.141171 -92.448711) (xy 397.064557 -92.401411) (xy 396.992423 -92.347526) (xy 396.925334 -92.287476)
			(xy 396.863814 -92.221731) (xy 396.808346 -92.150807) (xy 396.759363 -92.075258) (xy 396.717249 -91.995676)
			(xy 396.682333 -91.912683) (xy 396.654889 -91.826929) (xy 396.635131 -91.739085) (xy 396.623214 -91.649838)
			(xy 396.619232 -91.559888) (xy 379.09627 -91.559888) (xy 379.095772 -91.604907) (xy 379.087815 -91.694594)
			(xy 379.071962 -91.783226) (xy 379.048338 -91.87011) (xy 379.017127 -91.954566) (xy 378.978574 -92.035933)
			(xy 378.932981 -92.113575) (xy 378.880704 -92.186883) (xy 378.822153 -92.255284) (xy 378.757786 -92.318243)
			(xy 378.688106 -92.375267) (xy 378.613659 -92.425909) (xy 378.535028 -92.469773) (xy 378.452828 -92.506516)
			(xy 378.367702 -92.535851) (xy 378.280317 -92.557547) (xy 378.191356 -92.571436) (xy 378.101515 -92.577407)
			(xy 378.011499 -92.575416) (xy 377.92201 -92.565476) (xy 377.833751 -92.547666) (xy 377.74741 -92.522126)
			(xy 377.663665 -92.489054) (xy 377.583171 -92.448711) (xy 377.506557 -92.401411) (xy 377.434423 -92.347526)
			(xy 377.367334 -92.287476) (xy 377.305814 -92.221731) (xy 377.250346 -92.150807) (xy 377.201363 -92.075258)
			(xy 377.159249 -91.995676) (xy 377.124333 -91.912683) (xy 377.096889 -91.826929) (xy 377.077131 -91.739085)
			(xy 377.065214 -91.649838) (xy 377.061232 -91.559888) (xy 62.93866 -91.559888) (xy 62.938162 -91.604907)
			(xy 62.930205 -91.694594) (xy 62.914352 -91.783226) (xy 62.890728 -91.87011) (xy 62.859517 -91.954566)
			(xy 62.820964 -92.035933) (xy 62.775371 -92.113575) (xy 62.723094 -92.186883) (xy 62.664543 -92.255284)
			(xy 62.600176 -92.318243) (xy 62.530496 -92.375267) (xy 62.456049 -92.425909) (xy 62.377418 -92.469773)
			(xy 62.295218 -92.506516) (xy 62.210092 -92.535851) (xy 62.122707 -92.557547) (xy 62.033746 -92.571436)
			(xy 61.943905 -92.577407) (xy 61.853889 -92.575416) (xy 61.7644 -92.565476) (xy 61.676141 -92.547666)
			(xy 61.5898 -92.522126) (xy 61.506055 -92.489054) (xy 61.425561 -92.448711) (xy 61.348947 -92.401411)
			(xy 61.276813 -92.347526) (xy 61.209724 -92.287476) (xy 61.148204 -92.221731) (xy 61.092736 -92.150807)
			(xy 61.043753 -92.075258) (xy 61.001639 -91.995676) (xy 60.966723 -91.912683) (xy 60.939279 -91.826929)
			(xy 60.919521 -91.739085) (xy 60.907604 -91.649838) (xy 60.903622 -91.559888) (xy 43.38066 -91.559888)
			(xy 43.380162 -91.604907) (xy 43.372205 -91.694594) (xy 43.356352 -91.783226) (xy 43.332728 -91.87011)
			(xy 43.301517 -91.954566) (xy 43.262964 -92.035933) (xy 43.217371 -92.113575) (xy 43.165094 -92.186883)
			(xy 43.106543 -92.255284) (xy 43.042176 -92.318243) (xy 42.972496 -92.375267) (xy 42.898049 -92.425909)
			(xy 42.819418 -92.469773) (xy 42.737218 -92.506516) (xy 42.652092 -92.535851) (xy 42.564707 -92.557547)
			(xy 42.475746 -92.571436) (xy 42.385905 -92.577407) (xy 42.295889 -92.575416) (xy 42.2064 -92.565476)
			(xy 42.118141 -92.547666) (xy 42.0318 -92.522126) (xy 41.948055 -92.489054) (xy 41.867561 -92.448711)
			(xy 41.790947 -92.401411) (xy 41.718813 -92.347526) (xy 41.651724 -92.287476) (xy 41.590204 -92.221731)
			(xy 41.534736 -92.150807) (xy 41.485753 -92.075258) (xy 41.443639 -91.995676) (xy 41.408723 -91.912683)
			(xy 41.381279 -91.826929) (xy 41.361521 -91.739085) (xy 41.349604 -91.649838) (xy 41.345622 -91.559888)
			(xy 0.509016 -91.559888) (xy 0.509016 -96.308361) (xy 157.479742 -96.308361) (xy 157.479742 -96.223639)
			(xy 157.487795 -96.139302) (xy 157.503829 -96.056112) (xy 157.527697 -95.974822) (xy 157.559185 -95.89617)
			(xy 157.598007 -95.820867) (xy 157.64381 -95.749595) (xy 157.696181 -95.682999) (xy 157.754646 -95.621684)
			(xy 157.818674 -95.566203) (xy 157.887686 -95.51706) (xy 157.961056 -95.4747) (xy 158.038121 -95.439505)
			(xy 158.118183 -95.411796) (xy 158.200516 -95.391822) (xy 158.284375 -95.379765) (xy 158.369 -95.375734)
			(xy 158.453625 -95.379765) (xy 158.537484 -95.391822) (xy 158.619817 -95.411796) (xy 158.699879 -95.439505)
			(xy 158.776944 -95.4747) (xy 158.850314 -95.51706) (xy 158.919326 -95.566203) (xy 158.983354 -95.621684)
			(xy 159.041819 -95.682999) (xy 159.09419 -95.749595) (xy 159.139993 -95.820867) (xy 159.178815 -95.89617)
			(xy 159.210303 -95.974822) (xy 159.234171 -96.056112) (xy 159.250205 -96.139302) (xy 159.258258 -96.223639)
			(xy 159.258762 -96.266) (xy 159.258258 -96.308361) (xy 159.250205 -96.392698) (xy 159.234171 -96.475888)
			(xy 159.210303 -96.557178) (xy 159.178815 -96.63583) (xy 159.139993 -96.711133) (xy 159.09419 -96.782405)
			(xy 159.041819 -96.849001) (xy 158.983354 -96.910316) (xy 158.919326 -96.965797) (xy 158.850314 -97.01494)
			(xy 158.776944 -97.0573) (xy 158.699879 -97.092495) (xy 158.619817 -97.120204) (xy 158.537484 -97.140178)
			(xy 158.453625 -97.152235) (xy 158.369 -97.156267) (xy 158.284375 -97.152235) (xy 158.200516 -97.140178)
			(xy 158.118183 -97.120204) (xy 158.038121 -97.092495) (xy 157.961056 -97.0573) (xy 157.887686 -97.01494)
			(xy 157.818674 -96.965797) (xy 157.754646 -96.910316) (xy 157.696181 -96.849001) (xy 157.64381 -96.782405)
			(xy 157.598007 -96.711133) (xy 157.559185 -96.63583) (xy 157.527697 -96.557178) (xy 157.503829 -96.475888)
			(xy 157.487795 -96.392698) (xy 157.479742 -96.308361) (xy 0.509016 -96.308361) (xy 0.509016 -99.06)
			(xy 40.838131 -99.06) (xy 40.842106 -98.949941) (xy 40.854014 -98.840455) (xy 40.87379 -98.732114)
			(xy 40.901333 -98.625483) (xy 40.936498 -98.521117) (xy 40.979102 -98.41956) (xy 41.028923 -98.321343)
			(xy 41.085702 -98.226976) (xy 41.149141 -98.136952) (xy 41.218912 -98.051741) (xy 41.294649 -97.971786)
			(xy 41.375958 -97.897505) (xy 41.462415 -97.829285) (xy 41.553569 -97.76748) (xy 41.648946 -97.712415)
			(xy 41.748047 -97.664375) (xy 41.850356 -97.623611) (xy 41.95534 -97.590336) (xy 42.062451 -97.564723)
			(xy 42.171131 -97.546906) (xy 42.280814 -97.536977) (xy 42.390927 -97.534989) (xy 42.500897 -97.540951)
			(xy 42.61015 -97.554833) (xy 42.718116 -97.576563) (xy 42.824233 -97.606026) (xy 42.927947 -97.643069)
			(xy 43.028718 -97.6875) (xy 43.12602 -97.739087) (xy 43.219346 -97.797559) (xy 43.308209 -97.862614)
			(xy 43.392147 -97.933912) (xy 43.470722 -98.01108) (xy 43.543523 -98.093717) (xy 43.610171 -98.181391)
			(xy 43.67032 -98.273647) (xy 43.723654 -98.370002) (xy 43.769897 -98.469954) (xy 43.808807 -98.572982)
			(xy 43.840181 -98.67855) (xy 43.863856 -98.786106) (xy 43.879708 -98.89509) (xy 43.887655 -99.004934)
			(xy 43.888152 -99.06) (xy 60.396131 -99.06) (xy 60.400106 -98.949941) (xy 60.412014 -98.840455) (xy 60.43179 -98.732114)
			(xy 60.459333 -98.625483) (xy 60.494498 -98.521117) (xy 60.537102 -98.41956) (xy 60.586923 -98.321343)
			(xy 60.643702 -98.226976) (xy 60.707141 -98.136952) (xy 60.776912 -98.051741) (xy 60.852649 -97.971786)
			(xy 60.933958 -97.897505) (xy 61.020415 -97.829285) (xy 61.111569 -97.76748) (xy 61.206946 -97.712415)
			(xy 61.306047 -97.664375) (xy 61.408356 -97.623611) (xy 61.51334 -97.590336) (xy 61.620451 -97.564723)
			(xy 61.729131 -97.546906) (xy 61.838814 -97.536977) (xy 61.948927 -97.534989) (xy 62.058897 -97.540951)
			(xy 62.16815 -97.554833) (xy 62.276116 -97.576563) (xy 62.382233 -97.606026) (xy 62.485947 -97.643069)
			(xy 62.586718 -97.6875) (xy 62.68402 -97.739087) (xy 62.777346 -97.797559) (xy 62.866209 -97.862614)
			(xy 62.950147 -97.933912) (xy 63.028722 -98.01108) (xy 63.101523 -98.093717) (xy 63.168171 -98.181391)
			(xy 63.22832 -98.273647) (xy 63.281654 -98.370002) (xy 63.327897 -98.469954) (xy 63.366807 -98.572982)
			(xy 63.398181 -98.67855) (xy 63.421856 -98.786106) (xy 63.437708 -98.89509) (xy 63.445655 -99.004934)
			(xy 63.446152 -99.06) (xy 376.553741 -99.06) (xy 376.557716 -98.949941) (xy 376.569624 -98.840455)
			(xy 376.5894 -98.732114) (xy 376.616943 -98.625483) (xy 376.652108 -98.521117) (xy 376.694712 -98.41956)
			(xy 376.744533 -98.321343) (xy 376.801312 -98.226976) (xy 376.864751 -98.136952) (xy 376.934522 -98.051741)
			(xy 377.010259 -97.971786) (xy 377.091568 -97.897505) (xy 377.178025 -97.829285) (xy 377.269179 -97.76748)
			(xy 377.364556 -97.712415) (xy 377.463657 -97.664375) (xy 377.565966 -97.623611) (xy 377.67095 -97.590336)
			(xy 377.778061 -97.564723) (xy 377.886741 -97.546906) (xy 377.996424 -97.536977) (xy 378.106537 -97.534989)
			(xy 378.216507 -97.540951) (xy 378.32576 -97.554833) (xy 378.433726 -97.576563) (xy 378.539843 -97.606026)
			(xy 378.643557 -97.643069) (xy 378.744328 -97.6875) (xy 378.84163 -97.739087) (xy 378.934956 -97.797559)
			(xy 379.023819 -97.862614) (xy 379.107757 -97.933912) (xy 379.186332 -98.01108) (xy 379.259133 -98.093717)
			(xy 379.325781 -98.181391) (xy 379.38593 -98.273647) (xy 379.439264 -98.370002) (xy 379.485507 -98.469954)
			(xy 379.524417 -98.572982) (xy 379.555791 -98.67855) (xy 379.579466 -98.786106) (xy 379.595318 -98.89509)
			(xy 379.603265 -99.004934) (xy 379.603762 -99.06) (xy 396.111741 -99.06) (xy 396.115716 -98.949941)
			(xy 396.127624 -98.840455) (xy 396.1474 -98.732114) (xy 396.174943 -98.625483) (xy 396.210108 -98.521117)
			(xy 396.252712 -98.41956) (xy 396.302533 -98.321343) (xy 396.359312 -98.226976) (xy 396.422751 -98.136952)
			(xy 396.492522 -98.051741) (xy 396.568259 -97.971786) (xy 396.649568 -97.897505) (xy 396.736025 -97.829285)
			(xy 396.827179 -97.76748) (xy 396.922556 -97.712415) (xy 397.021657 -97.664375) (xy 397.123966 -97.623611)
			(xy 397.22895 -97.590336) (xy 397.336061 -97.564723) (xy 397.444741 -97.546906) (xy 397.554424 -97.536977)
			(xy 397.664537 -97.534989) (xy 397.774507 -97.540951) (xy 397.88376 -97.554833) (xy 397.991726 -97.576563)
			(xy 398.097843 -97.606026) (xy 398.201557 -97.643069) (xy 398.302328 -97.6875) (xy 398.39963 -97.739087)
			(xy 398.492956 -97.797559) (xy 398.581819 -97.862614) (xy 398.665757 -97.933912) (xy 398.744332 -98.01108)
			(xy 398.817133 -98.093717) (xy 398.883781 -98.181391) (xy 398.94393 -98.273647) (xy 398.997264 -98.370002)
			(xy 399.043507 -98.469954) (xy 399.082417 -98.572982) (xy 399.113791 -98.67855) (xy 399.137466 -98.786106)
			(xy 399.153318 -98.89509) (xy 399.161265 -99.004934) (xy 399.161762 -99.06) (xy 399.161265 -99.115066)
			(xy 399.153318 -99.22491) (xy 399.137466 -99.333894) (xy 399.113791 -99.44145) (xy 399.082417 -99.547018)
			(xy 399.043507 -99.650046) (xy 398.997264 -99.749998) (xy 398.94393 -99.846353) (xy 398.883781 -99.938609)
			(xy 398.817133 -100.026283) (xy 398.744332 -100.10892) (xy 398.665757 -100.186088) (xy 398.581819 -100.257386)
			(xy 398.492956 -100.322441) (xy 398.39963 -100.380913) (xy 398.302328 -100.4325) (xy 398.201557 -100.476931)
			(xy 398.097843 -100.513974) (xy 397.991726 -100.543437) (xy 397.88376 -100.565167) (xy 397.774507 -100.579049)
			(xy 397.664537 -100.585011) (xy 397.554424 -100.583023) (xy 397.444741 -100.573094) (xy 397.336061 -100.555277)
			(xy 397.22895 -100.529664) (xy 397.123966 -100.496389) (xy 397.021657 -100.455625) (xy 396.922556 -100.407585)
			(xy 396.827179 -100.35252) (xy 396.736025 -100.290715) (xy 396.649568 -100.222495) (xy 396.568259 -100.148214)
			(xy 396.492522 -100.068259) (xy 396.422751 -99.983048) (xy 396.359312 -99.893024) (xy 396.302533 -99.798657)
			(xy 396.252712 -99.70044) (xy 396.210108 -99.598883) (xy 396.174943 -99.494517) (xy 396.1474 -99.387886)
			(xy 396.127624 -99.279545) (xy 396.115716 -99.170059) (xy 396.111741 -99.06) (xy 379.603762 -99.06)
			(xy 379.603265 -99.115066) (xy 379.595318 -99.22491) (xy 379.579466 -99.333894) (xy 379.555791 -99.44145)
			(xy 379.524417 -99.547018) (xy 379.485507 -99.650046) (xy 379.439264 -99.749998) (xy 379.38593 -99.846353)
			(xy 379.325781 -99.938609) (xy 379.259133 -100.026283) (xy 379.186332 -100.10892) (xy 379.107757 -100.186088)
			(xy 379.023819 -100.257386) (xy 378.934956 -100.322441) (xy 378.84163 -100.380913) (xy 378.744328 -100.4325)
			(xy 378.643557 -100.476931) (xy 378.539843 -100.513974) (xy 378.433726 -100.543437) (xy 378.32576 -100.565167)
			(xy 378.216507 -100.579049) (xy 378.106537 -100.585011) (xy 377.996424 -100.583023) (xy 377.886741 -100.573094)
			(xy 377.778061 -100.555277) (xy 377.67095 -100.529664) (xy 377.565966 -100.496389) (xy 377.463657 -100.455625)
			(xy 377.364556 -100.407585) (xy 377.269179 -100.35252) (xy 377.178025 -100.290715) (xy 377.091568 -100.222495)
			(xy 377.010259 -100.148214) (xy 376.934522 -100.068259) (xy 376.864751 -99.983048) (xy 376.801312 -99.893024)
			(xy 376.744533 -99.798657) (xy 376.694712 -99.70044) (xy 376.652108 -99.598883) (xy 376.616943 -99.494517)
			(xy 376.5894 -99.387886) (xy 376.569624 -99.279545) (xy 376.557716 -99.170059) (xy 376.553741 -99.06)
			(xy 63.446152 -99.06) (xy 63.445655 -99.115066) (xy 63.437708 -99.22491) (xy 63.421856 -99.333894)
			(xy 63.398181 -99.44145) (xy 63.366807 -99.547018) (xy 63.327897 -99.650046) (xy 63.281654 -99.749998)
			(xy 63.22832 -99.846353) (xy 63.168171 -99.938609) (xy 63.101523 -100.026283) (xy 63.028722 -100.10892)
			(xy 62.950147 -100.186088) (xy 62.866209 -100.257386) (xy 62.777346 -100.322441) (xy 62.68402 -100.380913)
			(xy 62.586718 -100.4325) (xy 62.485947 -100.476931) (xy 62.382233 -100.513974) (xy 62.276116 -100.543437)
			(xy 62.16815 -100.565167) (xy 62.058897 -100.579049) (xy 61.948927 -100.585011) (xy 61.838814 -100.583023)
			(xy 61.729131 -100.573094) (xy 61.620451 -100.555277) (xy 61.51334 -100.529664) (xy 61.408356 -100.496389)
			(xy 61.306047 -100.455625) (xy 61.206946 -100.407585) (xy 61.111569 -100.35252) (xy 61.020415 -100.290715)
			(xy 60.933958 -100.222495) (xy 60.852649 -100.148214) (xy 60.776912 -100.068259) (xy 60.707141 -99.983048)
			(xy 60.643702 -99.893024) (xy 60.586923 -99.798657) (xy 60.537102 -99.70044) (xy 60.494498 -99.598883)
			(xy 60.459333 -99.494517) (xy 60.43179 -99.387886) (xy 60.412014 -99.279545) (xy 60.400106 -99.170059)
			(xy 60.396131 -99.06) (xy 43.888152 -99.06) (xy 43.887655 -99.115066) (xy 43.879708 -99.22491) (xy 43.863856 -99.333894)
			(xy 43.840181 -99.44145) (xy 43.808807 -99.547018) (xy 43.769897 -99.650046) (xy 43.723654 -99.749998)
			(xy 43.67032 -99.846353) (xy 43.610171 -99.938609) (xy 43.543523 -100.026283) (xy 43.470722 -100.10892)
			(xy 43.392147 -100.186088) (xy 43.308209 -100.257386) (xy 43.219346 -100.322441) (xy 43.12602 -100.380913)
			(xy 43.028718 -100.4325) (xy 42.927947 -100.476931) (xy 42.824233 -100.513974) (xy 42.718116 -100.543437)
			(xy 42.61015 -100.565167) (xy 42.500897 -100.579049) (xy 42.390927 -100.585011) (xy 42.280814 -100.583023)
			(xy 42.171131 -100.573094) (xy 42.062451 -100.555277) (xy 41.95534 -100.529664) (xy 41.850356 -100.496389)
			(xy 41.748047 -100.455625) (xy 41.648946 -100.407585) (xy 41.553569 -100.35252) (xy 41.462415 -100.290715)
			(xy 41.375958 -100.222495) (xy 41.294649 -100.148214) (xy 41.218912 -100.068259) (xy 41.149141 -99.983048)
			(xy 41.085702 -99.893024) (xy 41.028923 -99.798657) (xy 40.979102 -99.70044) (xy 40.936498 -99.598883)
			(xy 40.901333 -99.494517) (xy 40.87379 -99.387886) (xy 40.854014 -99.279545) (xy 40.842106 -99.170059)
			(xy 40.838131 -99.06) (xy 0.509016 -99.06) (xy 0.509016 -104.544876) (xy 12.484104 -104.544876) (xy 12.488134 -104.402541)
			(xy 12.500209 -104.260661) (xy 12.520292 -104.119693) (xy 12.548319 -103.980086) (xy 12.584199 -103.842288)
			(xy 12.627817 -103.706741) (xy 12.679034 -103.573879) (xy 12.737685 -103.444127) (xy 12.803583 -103.317901)
			(xy 12.876517 -103.195605) (xy 12.956254 -103.077632) (xy 13.042536 -102.964359) (xy 13.135089 -102.856148)
			(xy 13.233616 -102.753347) (xy 13.337801 -102.656285) (xy 13.44731 -102.565273) (xy 13.561793 -102.480601)
			(xy 13.680883 -102.402543) (xy 13.804198 -102.331347) (xy 13.931344 -102.267241) (xy 14.061913 -102.210432)
			(xy 14.195487 -102.1611) (xy 14.331638 -102.119404) (xy 14.469929 -102.085478) (xy 14.609919 -102.05943)
			(xy 14.751158 -102.041344) (xy 14.893194 -102.031277) (xy 15.035572 -102.029262) (xy 15.177836 -102.035305)
			(xy 15.31953 -102.049387) (xy 15.4602 -102.071463) (xy 15.599397 -102.101463) (xy 15.736673 -102.139289)
			(xy 15.871589 -102.184821) (xy 16.003713 -102.237912) (xy 16.132622 -102.298394) (xy 16.257903 -102.366072)
			(xy 16.379154 -102.440729) (xy 16.495987 -102.522127) (xy 16.608028 -102.610004) (xy 16.714918 -102.704079)
			(xy 16.816315 -102.804051) (xy 16.911893 -102.909599) (xy 17.001347 -103.020385) (xy 17.084389 -103.136054)
			(xy 17.160755 -103.256237) (xy 17.230199 -103.380547) (xy 17.292499 -103.508588) (xy 17.347455 -103.639947)
			(xy 17.394892 -103.774206) (xy 17.434656 -103.910933) (xy 17.466622 -104.049691) (xy 17.490687 -104.190035)
			(xy 17.506773 -104.331516) (xy 17.514828 -104.47368) (xy 17.515332 -104.544876) (xy 17.514828 -104.616072)
			(xy 17.506773 -104.758236) (xy 17.490687 -104.899717) (xy 17.466622 -105.040061) (xy 17.434656 -105.178819)
			(xy 17.394892 -105.315546) (xy 17.347455 -105.449805) (xy 17.292499 -105.581164) (xy 17.230199 -105.709205)
			(xy 17.160755 -105.833515) (xy 17.084389 -105.953698) (xy 17.001347 -106.069367) (xy 16.911893 -106.180153)
			(xy 16.816315 -106.285701) (xy 16.714918 -106.385673) (xy 16.608028 -106.479748) (xy 16.495987 -106.567625)
			(xy 16.379154 -106.649023) (xy 16.257903 -106.72368) (xy 16.132622 -106.791358) (xy 16.003713 -106.85184)
			(xy 15.871589 -106.904931) (xy 15.736673 -106.950463) (xy 15.599397 -106.988289) (xy 15.4602 -107.018289)
			(xy 15.31953 -107.040365) (xy 15.177836 -107.054447) (xy 15.035572 -107.06049) (xy 14.893194 -107.058475)
			(xy 14.751158 -107.048408) (xy 14.609919 -107.030322) (xy 14.469929 -107.004274) (xy 14.331638 -106.970348)
			(xy 14.195487 -106.928652) (xy 14.061913 -106.87932) (xy 13.931344 -106.822511) (xy 13.804198 -106.758405)
			(xy 13.680883 -106.687209) (xy 13.561793 -106.609151) (xy 13.44731 -106.524479) (xy 13.337801 -106.433467)
			(xy 13.233616 -106.336405) (xy 13.135089 -106.233604) (xy 13.042536 -106.125393) (xy 12.956254 -106.01212)
			(xy 12.876517 -105.894147) (xy 12.803583 -105.771851) (xy 12.737685 -105.645625) (xy 12.679034 -105.515873)
			(xy 12.627817 -105.383011) (xy 12.584199 -105.247464) (xy 12.548319 -105.109666) (xy 12.520292 -104.970059)
			(xy 12.500209 -104.829091) (xy 12.488134 -104.687211) (xy 12.484104 -104.544876) (xy 0.509016 -104.544876)
			(xy 0.509016 -111.879888) (xy 41.345622 -111.879888) (xy 41.349604 -111.789938) (xy 41.361521 -111.700691)
			(xy 41.381279 -111.612847) (xy 41.408723 -111.527093) (xy 41.443639 -111.4441) (xy 41.485753 -111.364518)
			(xy 41.534736 -111.288969) (xy 41.590204 -111.218045) (xy 41.651724 -111.1523) (xy 41.718813 -111.09225)
			(xy 41.790947 -111.038365) (xy 41.867561 -110.991065) (xy 41.948055 -110.950722) (xy 42.0318 -110.91765)
			(xy 42.118141 -110.89211) (xy 42.2064 -110.8743) (xy 42.295889 -110.86436) (xy 42.385905 -110.862369)
			(xy 42.475746 -110.86834) (xy 42.564707 -110.882229) (xy 42.652092 -110.903925) (xy 42.737218 -110.93326)
			(xy 42.819418 -110.970003) (xy 42.898049 -111.013867) (xy 42.972496 -111.064509) (xy 43.042176 -111.121533)
			(xy 43.106543 -111.184492) (xy 43.165094 -111.252893) (xy 43.217371 -111.326201) (xy 43.262964 -111.403843)
			(xy 43.301517 -111.48521) (xy 43.332728 -111.569666) (xy 43.356352 -111.65655) (xy 43.372205 -111.745182)
			(xy 43.380162 -111.834869) (xy 43.38066 -111.879888) (xy 60.903622 -111.879888) (xy 60.907604 -111.789938)
			(xy 60.919521 -111.700691) (xy 60.939279 -111.612847) (xy 60.966723 -111.527093) (xy 61.001639 -111.4441)
			(xy 61.043753 -111.364518) (xy 61.092736 -111.288969) (xy 61.148204 -111.218045) (xy 61.209724 -111.1523)
			(xy 61.276813 -111.09225) (xy 61.348947 -111.038365) (xy 61.425561 -110.991065) (xy 61.506055 -110.950722)
			(xy 61.5898 -110.91765) (xy 61.676141 -110.89211) (xy 61.7644 -110.8743) (xy 61.853889 -110.86436)
			(xy 61.943905 -110.862369) (xy 62.033746 -110.86834) (xy 62.122707 -110.882229) (xy 62.210092 -110.903925)
			(xy 62.295218 -110.93326) (xy 62.377418 -110.970003) (xy 62.456049 -111.013867) (xy 62.530496 -111.064509)
			(xy 62.600176 -111.121533) (xy 62.664543 -111.184492) (xy 62.723094 -111.252893) (xy 62.775371 -111.326201)
			(xy 62.820964 -111.403843) (xy 62.859517 -111.48521) (xy 62.890728 -111.569666) (xy 62.914352 -111.65655)
			(xy 62.930205 -111.745182) (xy 62.938162 -111.834869) (xy 62.93866 -111.879888) (xy 62.938162 -111.924907)
			(xy 62.930205 -112.014594) (xy 62.914352 -112.103226) (xy 62.890728 -112.19011) (xy 62.859517 -112.274566)
			(xy 62.820964 -112.355933) (xy 62.775371 -112.433575) (xy 62.723094 -112.506883) (xy 62.664543 -112.575284)
			(xy 62.600176 -112.638243) (xy 62.530496 -112.695267) (xy 62.456049 -112.745909) (xy 62.377418 -112.789773)
			(xy 62.295218 -112.826516) (xy 62.210092 -112.855851) (xy 62.122707 -112.877547) (xy 62.033746 -112.891436)
			(xy 61.943905 -112.897407) (xy 61.853889 -112.895416) (xy 61.7644 -112.885476) (xy 61.676141 -112.867666)
			(xy 61.5898 -112.842126) (xy 61.506055 -112.809054) (xy 61.425561 -112.768711) (xy 61.348947 -112.721411)
			(xy 61.276813 -112.667526) (xy 61.209724 -112.607476) (xy 61.148204 -112.541731) (xy 61.092736 -112.470807)
			(xy 61.043753 -112.395258) (xy 61.001639 -112.315676) (xy 60.966723 -112.232683) (xy 60.939279 -112.146929)
			(xy 60.919521 -112.059085) (xy 60.907604 -111.969838) (xy 60.903622 -111.879888) (xy 43.38066 -111.879888)
			(xy 43.380162 -111.924907) (xy 43.372205 -112.014594) (xy 43.356352 -112.103226) (xy 43.332728 -112.19011)
			(xy 43.301517 -112.274566) (xy 43.262964 -112.355933) (xy 43.217371 -112.433575) (xy 43.165094 -112.506883)
			(xy 43.106543 -112.575284) (xy 43.042176 -112.638243) (xy 42.972496 -112.695267) (xy 42.898049 -112.745909)
			(xy 42.819418 -112.789773) (xy 42.737218 -112.826516) (xy 42.652092 -112.855851) (xy 42.564707 -112.877547)
			(xy 42.475746 -112.891436) (xy 42.385905 -112.897407) (xy 42.295889 -112.895416) (xy 42.2064 -112.885476)
			(xy 42.118141 -112.867666) (xy 42.0318 -112.842126) (xy 41.948055 -112.809054) (xy 41.867561 -112.768711)
			(xy 41.790947 -112.721411) (xy 41.718813 -112.667526) (xy 41.651724 -112.607476) (xy 41.590204 -112.541731)
			(xy 41.534736 -112.470807) (xy 41.485753 -112.395258) (xy 41.443639 -112.315676) (xy 41.408723 -112.232683)
			(xy 41.381279 -112.146929) (xy 41.361521 -112.059085) (xy 41.349604 -111.969838) (xy 41.345622 -111.879888)
			(xy 0.509016 -111.879888) (xy 0.509016 -119.38) (xy 40.838131 -119.38) (xy 40.842106 -119.269941)
			(xy 40.854014 -119.160455) (xy 40.87379 -119.052114) (xy 40.901333 -118.945483) (xy 40.936498 -118.841117)
			(xy 40.979102 -118.73956) (xy 41.028923 -118.641343) (xy 41.085702 -118.546976) (xy 41.149141 -118.456952)
			(xy 41.218912 -118.371741) (xy 41.294649 -118.291786) (xy 41.375958 -118.217505) (xy 41.462415 -118.149285)
			(xy 41.553569 -118.08748) (xy 41.648946 -118.032415) (xy 41.748047 -117.984375) (xy 41.850356 -117.943611)
			(xy 41.95534 -117.910336) (xy 42.062451 -117.884723) (xy 42.171131 -117.866906) (xy 42.280814 -117.856977)
			(xy 42.390927 -117.854989) (xy 42.500897 -117.860951) (xy 42.61015 -117.874833) (xy 42.718116 -117.896563)
			(xy 42.824233 -117.926026) (xy 42.927947 -117.963069) (xy 43.028718 -118.0075) (xy 43.12602 -118.059087)
			(xy 43.219346 -118.117559) (xy 43.308209 -118.182614) (xy 43.392147 -118.253912) (xy 43.470722 -118.33108)
			(xy 43.543523 -118.413717) (xy 43.610171 -118.501391) (xy 43.67032 -118.593647) (xy 43.723654 -118.690002)
			(xy 43.769897 -118.789954) (xy 43.808807 -118.892982) (xy 43.840181 -118.99855) (xy 43.863856 -119.106106)
			(xy 43.879708 -119.21509) (xy 43.887655 -119.324934) (xy 43.888152 -119.38) (xy 60.396131 -119.38)
			(xy 60.400106 -119.269941) (xy 60.412014 -119.160455) (xy 60.43179 -119.052114) (xy 60.459333 -118.945483)
			(xy 60.494498 -118.841117) (xy 60.537102 -118.73956) (xy 60.586923 -118.641343) (xy 60.643702 -118.546976)
			(xy 60.707141 -118.456952) (xy 60.776912 -118.371741) (xy 60.852649 -118.291786) (xy 60.933958 -118.217505)
			(xy 61.020415 -118.149285) (xy 61.111569 -118.08748) (xy 61.206946 -118.032415) (xy 61.306047 -117.984375)
			(xy 61.408356 -117.943611) (xy 61.51334 -117.910336) (xy 61.620451 -117.884723) (xy 61.729131 -117.866906)
			(xy 61.838814 -117.856977) (xy 61.948927 -117.854989) (xy 62.058897 -117.860951) (xy 62.16815 -117.874833)
			(xy 62.276116 -117.896563) (xy 62.382233 -117.926026) (xy 62.485947 -117.963069) (xy 62.586718 -118.0075)
			(xy 62.68402 -118.059087) (xy 62.777346 -118.117559) (xy 62.866209 -118.182614) (xy 62.950147 -118.253912)
			(xy 63.028722 -118.33108) (xy 63.101523 -118.413717) (xy 63.168171 -118.501391) (xy 63.22832 -118.593647)
			(xy 63.281654 -118.690002) (xy 63.327897 -118.789954) (xy 63.366807 -118.892982) (xy 63.398181 -118.99855)
			(xy 63.421856 -119.106106) (xy 63.437708 -119.21509) (xy 63.445655 -119.324934) (xy 63.446152 -119.38)
			(xy 63.445655 -119.435066) (xy 63.437708 -119.54491) (xy 63.421856 -119.653894) (xy 63.398181 -119.76145)
			(xy 63.366807 -119.867018) (xy 63.327897 -119.970046) (xy 63.281654 -120.069998) (xy 63.22832 -120.166353)
			(xy 63.168171 -120.258609) (xy 63.101523 -120.346283) (xy 63.028722 -120.42892) (xy 62.950147 -120.506088)
			(xy 62.866209 -120.577386) (xy 62.777346 -120.642441) (xy 62.68402 -120.700913) (xy 62.586718 -120.7525)
			(xy 62.485947 -120.796931) (xy 62.382233 -120.833974) (xy 62.276116 -120.863437) (xy 62.16815 -120.885167)
			(xy 62.058897 -120.899049) (xy 61.948927 -120.905011) (xy 61.838814 -120.903023) (xy 61.729131 -120.893094)
			(xy 61.620451 -120.875277) (xy 61.51334 -120.849664) (xy 61.408356 -120.816389) (xy 61.306047 -120.775625)
			(xy 61.206946 -120.727585) (xy 61.111569 -120.67252) (xy 61.020415 -120.610715) (xy 60.933958 -120.542495)
			(xy 60.852649 -120.468214) (xy 60.776912 -120.388259) (xy 60.707141 -120.303048) (xy 60.643702 -120.213024)
			(xy 60.586923 -120.118657) (xy 60.537102 -120.02044) (xy 60.494498 -119.918883) (xy 60.459333 -119.814517)
			(xy 60.43179 -119.707886) (xy 60.412014 -119.599545) (xy 60.400106 -119.490059) (xy 60.396131 -119.38)
			(xy 43.888152 -119.38) (xy 43.887655 -119.435066) (xy 43.879708 -119.54491) (xy 43.863856 -119.653894)
			(xy 43.840181 -119.76145) (xy 43.808807 -119.867018) (xy 43.769897 -119.970046) (xy 43.723654 -120.069998)
			(xy 43.67032 -120.166353) (xy 43.610171 -120.258609) (xy 43.543523 -120.346283) (xy 43.470722 -120.42892)
			(xy 43.392147 -120.506088) (xy 43.308209 -120.577386) (xy 43.219346 -120.642441) (xy 43.12602 -120.700913)
			(xy 43.028718 -120.7525) (xy 42.927947 -120.796931) (xy 42.824233 -120.833974) (xy 42.718116 -120.863437)
			(xy 42.61015 -120.885167) (xy 42.500897 -120.899049) (xy 42.390927 -120.905011) (xy 42.280814 -120.903023)
			(xy 42.171131 -120.893094) (xy 42.062451 -120.875277) (xy 41.95534 -120.849664) (xy 41.850356 -120.816389)
			(xy 41.748047 -120.775625) (xy 41.648946 -120.727585) (xy 41.553569 -120.67252) (xy 41.462415 -120.610715)
			(xy 41.375958 -120.542495) (xy 41.294649 -120.468214) (xy 41.218912 -120.388259) (xy 41.149141 -120.303048)
			(xy 41.085702 -120.213024) (xy 41.028923 -120.118657) (xy 40.979102 -120.02044) (xy 40.936498 -119.918883)
			(xy 40.901333 -119.814517) (xy 40.87379 -119.707886) (xy 40.854014 -119.599545) (xy 40.842106 -119.490059)
			(xy 40.838131 -119.38) (xy 0.509016 -119.38) (xy 0.509016 -132.199888) (xy 41.345622 -132.199888)
			(xy 41.349604 -132.109938) (xy 41.361521 -132.020691) (xy 41.381279 -131.932847) (xy 41.408723 -131.847093)
			(xy 41.443639 -131.7641) (xy 41.485753 -131.684518) (xy 41.534736 -131.608969) (xy 41.590204 -131.538045)
			(xy 41.651724 -131.4723) (xy 41.718813 -131.41225) (xy 41.790947 -131.358365) (xy 41.867561 -131.311065)
			(xy 41.948055 -131.270722) (xy 42.0318 -131.23765) (xy 42.118141 -131.21211) (xy 42.2064 -131.1943)
			(xy 42.295889 -131.18436) (xy 42.385905 -131.182369) (xy 42.475746 -131.18834) (xy 42.564707 -131.202229)
			(xy 42.652092 -131.223925) (xy 42.737218 -131.25326) (xy 42.819418 -131.290003) (xy 42.898049 -131.333867)
			(xy 42.972496 -131.384509) (xy 43.042176 -131.441533) (xy 43.106543 -131.504492) (xy 43.165094 -131.572893)
			(xy 43.217371 -131.646201) (xy 43.262964 -131.723843) (xy 43.301517 -131.80521) (xy 43.332728 -131.889666)
			(xy 43.356352 -131.97655) (xy 43.372205 -132.065182) (xy 43.380162 -132.154869) (xy 43.38066 -132.199888)
			(xy 60.903622 -132.199888) (xy 60.907604 -132.109938) (xy 60.919521 -132.020691) (xy 60.939279 -131.932847)
			(xy 60.966723 -131.847093) (xy 61.001639 -131.7641) (xy 61.043753 -131.684518) (xy 61.092736 -131.608969)
			(xy 61.148204 -131.538045) (xy 61.209724 -131.4723) (xy 61.276813 -131.41225) (xy 61.348947 -131.358365)
			(xy 61.425561 -131.311065) (xy 61.506055 -131.270722) (xy 61.5898 -131.23765) (xy 61.676141 -131.21211)
			(xy 61.7644 -131.1943) (xy 61.853889 -131.18436) (xy 61.943905 -131.182369) (xy 62.033746 -131.18834)
			(xy 62.122707 -131.202229) (xy 62.210092 -131.223925) (xy 62.295218 -131.25326) (xy 62.377418 -131.290003)
			(xy 62.456049 -131.333867) (xy 62.530496 -131.384509) (xy 62.600176 -131.441533) (xy 62.664543 -131.504492)
			(xy 62.723094 -131.572893) (xy 62.775371 -131.646201) (xy 62.820964 -131.723843) (xy 62.859517 -131.80521)
			(xy 62.890728 -131.889666) (xy 62.914352 -131.97655) (xy 62.930205 -132.065182) (xy 62.938162 -132.154869)
			(xy 62.93866 -132.199888) (xy 62.938162 -132.244907) (xy 62.930205 -132.334594) (xy 62.914352 -132.423226)
			(xy 62.890728 -132.51011) (xy 62.859517 -132.594566) (xy 62.820964 -132.675933) (xy 62.775371 -132.753575)
			(xy 62.723094 -132.826883) (xy 62.664543 -132.895284) (xy 62.600176 -132.958243) (xy 62.530496 -133.015267)
			(xy 62.456049 -133.065909) (xy 62.377418 -133.109773) (xy 62.295218 -133.146516) (xy 62.210092 -133.175851)
			(xy 62.122707 -133.197547) (xy 62.033746 -133.211436) (xy 61.943905 -133.217407) (xy 61.853889 -133.215416)
			(xy 61.7644 -133.205476) (xy 61.676141 -133.187666) (xy 61.5898 -133.162126) (xy 61.506055 -133.129054)
			(xy 61.425561 -133.088711) (xy 61.348947 -133.041411) (xy 61.276813 -132.987526) (xy 61.209724 -132.927476)
			(xy 61.148204 -132.861731) (xy 61.092736 -132.790807) (xy 61.043753 -132.715258) (xy 61.001639 -132.635676)
			(xy 60.966723 -132.552683) (xy 60.939279 -132.466929) (xy 60.919521 -132.379085) (xy 60.907604 -132.289838)
			(xy 60.903622 -132.199888) (xy 43.38066 -132.199888) (xy 43.380162 -132.244907) (xy 43.372205 -132.334594)
			(xy 43.356352 -132.423226) (xy 43.332728 -132.51011) (xy 43.301517 -132.594566) (xy 43.262964 -132.675933)
			(xy 43.217371 -132.753575) (xy 43.165094 -132.826883) (xy 43.106543 -132.895284) (xy 43.042176 -132.958243)
			(xy 42.972496 -133.015267) (xy 42.898049 -133.065909) (xy 42.819418 -133.109773) (xy 42.737218 -133.146516)
			(xy 42.652092 -133.175851) (xy 42.564707 -133.197547) (xy 42.475746 -133.211436) (xy 42.385905 -133.217407)
			(xy 42.295889 -133.215416) (xy 42.2064 -133.205476) (xy 42.118141 -133.187666) (xy 42.0318 -133.162126)
			(xy 41.948055 -133.129054) (xy 41.867561 -133.088711) (xy 41.790947 -133.041411) (xy 41.718813 -132.987526)
			(xy 41.651724 -132.927476) (xy 41.590204 -132.861731) (xy 41.534736 -132.790807) (xy 41.485753 -132.715258)
			(xy 41.443639 -132.635676) (xy 41.408723 -132.552683) (xy 41.381279 -132.466929) (xy 41.361521 -132.379085)
			(xy 41.349604 -132.289838) (xy 41.345622 -132.199888) (xy 0.509016 -132.199888) (xy 0.509016 -139.7)
			(xy 40.838131 -139.7) (xy 40.842106 -139.589941) (xy 40.854014 -139.480455) (xy 40.87379 -139.372114)
			(xy 40.901333 -139.265483) (xy 40.936498 -139.161117) (xy 40.979102 -139.05956) (xy 41.028923 -138.961343)
			(xy 41.085702 -138.866976) (xy 41.149141 -138.776952) (xy 41.218912 -138.691741) (xy 41.294649 -138.611786)
			(xy 41.375958 -138.537505) (xy 41.462415 -138.469285) (xy 41.553569 -138.40748) (xy 41.648946 -138.352415)
			(xy 41.748047 -138.304375) (xy 41.850356 -138.263611) (xy 41.95534 -138.230336) (xy 42.062451 -138.204723)
			(xy 42.171131 -138.186906) (xy 42.280814 -138.176977) (xy 42.390927 -138.174989) (xy 42.500897 -138.180951)
			(xy 42.61015 -138.194833) (xy 42.718116 -138.216563) (xy 42.824233 -138.246026) (xy 42.927947 -138.283069)
			(xy 43.028718 -138.3275) (xy 43.12602 -138.379087) (xy 43.219346 -138.437559) (xy 43.308209 -138.502614)
			(xy 43.392147 -138.573912) (xy 43.470722 -138.65108) (xy 43.543523 -138.733717) (xy 43.610171 -138.821391)
			(xy 43.67032 -138.913647) (xy 43.723654 -139.010002) (xy 43.769897 -139.109954) (xy 43.808807 -139.212982)
			(xy 43.840181 -139.31855) (xy 43.863856 -139.426106) (xy 43.879708 -139.53509) (xy 43.887655 -139.644934)
			(xy 43.888152 -139.7) (xy 60.396131 -139.7) (xy 60.400106 -139.589941) (xy 60.412014 -139.480455)
			(xy 60.43179 -139.372114) (xy 60.459333 -139.265483) (xy 60.494498 -139.161117) (xy 60.537102 -139.05956)
			(xy 60.586923 -138.961343) (xy 60.643702 -138.866976) (xy 60.707141 -138.776952) (xy 60.776912 -138.691741)
			(xy 60.852649 -138.611786) (xy 60.933958 -138.537505) (xy 61.020415 -138.469285) (xy 61.111569 -138.40748)
			(xy 61.206946 -138.352415) (xy 61.306047 -138.304375) (xy 61.408356 -138.263611) (xy 61.51334 -138.230336)
			(xy 61.620451 -138.204723) (xy 61.729131 -138.186906) (xy 61.838814 -138.176977) (xy 61.948927 -138.174989)
			(xy 62.058897 -138.180951) (xy 62.16815 -138.194833) (xy 62.276116 -138.216563) (xy 62.382233 -138.246026)
			(xy 62.485947 -138.283069) (xy 62.586718 -138.3275) (xy 62.68402 -138.379087) (xy 62.777346 -138.437559)
			(xy 62.866209 -138.502614) (xy 62.950147 -138.573912) (xy 63.028722 -138.65108) (xy 63.101523 -138.733717)
			(xy 63.168171 -138.821391) (xy 63.22832 -138.913647) (xy 63.281654 -139.010002) (xy 63.327897 -139.109954)
			(xy 63.366807 -139.212982) (xy 63.398181 -139.31855) (xy 63.421856 -139.426106) (xy 63.437708 -139.53509)
			(xy 63.445655 -139.644934) (xy 63.446152 -139.7) (xy 63.445655 -139.755066) (xy 63.437708 -139.86491)
			(xy 63.421856 -139.973894) (xy 63.398181 -140.08145) (xy 63.366807 -140.187018) (xy 63.327897 -140.290046)
			(xy 63.281654 -140.389998) (xy 63.22832 -140.486353) (xy 63.168171 -140.578609) (xy 63.101523 -140.666283)
			(xy 63.028722 -140.74892) (xy 62.950147 -140.826088) (xy 62.866209 -140.897386) (xy 62.777346 -140.962441)
			(xy 62.68402 -141.020913) (xy 62.586718 -141.0725) (xy 62.485947 -141.116931) (xy 62.382233 -141.153974)
			(xy 62.276116 -141.183437) (xy 62.16815 -141.205167) (xy 62.058897 -141.219049) (xy 61.948927 -141.225011)
			(xy 61.838814 -141.223023) (xy 61.729131 -141.213094) (xy 61.620451 -141.195277) (xy 61.51334 -141.169664)
			(xy 61.408356 -141.136389) (xy 61.306047 -141.095625) (xy 61.206946 -141.047585) (xy 61.111569 -140.99252)
			(xy 61.020415 -140.930715) (xy 60.933958 -140.862495) (xy 60.852649 -140.788214) (xy 60.776912 -140.708259)
			(xy 60.707141 -140.623048) (xy 60.643702 -140.533024) (xy 60.586923 -140.438657) (xy 60.537102 -140.34044)
			(xy 60.494498 -140.238883) (xy 60.459333 -140.134517) (xy 60.43179 -140.027886) (xy 60.412014 -139.919545)
			(xy 60.400106 -139.810059) (xy 60.396131 -139.7) (xy 43.888152 -139.7) (xy 43.887655 -139.755066)
			(xy 43.879708 -139.86491) (xy 43.863856 -139.973894) (xy 43.840181 -140.08145) (xy 43.808807 -140.187018)
			(xy 43.769897 -140.290046) (xy 43.723654 -140.389998) (xy 43.67032 -140.486353) (xy 43.610171 -140.578609)
			(xy 43.543523 -140.666283) (xy 43.470722 -140.74892) (xy 43.392147 -140.826088) (xy 43.308209 -140.897386)
			(xy 43.219346 -140.962441) (xy 43.12602 -141.020913) (xy 43.028718 -141.0725) (xy 42.927947 -141.116931)
			(xy 42.824233 -141.153974) (xy 42.718116 -141.183437) (xy 42.61015 -141.205167) (xy 42.500897 -141.219049)
			(xy 42.390927 -141.225011) (xy 42.280814 -141.223023) (xy 42.171131 -141.213094) (xy 42.062451 -141.195277)
			(xy 41.95534 -141.169664) (xy 41.850356 -141.136389) (xy 41.748047 -141.095625) (xy 41.648946 -141.047585)
			(xy 41.553569 -140.99252) (xy 41.462415 -140.930715) (xy 41.375958 -140.862495) (xy 41.294649 -140.788214)
			(xy 41.218912 -140.708259) (xy 41.149141 -140.623048) (xy 41.085702 -140.533024) (xy 41.028923 -140.438657)
			(xy 40.979102 -140.34044) (xy 40.936498 -140.238883) (xy 40.901333 -140.134517) (xy 40.87379 -140.027886)
			(xy 40.854014 -139.919545) (xy 40.842106 -139.810059) (xy 40.838131 -139.7) (xy 0.509016 -139.7)
			(xy 0.509016 -153.299922) (xy 0.509522 -153.395255) (xy 0.517614 -153.58575) (xy 0.533784 -153.77573)
			(xy 0.558002 -153.964852) (xy 0.590225 -154.152777) (xy 0.630395 -154.339164) (xy 0.678438 -154.523678)
			(xy 0.73427 -154.705987) (xy 0.797789 -154.885763) (xy 0.86888 -155.06268) (xy 0.947416 -155.236421)
			(xy 1.033255 -155.406672) (xy 1.126242 -155.573127) (xy 1.22621 -155.735485) (xy 1.332979 -155.893455)
			(xy 1.446356 -156.04675) (xy 1.566136 -156.195096) (xy 1.692105 -156.338224) (xy 1.824035 -156.475877)
			(xy 1.961688 -156.607806) (xy 2.104816 -156.733775) (xy 2.253162 -156.853556) (xy 2.406457 -156.966932)
			(xy 2.564426 -157.073701) (xy 2.726785 -157.173669) (xy 2.893239 -157.266656) (xy 3.063491 -157.352495)
			(xy 3.237232 -157.431031) (xy 3.414149 -157.502122) (xy 3.593924 -157.565641) (xy 3.776234 -157.621472)
			(xy 3.960748 -157.669516) (xy 4.147135 -157.709685) (xy 4.335059 -157.741908) (xy 4.524182 -157.766126)
			(xy 4.714162 -157.782296) (xy 4.904657 -157.790388) (xy 4.99999 -157.790896) (xy 25.999948 -157.790896)
			(xy 26.105482 -157.791395) (xy 26.316396 -157.79948) (xy 26.526845 -157.815637) (xy 26.73652 -157.839843)
			(xy 26.945115 -157.872062) (xy 27.152323 -157.912248) (xy 27.357839 -157.96034) (xy 27.561362 -158.016269)
			(xy 27.762594 -158.079953) (xy 27.961239 -158.151298) (xy 28.157005 -158.230198) (xy 28.349606 -158.31654)
			(xy 28.538758 -158.410195) (xy 28.724184 -158.511027) (xy 28.905612 -158.618886) (xy 29.082776 -158.733616)
			(xy 29.255415 -158.855048) (xy 29.423276 -158.983003) (xy 29.586113 -159.117293) (xy 29.743686 -159.257723)
			(xy 29.895766 -159.404084) (xy 30.042127 -159.556164) (xy 30.182557 -159.713737) (xy 30.316847 -159.876574)
			(xy 30.444802 -160.044435) (xy 30.566234 -160.217074) (xy 30.680964 -160.394238) (xy 30.788823 -160.575666)
			(xy 30.889655 -160.761092) (xy 30.98331 -160.950244) (xy 31.069652 -161.142845) (xy 31.148552 -161.338611)
			(xy 31.219897 -161.537256) (xy 31.283581 -161.738488) (xy 31.33951 -161.942011) (xy 31.387602 -162.147527)
			(xy 31.427788 -162.354735) (xy 31.460007 -162.56333) (xy 31.484213 -162.773005) (xy 31.50037 -162.983454)
			(xy 31.508455 -163.194368) (xy 31.508954 -163.299902) (xy 31.508954 -166.649908) (xy 31.50946 -166.745241)
			(xy 31.517552 -166.935736) (xy 31.533721 -167.125716) (xy 31.557939 -167.314839) (xy 31.590162 -167.502763)
			(xy 31.630332 -167.689151) (xy 31.678375 -167.873665) (xy 31.734207 -168.055975) (xy 31.797726 -168.23575)
			(xy 31.868817 -168.412668) (xy 31.947353 -168.586409) (xy 32.033192 -168.75666) (xy 32.074156 -168.82999)
			(xy 33.661096 -168.82999) (xy 33.661535 -168.782327) (xy 33.669022 -168.687296) (xy 33.683942 -168.593144)
			(xy 33.706203 -168.500454) (xy 33.735667 -168.409796) (xy 33.772152 -168.321729) (xy 33.815435 -168.236795)
			(xy 33.865248 -168.15552) (xy 33.921283 -168.078402) (xy 33.983196 -168.005919) (xy 34.050605 -167.938517)
			(xy 34.086546 -167.907208) (xy 34.094571 -167.899638) (xy 34.103786 -167.879619) (xy 34.104326 -167.8686)
			(xy 34.104326 -167.791384) (xy 34.103789 -167.780365) (xy 34.094568 -167.760349) (xy 34.086546 -167.752776)
			(xy 34.050612 -167.721463) (xy 33.983218 -167.654051) (xy 33.921318 -167.581561) (xy 33.865293 -167.504441)
			(xy 33.815489 -167.423164) (xy 33.772212 -167.338232) (xy 33.735729 -167.250168) (xy 33.706265 -167.159514)
			(xy 33.684 -167.066828) (xy 33.669073 -166.972682) (xy 33.661575 -166.877655) (xy 33.661096 -166.829994)
			(xy 33.661537 -166.782331) (xy 33.669025 -166.6873) (xy 33.683944 -166.593149) (xy 33.706205 -166.500458)
			(xy 33.735668 -166.4098) (xy 33.772154 -166.321733) (xy 33.815436 -166.2368) (xy 33.865249 -166.155524)
			(xy 33.921284 -166.078407) (xy 33.983197 -166.005923) (xy 34.050605 -165.938521) (xy 34.086546 -165.907212)
			(xy 34.094569 -165.89964) (xy 34.103786 -165.879623) (xy 34.104326 -165.868604) (xy 34.104326 -165.791388)
			(xy 34.103786 -165.78037) (xy 34.094567 -165.760354) (xy 34.086546 -165.75278) (xy 34.050614 -165.721464)
			(xy 33.98322 -165.654053) (xy 33.92132 -165.581563) (xy 33.865295 -165.504443) (xy 33.815491 -165.423167)
			(xy 33.772214 -165.338235) (xy 33.735731 -165.250171) (xy 33.706266 -165.159517) (xy 33.684001 -165.066832)
			(xy 33.669073 -164.972686) (xy 33.661575 -164.877659) (xy 33.661096 -164.829998) (xy 33.66154 -164.782335)
			(xy 33.669027 -164.687304) (xy 33.683947 -164.593153) (xy 33.706207 -164.500463) (xy 33.73567 -164.409804)
			(xy 33.772155 -164.321737) (xy 33.815437 -164.236804) (xy 33.865249 -164.155528) (xy 33.921284 -164.078411)
			(xy 33.983197 -164.005927) (xy 34.050606 -163.938525) (xy 34.086546 -163.907216) (xy 34.094567 -163.899643)
			(xy 34.103785 -163.879626) (xy 34.104326 -163.868608) (xy 34.104326 -163.791392) (xy 34.103784 -163.780374)
			(xy 34.094567 -163.760358) (xy 34.086546 -163.752784) (xy 34.050616 -163.721466) (xy 33.983221 -163.654055)
			(xy 33.921321 -163.581566) (xy 33.865297 -163.504446) (xy 33.815492 -163.42317) (xy 33.772215 -163.338238)
			(xy 33.735732 -163.250174) (xy 33.706267 -163.15952) (xy 33.684002 -163.066835) (xy 33.669074 -162.972689)
			(xy 33.661575 -162.877663) (xy 33.661096 -162.830002) (xy 33.661543 -162.782339) (xy 33.66903 -162.687308)
			(xy 33.683949 -162.593157) (xy 33.706209 -162.500467) (xy 33.735672 -162.409809) (xy 33.772157 -162.321741)
			(xy 33.815438 -162.236808) (xy 33.86525 -162.155532) (xy 33.921285 -162.078415) (xy 33.983197 -162.005932)
			(xy 34.050606 -161.938529) (xy 34.086546 -161.90722) (xy 34.094565 -161.899645) (xy 34.103784 -161.87963)
			(xy 34.104326 -161.868612) (xy 34.104326 -161.791396) (xy 34.103782 -161.780378) (xy 34.094566 -161.760362)
			(xy 34.086546 -161.752788) (xy 34.050618 -161.721468) (xy 33.983223 -161.654057) (xy 33.921323 -161.581568)
			(xy 33.865298 -161.504448) (xy 33.815494 -161.423172) (xy 33.772217 -161.338241) (xy 33.735733 -161.250177)
			(xy 33.706268 -161.159524) (xy 33.684002 -161.066839) (xy 33.669074 -160.972693) (xy 33.661575 -160.877667)
			(xy 33.661096 -160.830006) (xy 33.661546 -160.782343) (xy 33.669032 -160.687312) (xy 33.683951 -160.593161)
			(xy 33.70621 -160.500471) (xy 33.735673 -160.409813) (xy 33.772158 -160.321746) (xy 33.815439 -160.236812)
			(xy 33.865251 -160.155537) (xy 33.921286 -160.078419) (xy 33.983198 -160.005936) (xy 34.050606 -159.938533)
			(xy 34.086546 -159.907224) (xy 34.094563 -159.899647) (xy 34.103783 -159.879633) (xy 34.104326 -159.868616)
			(xy 34.104326 -159.7914) (xy 34.10378 -159.780382) (xy 34.094565 -159.760366) (xy 34.086546 -159.752792)
			(xy 34.05062 -159.72147) (xy 33.983225 -159.654059) (xy 33.921325 -159.58157) (xy 33.8653 -159.504451)
			(xy 33.815495 -159.423175) (xy 33.772218 -159.338244) (xy 33.735734 -159.250181) (xy 33.706269 -159.159527)
			(xy 33.684003 -159.066842) (xy 33.669075 -158.972697) (xy 33.661575 -158.877671) (xy 33.661096 -158.83001)
			(xy 33.661549 -158.782347) (xy 33.669035 -158.687316) (xy 33.683953 -158.593165) (xy 33.706212 -158.500475)
			(xy 33.735675 -158.409817) (xy 33.772159 -158.32175) (xy 33.815441 -158.236817) (xy 33.865252 -158.155541)
			(xy 33.921286 -158.078423) (xy 33.983198 -158.00594) (xy 34.050606 -157.938537) (xy 34.086546 -157.907228)
			(xy 34.094562 -157.89965) (xy 34.103782 -157.879637) (xy 34.104326 -157.86862) (xy 34.104326 -157.791404)
			(xy 34.103778 -157.780387) (xy 34.094565 -157.76037) (xy 34.086546 -157.752796) (xy 34.050621 -157.721472)
			(xy 33.983227 -157.654061) (xy 33.921327 -157.581573) (xy 33.865302 -157.504453) (xy 33.815497 -157.423178)
			(xy 33.772219 -157.338247) (xy 33.735735 -157.250184) (xy 33.70627 -157.159531) (xy 33.684004 -157.066846)
			(xy 33.669075 -156.972701) (xy 33.661575 -156.877675) (xy 33.661096 -156.830014) (xy 33.661552 -156.782351)
			(xy 33.669037 -156.68732) (xy 33.683956 -156.59317) (xy 33.706214 -156.50048) (xy 33.735677 -156.409821)
			(xy 33.772161 -156.321754) (xy 33.815442 -156.236821) (xy 33.865253 -156.155545) (xy 33.921287 -156.078428)
			(xy 33.983198 -156.005944) (xy 34.050606 -155.938541) (xy 34.086546 -155.907232) (xy 34.09456 -155.899652)
			(xy 34.103782 -155.879641) (xy 34.104326 -155.868624) (xy 34.104326 -155.791408) (xy 34.103776 -155.780391)
			(xy 34.094564 -155.760375) (xy 34.086546 -155.7528) (xy 34.050623 -155.721473) (xy 33.983229 -155.654063)
			(xy 33.921329 -155.581575) (xy 33.865303 -155.504456) (xy 33.815499 -155.423181) (xy 33.772221 -155.33825)
			(xy 33.735736 -155.250187) (xy 33.706271 -155.159534) (xy 33.684005 -155.06685) (xy 33.669076 -154.972705)
			(xy 33.661575 -154.877679) (xy 33.661096 -154.830018) (xy 33.661555 -154.782355) (xy 33.66904 -154.687325)
			(xy 33.683958 -154.593174) (xy 33.706216 -154.500484) (xy 33.735678 -154.409826) (xy 33.772162 -154.321759)
			(xy 33.815443 -154.236825) (xy 33.865254 -154.155549) (xy 33.921287 -154.078432) (xy 33.983199 -154.005948)
			(xy 34.050606 -153.938545) (xy 34.086546 -153.907236) (xy 34.094558 -153.899654) (xy 34.103781 -153.879644)
			(xy 34.104326 -153.868628) (xy 34.104326 -153.791412) (xy 34.103773 -153.780395) (xy 34.094564 -153.760379)
			(xy 34.086546 -153.752804) (xy 34.050625 -153.721475) (xy 33.983231 -153.654065) (xy 33.92133 -153.581577)
			(xy 33.865305 -153.504458) (xy 33.8155 -153.423183) (xy 33.772222 -153.338253) (xy 33.735738 -153.25019)
			(xy 33.706272 -153.159538) (xy 33.684005 -153.066853) (xy 33.669076 -152.972708) (xy 33.661576 -152.877683)
			(xy 33.661096 -152.830022) (xy 33.661673 -152.779839) (xy 33.66996 -152.679815) (xy 33.686478 -152.580818)
			(xy 33.711114 -152.483522) (xy 33.743701 -152.388593) (xy 33.784016 -152.29668) (xy 33.831783 -152.208409)
			(xy 33.886676 -152.124385) (xy 33.94832 -152.04518) (xy 34.016294 -151.971337) (xy 34.090135 -151.903359)
			(xy 34.169336 -151.841711) (xy 34.253358 -151.786813) (xy 34.341626 -151.739042) (xy 34.433537 -151.698723)
			(xy 34.528465 -151.666131) (xy 34.625759 -151.64149) (xy 34.724756 -151.624967) (xy 34.824779 -151.616676)
			(xy 34.874962 -151.616156) (xy 34.922624 -151.616643) (xy 35.017654 -151.624127) (xy 35.111803 -151.639042)
			(xy 35.204493 -151.661299) (xy 35.29515 -151.690758) (xy 35.383217 -151.727239) (xy 35.468151 -151.770517)
			(xy 35.549427 -151.820325) (xy 35.626545 -151.876355) (xy 35.69903 -151.938264) (xy 35.766434 -152.005668)
			(xy 35.797744 -152.041606) (xy 35.80534 -152.049603) (xy 35.825339 -152.058836) (xy 35.836352 -152.059386)
			(xy 35.913568 -152.059386) (xy 35.924585 -152.058835) (xy 35.944602 -152.049625) (xy 35.952176 -152.041606)
			(xy 35.983506 -152.005687) (xy 36.050917 -151.938293) (xy 36.123405 -151.876393) (xy 36.200524 -151.820369)
			(xy 36.281799 -151.770564) (xy 36.366729 -151.727286) (xy 36.454792 -151.690802) (xy 36.545444 -151.661335)
			(xy 36.638128 -151.639068) (xy 36.732272 -151.624138) (xy 36.827298 -151.616636) (xy 36.874958 -151.616156)
			(xy 36.925143 -151.616679) (xy 37.02517 -151.624964) (xy 37.124172 -151.641481) (xy 37.221471 -151.666118)
			(xy 37.316403 -151.698706) (xy 37.40832 -151.739022) (xy 37.496594 -151.786792) (xy 37.580621 -151.841687)
			(xy 37.659828 -151.903335) (xy 37.733673 -151.971313) (xy 37.801652 -152.045157) (xy 37.863301 -152.124363)
			(xy 37.918198 -152.208389) (xy 37.965969 -152.296662) (xy 38.006287 -152.388578) (xy 38.038876 -152.48351)
			(xy 38.063514 -152.580809) (xy 38.080034 -152.67981) (xy 38.08832 -152.779837) (xy 38.088824 -152.830022)
			(xy 38.088387 -152.877685) (xy 38.080899 -152.972716) (xy 38.065978 -153.066867) (xy 38.043717 -153.159558)
			(xy 38.014253 -153.250216) (xy 37.977767 -153.338283) (xy 37.934484 -153.423216) (xy 37.884671 -153.504492)
			(xy 37.828636 -153.581609) (xy 37.766723 -153.654092) (xy 37.699315 -153.721495) (xy 37.663374 -153.752804)
			(xy 37.655347 -153.760372) (xy 37.646132 -153.780392) (xy 37.645594 -153.791412) (xy 37.645594 -153.868628)
			(xy 37.646118 -153.879648) (xy 37.655348 -153.899665) (xy 37.663374 -153.907236) (xy 37.699318 -153.938538)
			(xy 37.766712 -154.005952) (xy 37.828611 -154.078443) (xy 37.884634 -154.155565) (xy 37.934437 -154.236842)
			(xy 37.977713 -154.321776) (xy 38.014195 -154.409841) (xy 38.043659 -154.500496) (xy 38.065922 -154.593182)
			(xy 38.080849 -154.687329) (xy 38.088346 -154.782357) (xy 38.088824 -154.830018) (xy 38.088384 -154.877681)
			(xy 38.080896 -154.972712) (xy 38.065976 -155.066863) (xy 38.043715 -155.159553) (xy 38.014251 -155.250211)
			(xy 37.977765 -155.338278) (xy 37.934483 -155.423212) (xy 37.884671 -155.504487) (xy 37.828635 -155.581605)
			(xy 37.766723 -155.654088) (xy 37.699314 -155.721491) (xy 37.663374 -155.7528) (xy 37.655349 -155.76037)
			(xy 37.646132 -155.780389) (xy 37.645594 -155.791408) (xy 37.645594 -155.868624) (xy 37.64612 -155.879644)
			(xy 37.655348 -155.89966) (xy 37.663374 -155.907232) (xy 37.699316 -155.938536) (xy 37.76671 -156.00595)
			(xy 37.828609 -156.07844) (xy 37.884632 -156.155562) (xy 37.934436 -156.23684) (xy 37.977712 -156.321773)
			(xy 38.014194 -156.409838) (xy 38.043658 -156.500492) (xy 38.065921 -156.593179) (xy 38.080848 -156.687325)
			(xy 38.088346 -156.782353) (xy 38.088824 -156.830014) (xy 38.088381 -156.877677) (xy 38.080894 -156.972708)
			(xy 38.065974 -157.066859) (xy 38.043713 -157.159549) (xy 38.014249 -157.250207) (xy 37.977764 -157.338274)
			(xy 37.934482 -157.423207) (xy 37.88467 -157.504483) (xy 37.828635 -157.581601) (xy 37.766722 -157.654084)
			(xy 37.699314 -157.721487) (xy 37.663374 -157.752796) (xy 37.65535 -157.760367) (xy 37.646133 -157.780385)
			(xy 37.645594 -157.791404) (xy 37.645594 -157.86862) (xy 37.646123 -157.87964) (xy 37.655349 -157.899656)
			(xy 37.663374 -157.907228) (xy 37.699314 -157.938534) (xy 37.766708 -158.005947) (xy 37.828607 -158.078438)
			(xy 37.884631 -158.155559) (xy 37.934434 -158.236837) (xy 37.97771 -158.32177) (xy 38.014193 -158.409834)
			(xy 38.043657 -158.500489) (xy 38.065921 -158.593175) (xy 38.080848 -158.687322) (xy 38.088346 -158.782349)
			(xy 38.088824 -158.830006) (xy 47.585872 -158.830006) (xy 47.589977 -158.730238) (xy 47.602263 -158.631145)
			(xy 47.62265 -158.533395) (xy 47.650997 -158.437651) (xy 47.687114 -158.344559) (xy 47.730757 -158.254749)
			(xy 47.781631 -158.168828) (xy 47.839391 -158.087377) (xy 47.903647 -158.010946) (xy 47.973966 -157.940053)
			(xy 48.011588 -157.907228) (xy 48.019595 -157.899641) (xy 48.028823 -157.879635) (xy 48.029368 -157.86862)
			(xy 48.029368 -157.791404) (xy 48.028838 -157.780384) (xy 48.019614 -157.760367) (xy 48.011588 -157.752796)
			(xy 47.975656 -157.721488) (xy 47.908285 -157.654066) (xy 47.846409 -157.581568) (xy 47.790409 -157.504442)
			(xy 47.74063 -157.423161) (xy 47.697378 -157.338227) (xy 47.660919 -157.250163) (xy 47.631479 -157.159511)
			(xy 47.609239 -157.06683) (xy 47.594335 -156.972689) (xy 47.586859 -156.87767) (xy 47.586392 -156.830014)
			(xy 47.586965 -156.779838) (xy 47.59525 -156.679827) (xy 47.611764 -156.580842) (xy 47.636395 -156.483559)
			(xy 47.668973 -156.388642) (xy 47.709278 -156.296738) (xy 47.757033 -156.208477) (xy 47.811913 -156.124459)
			(xy 47.873542 -156.04526) (xy 47.9415 -155.97142) (xy 48.015323 -155.903443) (xy 48.094507 -155.841793)
			(xy 48.17851 -155.786892) (xy 48.26676 -155.739114) (xy 48.358653 -155.698786) (xy 48.453562 -155.666183)
			(xy 48.550839 -155.641528) (xy 48.64982 -155.624989) (xy 48.749828 -155.616678) (xy 48.800004 -155.616148)
			(xy 48.847666 -155.616608) (xy 48.942697 -155.624094) (xy 49.036847 -155.639013) (xy 49.129537 -155.661272)
			(xy 49.220195 -155.690735) (xy 49.308261 -155.727219) (xy 49.393195 -155.770499) (xy 49.474471 -155.820309)
			(xy 49.551588 -155.876342) (xy 49.624073 -155.938253) (xy 49.691476 -156.005659) (xy 49.722786 -156.041598)
			(xy 49.730366 -156.049613) (xy 49.750377 -156.058836) (xy 49.761394 -156.059378) (xy 49.83861 -156.059378)
			(xy 49.849631 -156.058852) (xy 49.869647 -156.049625) (xy 49.877218 -156.041598) (xy 49.908523 -156.005656)
			(xy 49.975937 -155.938264) (xy 50.048428 -155.876365) (xy 50.12555 -155.820342) (xy 50.206827 -155.770539)
			(xy 50.29176 -155.727263) (xy 50.379825 -155.690781) (xy 50.470479 -155.661317) (xy 50.563165 -155.639053)
			(xy 50.657312 -155.624125) (xy 50.752339 -155.616627) (xy 50.8 -155.616148) (xy 50.850166 -155.616706)
			(xy 50.950156 -155.62499) (xy 51.04912 -155.641502) (xy 51.146384 -155.666128) (xy 51.241281 -155.698701)
			(xy 51.333166 -155.738998) (xy 51.421409 -155.786744) (xy 51.505409 -155.841614) (xy 51.584592 -155.903231)
			(xy 51.658416 -155.971176) (xy 51.726379 -156.044984) (xy 51.788016 -156.124152) (xy 51.842905 -156.208138)
			(xy 51.890673 -156.29637) (xy 51.930992 -156.388245) (xy 51.963588 -156.483134) (xy 51.988238 -156.580392)
			(xy 52.004774 -156.679352) (xy 52.013082 -156.77934) (xy 52.013612 -156.829506) (xy 52.013612 -156.830014)
			(xy 52.013125 -156.87767) (xy 52.005656 -156.972689) (xy 51.990757 -157.06683) (xy 51.968521 -157.159512)
			(xy 51.939083 -157.250164) (xy 51.902626 -157.338228) (xy 51.859375 -157.423162) (xy 51.809594 -157.504441)
			(xy 51.753592 -157.581566) (xy 51.691714 -157.65406) (xy 51.62434 -157.721478) (xy 51.588416 -157.752796)
			(xy 51.580399 -157.760374) (xy 51.571177 -157.780386) (xy 51.570636 -157.791404) (xy 51.570636 -157.86862)
			(xy 51.571152 -157.879642) (xy 51.580386 -157.899659) (xy 51.588416 -157.907228) (xy 51.626049 -157.940041)
			(xy 51.696367 -158.010936) (xy 51.760624 -158.087368) (xy 51.818385 -158.16882) (xy 51.869259 -158.254742)
			(xy 51.912903 -158.344553) (xy 51.94902 -158.437646) (xy 51.977368 -158.533392) (xy 51.997754 -158.631142)
			(xy 52.010041 -158.730237) (xy 52.014146 -158.830007) (xy 52.01004 -158.929776) (xy 51.997752 -159.028871)
			(xy 51.977365 -159.126621) (xy 51.949016 -159.222366) (xy 51.912897 -159.315459) (xy 51.869253 -159.405269)
			(xy 51.818378 -159.491191) (xy 51.760616 -159.572642) (xy 51.696359 -159.649074) (xy 51.626039 -159.719967)
			(xy 51.588416 -159.752792) (xy 51.580401 -159.760372) (xy 51.571178 -159.780383) (xy 51.570636 -159.7914)
			(xy 51.570636 -159.868616) (xy 51.571154 -159.879638) (xy 51.580386 -159.899655) (xy 51.588416 -159.907224)
			(xy 51.624359 -159.93852) (xy 51.691729 -160.005944) (xy 51.753604 -160.078442) (xy 51.809604 -160.15557)
			(xy 51.859382 -160.236852) (xy 51.902633 -160.321787) (xy 51.939091 -160.409853) (xy 51.96853 -160.500506)
			(xy 51.990769 -160.593188) (xy 52.005671 -160.687329) (xy 52.013145 -160.782349) (xy 52.013612 -160.830006)
			(xy 52.013509 -160.852379) (xy 52.011856 -160.897094) (xy 52.01031 -160.919414) (xy 52.01031 -160.919668)
			(xy 52.010063 -160.928551) (xy 52.014939 -160.945628) (xy 52.025303 -160.960049) (xy 52.032408 -160.965388)
			(xy 52.10556 -161.014664) (xy 52.113141 -161.019381) (xy 52.130424 -161.023806) (xy 52.148176 -161.022038)
			(xy 52.15636 -161.018474) (xy 52.156614 -161.01822) (xy 52.206696 -160.994237) (xy 52.309828 -160.953049)
			(xy 52.415788 -160.919811) (xy 52.523967 -160.894713) (xy 52.633739 -160.877899) (xy 52.74447 -160.869468)
			(xy 52.855522 -160.869468) (xy 52.966253 -160.877899) (xy 53.076025 -160.894713) (xy 53.184204 -160.919811)
			(xy 53.290164 -160.953049) (xy 53.393296 -160.994237) (xy 53.443378 -161.01822) (xy 53.443632 -161.018474)
			(xy 53.451831 -161.022014) (xy 53.469582 -161.023818) (xy 53.486874 -161.019416) (xy 53.494432 -161.014664)
			(xy 53.567584 -160.965388) (xy 53.574788 -160.960147) (xy 53.585215 -160.945714) (xy 53.590029 -160.928571)
			(xy 53.589682 -160.919668) (xy 53.589682 -160.919414) (xy 53.588137 -160.897094) (xy 53.586483 -160.852379)
			(xy 53.58638 -160.830006) (xy 53.58685 -160.782349) (xy 53.594318 -160.687329) (xy 53.609216 -160.593187)
			(xy 53.631453 -160.500504) (xy 53.660891 -160.409851) (xy 53.69735 -160.321786) (xy 53.740604 -160.236853)
			(xy 53.790387 -160.155574) (xy 53.846391 -160.07845) (xy 53.908273 -160.005957) (xy 53.975651 -159.938541)
			(xy 54.011576 -159.907224) (xy 54.019598 -159.899652) (xy 54.028814 -159.879634) (xy 54.029356 -159.868616)
			(xy 54.029356 -159.7914) (xy 54.028832 -159.780379) (xy 54.019604 -159.760362) (xy 54.011576 -159.752792)
			(xy 53.973961 -159.719958) (xy 53.903637 -159.649067) (xy 53.839375 -159.572639) (xy 53.78161 -159.491189)
			(xy 53.730732 -159.405269) (xy 53.687085 -159.315459) (xy 53.650964 -159.222367) (xy 53.622613 -159.126622)
			(xy 53.602224 -159.028872) (xy 53.589935 -158.929776) (xy 53.585829 -158.830006) (xy 53.589934 -158.730237)
			(xy 53.602222 -158.631141) (xy 53.62261 -158.533391) (xy 53.650959 -158.437645) (xy 53.68708 -158.344553)
			(xy 53.730726 -158.254743) (xy 53.781603 -158.168822) (xy 53.839368 -158.087371) (xy 53.903628 -158.010942)
			(xy 53.973951 -157.940051) (xy 54.011576 -157.907228) (xy 54.019596 -157.899654) (xy 54.028813 -157.879638)
			(xy 54.029356 -157.86862) (xy 54.029356 -157.791404) (xy 54.02883 -157.780383) (xy 54.019604 -157.760366)
			(xy 54.011576 -157.752796) (xy 53.975641 -157.721491) (xy 53.908271 -157.654068) (xy 53.846396 -157.58157)
			(xy 53.790396 -157.504443) (xy 53.740617 -157.423162) (xy 53.697365 -157.338228) (xy 53.660907 -157.250164)
			(xy 53.631467 -157.159512) (xy 53.609227 -157.06683) (xy 53.594323 -156.97269) (xy 53.586847 -156.87767)
			(xy 53.58638 -156.830014) (xy 53.586866 -156.779835) (xy 53.595151 -156.67982) (xy 53.611667 -156.580831)
			(xy 53.636299 -156.483544) (xy 53.668881 -156.388622) (xy 53.709189 -156.296715) (xy 53.756949 -156.208451)
			(xy 53.811833 -156.124431) (xy 53.873468 -156.04523) (xy 53.941431 -155.971389) (xy 54.01526 -155.903411)
			(xy 54.09445 -155.841762) (xy 54.17846 -155.786862) (xy 54.266716 -155.739087) (xy 54.358615 -155.698762)
			(xy 54.453531 -155.666163) (xy 54.550814 -155.641512) (xy 54.6498 -155.624979) (xy 54.749813 -155.616675)
			(xy 54.799992 -155.616148) (xy 54.847654 -155.616616) (xy 54.942685 -155.624102) (xy 55.036835 -155.63902)
			(xy 55.129524 -155.661278) (xy 55.220182 -155.69074) (xy 55.308249 -155.727223) (xy 55.393182 -155.770502)
			(xy 55.474458 -155.820312) (xy 55.551576 -155.876344) (xy 55.62406 -155.938254) (xy 55.691464 -156.005659)
			(xy 55.722774 -156.041598) (xy 55.730359 -156.049607) (xy 55.750366 -156.058833) (xy 55.761382 -156.059378)
			(xy 55.838598 -156.059378) (xy 55.849618 -156.058846) (xy 55.869635 -156.049623) (xy 55.877206 -156.041598)
			(xy 55.908518 -156.005662) (xy 55.975931 -155.93827) (xy 56.048421 -155.876371) (xy 56.125542 -155.820347)
			(xy 56.206819 -155.770544) (xy 56.291751 -155.727267) (xy 56.379815 -155.690784) (xy 56.470469 -155.66132)
			(xy 56.563154 -155.639055) (xy 56.6573 -155.624127) (xy 56.752327 -155.616627) (xy 56.799988 -155.616148)
			(xy 56.850154 -155.616717) (xy 56.950144 -155.625) (xy 57.049108 -155.641511) (xy 57.146371 -155.666137)
			(xy 57.241269 -155.698709) (xy 57.333153 -155.739005) (xy 57.421396 -155.786751) (xy 57.505396 -155.841619)
			(xy 57.584579 -155.903236) (xy 57.658404 -155.97118) (xy 57.726366 -156.044988) (xy 57.788003 -156.124155)
			(xy 57.842893 -156.208141) (xy 57.89066 -156.296372) (xy 57.93098 -156.388246) (xy 57.963576 -156.483136)
			(xy 57.988226 -156.580393) (xy 58.004762 -156.679353) (xy 58.01307 -156.77934) (xy 58.0136 -156.829506)
			(xy 58.0136 -156.830014) (xy 58.013117 -156.87767) (xy 58.005648 -156.97269) (xy 57.990749 -157.06683)
			(xy 57.968513 -157.159512) (xy 57.939075 -157.250165) (xy 57.902617 -157.338229) (xy 57.859365 -157.423163)
			(xy 57.809584 -157.504442) (xy 57.753582 -157.581567) (xy 57.691703 -157.654061) (xy 57.624328 -157.721478)
			(xy 57.588404 -157.752796) (xy 57.580385 -157.760372) (xy 57.571164 -157.780386) (xy 57.570624 -157.791404)
			(xy 57.570624 -157.86862) (xy 57.571143 -157.879641) (xy 57.580375 -157.899658) (xy 57.588404 -157.907228)
			(xy 57.626037 -157.940041) (xy 57.696356 -158.010935) (xy 57.760614 -158.087367) (xy 57.818375 -158.168819)
			(xy 57.86925 -158.254741) (xy 57.912894 -158.344552) (xy 57.949012 -158.437645) (xy 57.97736 -158.533391)
			(xy 57.997746 -158.631142) (xy 58.010033 -158.730237) (xy 58.014138 -158.830006) (xy 61.785988 -158.830006)
			(xy 61.790092 -158.730238) (xy 61.802379 -158.631144) (xy 61.822766 -158.533394) (xy 61.851114 -158.437649)
			(xy 61.887232 -158.344557) (xy 61.930876 -158.254747) (xy 61.981751 -158.168826) (xy 62.039512 -158.087375)
			(xy 62.10377 -158.010945) (xy 62.174089 -157.940052) (xy 62.211712 -157.907228) (xy 62.219722 -157.899645)
			(xy 62.228947 -157.879636) (xy 62.229492 -157.86862) (xy 62.229492 -157.791404) (xy 62.228954 -157.780385)
			(xy 62.219735 -157.760368) (xy 62.211712 -157.752796) (xy 62.175785 -157.721482) (xy 62.108414 -157.654061)
			(xy 62.046537 -157.581565) (xy 61.990536 -157.504439) (xy 61.940756 -157.423159) (xy 61.897503 -157.338226)
			(xy 61.861045 -157.250162) (xy 61.831604 -157.15951) (xy 61.809363 -157.066829) (xy 61.794459 -156.972689)
			(xy 61.786983 -156.87767) (xy 61.786516 -156.830014) (xy 61.787065 -156.779837) (xy 61.79535 -156.679825)
			(xy 61.811865 -156.580839) (xy 61.836496 -156.483555) (xy 61.869075 -156.388636) (xy 61.909381 -156.296732)
			(xy 61.957137 -156.20847) (xy 62.012018 -156.124451) (xy 62.073649 -156.045252) (xy 62.141609 -155.971411)
			(xy 62.215433 -155.903434) (xy 62.294619 -155.841785) (xy 62.378624 -155.786884) (xy 62.466875 -155.739107)
			(xy 62.55877 -155.698779) (xy 62.653681 -155.666178) (xy 62.750959 -155.641524) (xy 62.849941 -155.624986)
			(xy 62.949951 -155.616677) (xy 63.000128 -155.616148) (xy 63.047791 -155.61659) (xy 63.142822 -155.624079)
			(xy 63.236972 -155.639) (xy 63.329662 -155.661261) (xy 63.42032 -155.690725) (xy 63.508387 -155.72721)
			(xy 63.59332 -155.770492) (xy 63.674596 -155.820304) (xy 63.751713 -155.876339) (xy 63.824197 -155.938251)
			(xy 63.891601 -156.005658) (xy 63.92291 -156.041598) (xy 63.93048 -156.049623) (xy 63.950499 -156.058841)
			(xy 63.961518 -156.059378) (xy 64.038734 -156.059378) (xy 64.049756 -156.058866) (xy 64.069773 -156.049629)
			(xy 64.077342 -156.041598) (xy 64.108634 -156.005645) (xy 64.176049 -155.938253) (xy 64.248542 -155.876355)
			(xy 64.325665 -155.820332) (xy 64.406944 -155.77053) (xy 64.491878 -155.727255) (xy 64.579944 -155.690774)
			(xy 64.6706 -155.661311) (xy 64.763287 -155.639048) (xy 64.857434 -155.624123) (xy 64.952462 -155.616626)
			(xy 65.000124 -155.616148) (xy 65.050291 -155.616683) (xy 65.150281 -155.624969) (xy 65.249246 -155.641482)
			(xy 65.346509 -155.666111) (xy 65.441407 -155.698685) (xy 65.533292 -155.738984) (xy 65.621535 -155.786732)
			(xy 65.705535 -155.841602) (xy 65.784717 -155.903221) (xy 65.858542 -155.971167) (xy 65.926504 -156.044977)
			(xy 65.988141 -156.124145) (xy 66.04303 -156.208133) (xy 66.090797 -156.296366) (xy 66.131116 -156.388241)
			(xy 66.163712 -156.483132) (xy 66.188362 -156.58039) (xy 66.204898 -156.679351) (xy 66.213206 -156.77934)
			(xy 66.213736 -156.829506) (xy 66.213736 -156.830014) (xy 66.213275 -156.877671) (xy 66.205806 -156.972691)
			(xy 66.190906 -157.066833) (xy 66.168668 -157.159516) (xy 66.139228 -157.250169) (xy 66.102769 -157.338234)
			(xy 66.059514 -157.423167) (xy 66.009731 -157.504446) (xy 65.953726 -157.58157) (xy 65.891843 -157.654063)
			(xy 65.824465 -157.721479) (xy 65.78854 -157.752796) (xy 65.780512 -157.760363) (xy 65.771299 -157.780384)
			(xy 65.77076 -157.791404) (xy 65.77076 -157.86862) (xy 65.771299 -157.879638) (xy 65.780519 -157.899654)
			(xy 65.78854 -157.907228) (xy 65.826175 -157.94004) (xy 65.896498 -158.010933) (xy 65.960758 -158.087363)
			(xy 66.018523 -158.168815) (xy 66.0694 -158.254736) (xy 66.113046 -158.344548) (xy 66.149166 -158.437641)
			(xy 66.177516 -158.533388) (xy 66.197904 -158.631139) (xy 66.210191 -158.730236) (xy 66.214296 -158.830006)
			(xy 67.78598 -158.830006) (xy 67.790084 -158.730238) (xy 67.802371 -158.631144) (xy 67.822758 -158.533394)
			(xy 67.851106 -158.43765) (xy 67.887223 -158.344558) (xy 67.930867 -158.254748) (xy 67.981741 -158.168827)
			(xy 68.039502 -158.087376) (xy 68.103758 -158.010946) (xy 68.174077 -157.940052) (xy 68.2117 -157.907228)
			(xy 68.219709 -157.899643) (xy 68.228935 -157.879636) (xy 68.22948 -157.86862) (xy 68.22948 -157.791404)
			(xy 68.228946 -157.780384) (xy 68.219725 -157.760368) (xy 68.2117 -157.752796) (xy 68.17577 -157.721485)
			(xy 68.108399 -157.654063) (xy 68.046523 -157.581566) (xy 67.990523 -157.50444) (xy 67.940743 -157.42316)
			(xy 67.897491 -157.338227) (xy 67.861032 -157.250163) (xy 67.831592 -157.159511) (xy 67.809351 -157.066829)
			(xy 67.794447 -156.972689) (xy 67.786971 -156.87767) (xy 67.786504 -156.830014) (xy 67.787065 -156.779837)
			(xy 67.79535 -156.679826) (xy 67.811864 -156.580841) (xy 67.836495 -156.483557) (xy 67.869074 -156.388639)
			(xy 67.90938 -156.296735) (xy 67.957135 -156.208473) (xy 68.012016 -156.124455) (xy 68.073646 -156.045256)
			(xy 68.141605 -155.971415) (xy 68.215428 -155.903438) (xy 68.294613 -155.841789) (xy 68.378617 -155.786888)
			(xy 68.466867 -155.73911) (xy 68.558761 -155.698783) (xy 68.653671 -155.66618) (xy 68.750949 -155.641526)
			(xy 68.84993 -155.624987) (xy 68.949939 -155.616678) (xy 69.000116 -155.616148) (xy 69.047779 -155.616599)
			(xy 69.142809 -155.624087) (xy 69.23696 -155.639006) (xy 69.32965 -155.661267) (xy 69.420307 -155.69073)
			(xy 69.508374 -155.727214) (xy 69.593307 -155.770496) (xy 69.674583 -155.820307) (xy 69.751701 -155.87634)
			(xy 69.824185 -155.938252) (xy 69.891588 -156.005658) (xy 69.922898 -156.041598) (xy 69.930473 -156.049618)
			(xy 69.950488 -156.058838) (xy 69.961506 -156.059378) (xy 70.038722 -156.059378) (xy 70.049743 -156.058859)
			(xy 70.06976 -156.049627) (xy 70.07733 -156.041598) (xy 70.108628 -156.005651) (xy 70.176043 -155.938258)
			(xy 70.248535 -155.87636) (xy 70.325657 -155.820337) (xy 70.406936 -155.770534) (xy 70.491869 -155.727259)
			(xy 70.579934 -155.690777) (xy 70.67059 -155.661314) (xy 70.763276 -155.639051) (xy 70.857423 -155.624124)
			(xy 70.952451 -155.616626) (xy 71.000112 -155.616148) (xy 71.050278 -155.616694) (xy 71.150268 -155.624979)
			(xy 71.249233 -155.641492) (xy 71.346496 -155.666119) (xy 71.441394 -155.698693) (xy 71.533279 -155.738991)
			(xy 71.621522 -155.786738) (xy 71.705522 -155.841608) (xy 71.784704 -155.903226) (xy 71.858529 -155.971171)
			(xy 71.926492 -156.04498) (xy 71.988128 -156.124149) (xy 72.043017 -156.208136) (xy 72.090785 -156.296368)
			(xy 72.131104 -156.388243) (xy 72.1637 -156.483133) (xy 72.18835 -156.580391) (xy 72.204886 -156.679352)
			(xy 72.213194 -156.77934) (xy 72.213724 -156.829506) (xy 72.213724 -156.830014) (xy 72.213267 -156.877671)
			(xy 72.205798 -156.972692) (xy 72.190898 -157.066833) (xy 72.16866 -157.159517) (xy 72.13922 -157.25017)
			(xy 72.10276 -157.338235) (xy 72.059505 -157.423168) (xy 72.009721 -157.504447) (xy 71.953715 -157.581571)
			(xy 71.891832 -157.654064) (xy 71.824454 -157.721479) (xy 71.788528 -157.752796) (xy 71.780497 -157.760361)
			(xy 71.771286 -157.780384) (xy 71.770748 -157.791404) (xy 71.770748 -157.86862) (xy 71.77126 -157.879642)
			(xy 71.780496 -157.89966) (xy 71.788528 -157.907228) (xy 71.826961 -157.940728) (xy 71.898668 -158.013216)
			(xy 71.964043 -158.091463) (xy 72.022625 -158.174917) (xy 72.074 -158.26299) (xy 72.096376 -158.308802)
			(xy 72.100948 -158.318454) (xy 72.11695 -158.332424) (xy 72.199246 -158.357316) (xy 72.209509 -158.35998)
			(xy 72.230544 -158.357501) (xy 72.239886 -158.35249) (xy 72.285848 -158.325685) (xy 72.380951 -158.27795)
			(xy 72.479225 -158.237137) (xy 72.580165 -158.203457) (xy 72.683255 -158.17708) (xy 72.787967 -158.158142)
			(xy 72.893765 -158.146741) (xy 73.000108 -158.142934) (xy 73.106451 -158.146741) (xy 73.212249 -158.158142)
			(xy 73.316961 -158.17708) (xy 73.420051 -158.203457) (xy 73.520991 -158.237137) (xy 73.619265 -158.27795)
			(xy 73.714368 -158.325685) (xy 73.76033 -158.35249) (xy 73.769716 -158.357372) (xy 73.790702 -158.359866)
			(xy 73.80097 -158.357316) (xy 73.883266 -158.332424) (xy 73.899268 -158.318454) (xy 73.90384 -158.308802)
			(xy 73.92622 -158.262993) (xy 73.97759 -158.174915) (xy 74.036169 -158.09146) (xy 74.101545 -158.013214)
			(xy 74.173257 -157.940731) (xy 74.211688 -157.907228) (xy 74.219695 -157.899641) (xy 74.228923 -157.879635)
			(xy 74.229468 -157.86862) (xy 74.229468 -157.791404) (xy 74.228938 -157.780384) (xy 74.219714 -157.760367)
			(xy 74.211688 -157.752796) (xy 74.175756 -157.721488) (xy 74.108385 -157.654066) (xy 74.046509 -157.581568)
			(xy 73.990509 -157.504442) (xy 73.94073 -157.423161) (xy 73.897478 -157.338227) (xy 73.861019 -157.250163)
			(xy 73.831579 -157.159511) (xy 73.809339 -157.06683) (xy 73.794435 -156.972689) (xy 73.786959 -156.87767)
			(xy 73.786492 -156.830014) (xy 73.787065 -156.779838) (xy 73.79535 -156.679827) (xy 73.811864 -156.580842)
			(xy 73.836495 -156.483559) (xy 73.869073 -156.388642) (xy 73.909378 -156.296738) (xy 73.957133 -156.208477)
			(xy 74.012013 -156.124459) (xy 74.073642 -156.04526) (xy 74.1416 -155.97142) (xy 74.215423 -155.903443)
			(xy 74.294607 -155.841793) (xy 74.37861 -155.786892) (xy 74.46686 -155.739114) (xy 74.558753 -155.698786)
			(xy 74.653662 -155.666183) (xy 74.750939 -155.641528) (xy 74.84992 -155.624989) (xy 74.949928 -155.616678)
			(xy 75.000104 -155.616148) (xy 75.047766 -155.616608) (xy 75.142797 -155.624094) (xy 75.236947 -155.639013)
			(xy 75.329637 -155.661272) (xy 75.420295 -155.690735) (xy 75.508361 -155.727219) (xy 75.593295 -155.770499)
			(xy 75.674571 -155.820309) (xy 75.751688 -155.876342) (xy 75.824173 -155.938253) (xy 75.891576 -156.005659)
			(xy 75.922886 -156.041598) (xy 75.930466 -156.049613) (xy 75.950477 -156.058836) (xy 75.961494 -156.059378)
			(xy 76.03871 -156.059378) (xy 76.049731 -156.058852) (xy 76.069747 -156.049625) (xy 76.077318 -156.041598)
			(xy 76.108623 -156.005656) (xy 76.176037 -155.938264) (xy 76.248528 -155.876365) (xy 76.32565 -155.820342)
			(xy 76.406927 -155.770539) (xy 76.49186 -155.727263) (xy 76.579925 -155.690781) (xy 76.670579 -155.661317)
			(xy 76.763265 -155.639053) (xy 76.857412 -155.624125) (xy 76.952439 -155.616627) (xy 77.0001 -155.616148)
			(xy 77.050266 -155.616706) (xy 77.150256 -155.62499) (xy 77.24922 -155.641502) (xy 77.346484 -155.666128)
			(xy 77.441381 -155.698701) (xy 77.533266 -155.738998) (xy 77.621509 -155.786744) (xy 77.705509 -155.841614)
			(xy 77.784692 -155.903231) (xy 77.858516 -155.971176) (xy 77.926479 -156.044984) (xy 77.988116 -156.124152)
			(xy 78.043005 -156.208138) (xy 78.090773 -156.29637) (xy 78.131092 -156.388245) (xy 78.163688 -156.483134)
			(xy 78.188338 -156.580392) (xy 78.204874 -156.679352) (xy 78.213182 -156.77934) (xy 78.213712 -156.829506)
			(xy 78.213712 -156.830014) (xy 78.213225 -156.87767) (xy 78.205756 -156.972689) (xy 78.190857 -157.06683)
			(xy 78.168621 -157.159512) (xy 78.139183 -157.250164) (xy 78.102726 -157.338228) (xy 78.059475 -157.423162)
			(xy 78.009694 -157.504441) (xy 77.953692 -157.581566) (xy 77.891814 -157.65406) (xy 77.82444 -157.721478)
			(xy 77.788516 -157.752796) (xy 77.780499 -157.760374) (xy 77.771277 -157.780386) (xy 77.770736 -157.791404)
			(xy 77.770736 -157.86862) (xy 77.771252 -157.879642) (xy 77.780486 -157.899659) (xy 77.788516 -157.907228)
			(xy 77.826149 -157.940041) (xy 77.896467 -158.010936) (xy 77.960724 -158.087368) (xy 78.018485 -158.16882)
			(xy 78.069359 -158.254742) (xy 78.113003 -158.344553) (xy 78.14912 -158.437646) (xy 78.177468 -158.533392)
			(xy 78.197854 -158.631142) (xy 78.210141 -158.730237) (xy 78.214246 -158.830007) (xy 78.21014 -158.929776)
			(xy 78.197852 -159.028871) (xy 78.177465 -159.126621) (xy 78.149116 -159.222366) (xy 78.112997 -159.315459)
			(xy 78.069353 -159.405269) (xy 78.018478 -159.491191) (xy 77.960716 -159.572642) (xy 77.896459 -159.649074)
			(xy 77.826139 -159.719967) (xy 77.788516 -159.752792) (xy 77.780501 -159.760372) (xy 77.771278 -159.780383)
			(xy 77.770736 -159.7914) (xy 77.770736 -159.868616) (xy 77.771254 -159.879638) (xy 77.780486 -159.899655)
			(xy 77.788516 -159.907224) (xy 77.824459 -159.93852) (xy 77.891829 -160.005944) (xy 77.953704 -160.078442)
			(xy 78.009704 -160.15557) (xy 78.059482 -160.236852) (xy 78.102733 -160.321787) (xy 78.139191 -160.409853)
			(xy 78.16863 -160.500506) (xy 78.190869 -160.593188) (xy 78.205771 -160.687329) (xy 78.213245 -160.782349)
			(xy 78.213712 -160.830006) (xy 78.213154 -160.880183) (xy 78.204867 -160.980193) (xy 78.188352 -161.079178)
			(xy 78.16372 -161.176461) (xy 78.13114 -161.271379) (xy 78.090834 -161.363282) (xy 78.043078 -161.451544)
			(xy 77.988197 -161.535561) (xy 77.926567 -161.61476) (xy 77.858608 -161.6886) (xy 77.784785 -161.756577)
			(xy 77.7056 -161.818226) (xy 77.621596 -161.873127) (xy 77.533346 -161.920905) (xy 77.441453 -161.961233)
			(xy 77.346543 -161.993836) (xy 77.249266 -162.018492) (xy 77.150285 -162.035031) (xy 77.050276 -162.043342)
			(xy 77.0001 -162.043872) (xy 76.952438 -162.043402) (xy 76.857408 -162.035916) (xy 76.763258 -162.020998)
			(xy 76.670569 -161.998739) (xy 76.579911 -161.969278) (xy 76.491844 -161.932795) (xy 76.406911 -161.889516)
			(xy 76.325635 -161.839706) (xy 76.248517 -161.783675) (xy 76.176032 -161.721766) (xy 76.108628 -161.654361)
			(xy 76.077318 -161.618422) (xy 76.069749 -161.610397) (xy 76.049729 -161.601183) (xy 76.03871 -161.600642)
			(xy 75.961494 -161.600642) (xy 75.950473 -161.601163) (xy 75.930456 -161.610393) (xy 75.922886 -161.618422)
			(xy 75.891584 -161.654366) (xy 75.824169 -161.721758) (xy 75.751678 -161.783656) (xy 75.674555 -161.839679)
			(xy 75.593277 -161.889481) (xy 75.508344 -161.932757) (xy 75.420279 -161.969239) (xy 75.329625 -161.998703)
			(xy 75.236939 -162.020967) (xy 75.142792 -162.035894) (xy 75.047765 -162.043393) (xy 75.000104 -162.043872)
			(xy 74.950123 -162.043374) (xy 74.8505 -162.035138) (xy 74.751892 -162.018736) (xy 74.654967 -161.994281)
			(xy 74.560381 -161.961938) (xy 74.468775 -161.921925) (xy 74.380771 -161.874515) (xy 74.296963 -161.820029)
			(xy 74.21792 -161.758834) (xy 74.144177 -161.691347) (xy 74.076234 -161.618024) (xy 74.014551 -161.539362)
			(xy 73.959545 -161.455893) (xy 73.911591 -161.368184) (xy 73.871011 -161.276829) (xy 73.838082 -161.182445)
			(xy 73.813027 -161.085673) (xy 73.804018 -161.036508) (xy 73.801427 -161.024877) (xy 73.787397 -161.005661)
			(xy 73.777094 -160.999678) (xy 73.693528 -160.957514) (xy 73.669906 -160.95726) (xy 73.658984 -160.962594)
			(xy 73.611709 -160.985464) (xy 73.514509 -161.025256) (xy 73.414743 -161.058087) (xy 73.312908 -161.083794)
			(xy 73.209512 -161.102248) (xy 73.105072 -161.113358) (xy 73.000108 -161.117067) (xy 72.895144 -161.113358)
			(xy 72.790704 -161.102248) (xy 72.687308 -161.083794) (xy 72.585473 -161.058087) (xy 72.485707 -161.025256)
			(xy 72.388507 -160.985464) (xy 72.341232 -160.962594) (xy 72.330331 -160.957905) (xy 72.306624 -160.958056)
			(xy 72.295766 -160.962848) (xy 72.223122 -160.999678) (xy 72.212846 -161.005698) (xy 72.198797 -161.024888)
			(xy 72.196198 -161.036508) (xy 72.187209 -161.085679) (xy 72.162169 -161.18246) (xy 72.129253 -161.276853)
			(xy 72.088683 -161.368219) (xy 72.040735 -161.455937) (xy 71.985733 -161.539413) (xy 71.924051 -161.618083)
			(xy 71.856106 -161.691411) (xy 71.78236 -161.758901) (xy 71.703311 -161.820096) (xy 71.619496 -161.874581)
			(xy 71.531484 -161.921986) (xy 71.439869 -161.961991) (xy 71.345275 -161.994323) (xy 71.248341 -162.018765)
			(xy 71.149725 -162.035149) (xy 71.050096 -162.043365) (xy 71.000112 -162.043872) (xy 70.95245 -162.043394)
			(xy 70.85742 -162.035909) (xy 70.76327 -162.020991) (xy 70.670581 -161.998734) (xy 70.579924 -161.969273)
			(xy 70.491857 -161.932791) (xy 70.406924 -161.889512) (xy 70.325648 -161.839704) (xy 70.248529 -161.783673)
			(xy 70.176045 -161.721764) (xy 70.10864 -161.65436) (xy 70.07733 -161.618422) (xy 70.069756 -161.610402)
			(xy 70.04974 -161.601185) (xy 70.038722 -161.600642) (xy 69.961506 -161.600642) (xy 69.950486 -161.60117)
			(xy 69.930468 -161.610395) (xy 69.922898 -161.618422) (xy 69.891589 -161.65436) (xy 69.824175 -161.721752)
			(xy 69.751684 -161.78365) (xy 69.674563 -161.839674) (xy 69.593286 -161.889477) (xy 69.508353 -161.932753)
			(xy 69.420289 -161.969235) (xy 69.329635 -161.9987) (xy 69.23695 -162.020965) (xy 69.142804 -162.035893)
			(xy 69.047777 -162.043393) (xy 69.000116 -162.043872) (xy 68.949948 -162.043379) (xy 68.849954 -162.035095)
			(xy 68.750986 -162.018583) (xy 68.653719 -161.993956) (xy 68.558818 -161.961382) (xy 68.466931 -161.921082)
			(xy 68.378685 -161.873333) (xy 68.294683 -161.818461) (xy 68.215498 -161.756839) (xy 68.141672 -161.68889)
			(xy 68.073709 -161.615077) (xy 68.012073 -161.535905) (xy 67.957185 -161.451913) (xy 67.909419 -161.363676)
			(xy 67.869102 -161.271796) (xy 67.836509 -161.176901) (xy 67.811864 -161.079639) (xy 67.795333 -160.980674)
			(xy 67.787031 -160.880682) (xy 67.786504 -160.830514) (xy 67.786504 -160.830006) (xy 67.787 -160.78235)
			(xy 67.794468 -160.687331) (xy 67.809365 -160.593191) (xy 67.8316 -160.500509) (xy 67.861037 -160.409856)
			(xy 67.897493 -160.321792) (xy 67.940744 -160.236858) (xy 67.990524 -160.155579) (xy 68.046525 -160.078454)
			(xy 68.108403 -160.00596) (xy 68.175777 -159.938542) (xy 68.2117 -159.907224) (xy 68.21971 -159.89964)
			(xy 68.228936 -159.879632) (xy 68.22948 -159.868616) (xy 68.22948 -159.7914) (xy 68.228948 -159.78038)
			(xy 68.219725 -159.760363) (xy 68.2117 -159.752792) (xy 68.174087 -159.719957) (xy 68.103767 -159.649064)
			(xy 68.039509 -159.572634) (xy 67.981748 -159.491184) (xy 67.930873 -159.405263) (xy 67.887228 -159.315454)
			(xy 67.85111 -159.222362) (xy 67.822761 -159.126618) (xy 67.802374 -159.028869) (xy 67.790086 -158.929775)
			(xy 67.78598 -158.830006) (xy 66.214296 -158.830006) (xy 66.21019 -158.929777) (xy 66.197902 -159.028873)
			(xy 66.177513 -159.126625) (xy 66.149162 -159.222371) (xy 66.113041 -159.315464) (xy 66.069394 -159.405275)
			(xy 66.018516 -159.491196) (xy 65.96075 -159.572647) (xy 65.896489 -159.649077) (xy 65.826165 -159.719969)
			(xy 65.78854 -159.752792) (xy 65.780513 -159.76036) (xy 65.771299 -159.780381) (xy 65.77076 -159.7914)
			(xy 65.77076 -159.868616) (xy 65.771302 -159.879634) (xy 65.78052 -159.89965) (xy 65.78854 -159.907224)
			(xy 65.824488 -159.938515) (xy 65.891857 -160.005939) (xy 65.953732 -160.078439) (xy 66.009731 -160.155567)
			(xy 66.059509 -160.23685) (xy 66.102759 -160.321786) (xy 66.139216 -160.409851) (xy 66.168654 -160.500505)
			(xy 66.190893 -160.593188) (xy 66.205795 -160.687329) (xy 66.213269 -160.782349) (xy 66.213736 -160.830006)
			(xy 66.213254 -160.880185) (xy 66.204967 -160.980199) (xy 66.18845 -161.079188) (xy 66.163816 -161.176475)
			(xy 66.131233 -161.271396) (xy 66.090925 -161.363302) (xy 66.043165 -161.451566) (xy 65.98828 -161.535585)
			(xy 65.926645 -161.614786) (xy 65.858681 -161.688627) (xy 65.784852 -161.756604) (xy 65.705663 -161.818253)
			(xy 65.621653 -161.873153) (xy 65.533398 -161.920929) (xy 65.441499 -161.961254) (xy 65.346584 -161.993854)
			(xy 65.249301 -162.018505) (xy 65.150316 -162.03504) (xy 65.050303 -162.043345) (xy 65.000124 -162.043872)
			(xy 64.952462 -162.043385) (xy 64.857433 -162.035901) (xy 64.763283 -162.020984) (xy 64.670594 -161.998728)
			(xy 64.579937 -161.969268) (xy 64.49187 -161.932787) (xy 64.406937 -161.889509) (xy 64.32566 -161.839701)
			(xy 64.248542 -161.783671) (xy 64.176057 -161.721763) (xy 64.108652 -161.65436) (xy 64.077342 -161.618422)
			(xy 64.069763 -161.610408) (xy 64.049751 -161.601187) (xy 64.038734 -161.600642) (xy 63.961518 -161.600642)
			(xy 63.950498 -161.601177) (xy 63.930481 -161.610397) (xy 63.92291 -161.618422) (xy 63.891594 -161.654354)
			(xy 63.824181 -161.721746) (xy 63.751691 -161.783645) (xy 63.674571 -161.839668) (xy 63.593294 -161.889472)
			(xy 63.508362 -161.932748) (xy 63.420299 -161.969232) (xy 63.329645 -161.998697) (xy 63.23696 -162.020963)
			(xy 63.142815 -162.035892) (xy 63.047789 -162.043392) (xy 63.000128 -162.043872) (xy 62.94996 -162.043367)
			(xy 62.849967 -162.035085) (xy 62.750999 -162.018574) (xy 62.653732 -161.993947) (xy 62.558831 -161.961374)
			(xy 62.466944 -161.921075) (xy 62.378698 -161.873327) (xy 62.294695 -161.818455) (xy 62.215511 -161.756835)
			(xy 62.141685 -161.688886) (xy 62.073722 -161.615074) (xy 62.012086 -161.535902) (xy 61.957197 -161.45191)
			(xy 61.909431 -161.363674) (xy 61.869114 -161.271795) (xy 61.836522 -161.1769) (xy 61.811876 -161.079638)
			(xy 61.795345 -160.980673) (xy 61.787043 -160.880682) (xy 61.786516 -160.830514) (xy 61.786516 -160.830006)
			(xy 61.787008 -160.78235) (xy 61.794476 -160.687331) (xy 61.809373 -160.59319) (xy 61.831609 -160.500508)
			(xy 61.861045 -160.409855) (xy 61.897502 -160.321791) (xy 61.940753 -160.236858) (xy 61.990533 -160.155578)
			(xy 62.046535 -160.078454) (xy 62.108414 -160.005959) (xy 62.175788 -159.938542) (xy 62.211712 -159.907224)
			(xy 62.219724 -159.899642) (xy 62.228948 -159.879632) (xy 62.229492 -159.868616) (xy 62.229492 -159.7914)
			(xy 62.228956 -159.780381) (xy 62.219736 -159.760364) (xy 62.211712 -159.752792) (xy 62.174098 -159.719957)
			(xy 62.103778 -159.649065) (xy 62.03952 -159.572635) (xy 61.981758 -159.491185) (xy 61.930882 -159.405264)
			(xy 61.887237 -159.315455) (xy 61.851118 -159.222363) (xy 61.822769 -159.126619) (xy 61.802382 -159.028869)
			(xy 61.790093 -158.929775) (xy 61.785988 -158.830006) (xy 58.014138 -158.830006) (xy 58.014138 -158.830007)
			(xy 58.010032 -158.929776) (xy 57.997744 -159.028871) (xy 57.977357 -159.126622) (xy 57.949007 -159.222367)
			(xy 57.912888 -159.315459) (xy 57.869244 -159.40527) (xy 57.818368 -159.491192) (xy 57.760606 -159.572643)
			(xy 57.696348 -159.649074) (xy 57.626027 -159.719968) (xy 57.588404 -159.752792) (xy 57.580387 -159.76037)
			(xy 57.571165 -159.780382) (xy 57.570624 -159.7914) (xy 57.570624 -159.868616) (xy 57.571146 -159.879637)
			(xy 57.580376 -159.899654) (xy 57.588404 -159.907224) (xy 57.624344 -159.938523) (xy 57.691715 -160.005946)
			(xy 57.753591 -160.078444) (xy 57.80959 -160.155572) (xy 57.859369 -160.236853) (xy 57.902621 -160.321788)
			(xy 57.939078 -160.409853) (xy 57.968517 -160.500506) (xy 57.990757 -160.593189) (xy 58.005659 -160.68733)
			(xy 58.013133 -160.782349) (xy 58.0136 -160.830006) (xy 58.013054 -160.880183) (xy 58.004767 -160.980194)
			(xy 57.988252 -161.07918) (xy 57.963619 -161.176464) (xy 57.931039 -161.271382) (xy 57.890733 -161.363285)
			(xy 57.842976 -161.451547) (xy 57.788095 -161.535565) (xy 57.726464 -161.614764) (xy 57.658504 -161.688604)
			(xy 57.584679 -161.756581) (xy 57.505494 -161.818231) (xy 57.42149 -161.873131) (xy 57.333239 -161.920909)
			(xy 57.241344 -161.961236) (xy 57.146434 -161.993839) (xy 57.049156 -162.018494) (xy 56.950174 -162.035032)
			(xy 56.850165 -162.043342) (xy 56.799988 -162.043872) (xy 56.752326 -162.043411) (xy 56.657295 -162.035924)
			(xy 56.563145 -162.021005) (xy 56.470456 -161.998745) (xy 56.379798 -161.969283) (xy 56.291731 -161.932799)
			(xy 56.206798 -161.889519) (xy 56.125522 -161.839709) (xy 56.048404 -161.783676) (xy 55.97592 -161.721767)
			(xy 55.908516 -161.654361) (xy 55.877206 -161.618422) (xy 55.869641 -161.610391) (xy 55.849618 -161.60118)
			(xy 55.838598 -161.600642) (xy 55.761382 -161.600642) (xy 55.75036 -161.601157) (xy 55.730343 -161.610391)
			(xy 55.722774 -161.618422) (xy 55.691478 -161.654372) (xy 55.624063 -161.721763) (xy 55.551571 -161.783661)
			(xy 55.474448 -161.839684) (xy 55.393169 -161.889486) (xy 55.308235 -161.932761) (xy 55.22017 -161.969242)
			(xy 55.129515 -161.998706) (xy 55.036828 -162.020969) (xy 54.942681 -162.035896) (xy 54.847653 -162.043394)
			(xy 54.799992 -162.043872) (xy 54.745712 -162.043259) (xy 54.637587 -162.033538) (xy 54.530764 -162.014191)
			(xy 54.426097 -161.985373) (xy 54.37505 -161.96691) (xy 54.362096 -161.962084) (xy 54.33568 -161.966656)
			(xy 54.246526 -162.040316) (xy 54.237128 -162.06597) (xy 54.239414 -162.079432) (xy 54.248227 -162.132911)
			(xy 54.25886 -162.240785) (xy 54.26147 -162.34915) (xy 54.256041 -162.457411) (xy 54.242604 -162.564971)
			(xy 54.221232 -162.67124) (xy 54.192043 -162.775633) (xy 54.155197 -162.877575) (xy 54.110898 -162.976507)
			(xy 54.059389 -163.071883) (xy 54.000952 -163.163179) (xy 53.935911 -163.249894) (xy 53.864621 -163.331549)
			(xy 53.787476 -163.407697) (xy 53.7049 -163.477918) (xy 53.617346 -163.541825) (xy 53.525297 -163.599069)
			(xy 53.429259 -163.649333) (xy 53.329759 -163.692341) (xy 53.227346 -163.727856) (xy 53.122582 -163.755684)
			(xy 53.016044 -163.775672) (xy 52.908318 -163.787708) (xy 52.799996 -163.791727) (xy 52.691674 -163.787708)
			(xy 52.583948 -163.775672) (xy 52.47741 -163.755684) (xy 52.372646 -163.727856) (xy 52.270233 -163.692341)
			(xy 52.170733 -163.649333) (xy 52.074695 -163.599069) (xy 51.982646 -163.541825) (xy 51.895092 -163.477918)
			(xy 51.812516 -163.407697) (xy 51.735371 -163.331549) (xy 51.664081 -163.249894) (xy 51.59904 -163.163179)
			(xy 51.540603 -163.071883) (xy 51.489094 -162.976507) (xy 51.444795 -162.877575) (xy 51.407949 -162.775633)
			(xy 51.37876 -162.67124) (xy 51.357388 -162.564971) (xy 51.343951 -162.457411) (xy 51.338522 -162.34915)
			(xy 51.341132 -162.240785) (xy 51.351765 -162.132911) (xy 51.360578 -162.079432) (xy 51.362864 -162.06597)
			(xy 51.353466 -162.040316) (xy 51.264312 -161.966656) (xy 51.237896 -161.962084) (xy 51.224942 -161.96691)
			(xy 51.173891 -161.985361) (xy 51.069222 -162.01416) (xy 50.962401 -162.033507) (xy 50.854279 -162.043245)
			(xy 50.8 -162.043872) (xy 50.752338 -162.043402) (xy 50.657308 -162.035916) (xy 50.563158 -162.020998)
			(xy 50.470469 -161.998739) (xy 50.379811 -161.969278) (xy 50.291744 -161.932795) (xy 50.206811 -161.889516)
			(xy 50.125535 -161.839706) (xy 50.048417 -161.783675) (xy 49.975932 -161.721766) (xy 49.908528 -161.654361)
			(xy 49.877218 -161.618422) (xy 49.869649 -161.610397) (xy 49.849629 -161.601183) (xy 49.83861 -161.600642)
			(xy 49.761394 -161.600642) (xy 49.750373 -161.601163) (xy 49.730356 -161.610393) (xy 49.722786 -161.618422)
			(xy 49.691484 -161.654366) (xy 49.624069 -161.721758) (xy 49.551578 -161.783656) (xy 49.474455 -161.839679)
			(xy 49.393177 -161.889481) (xy 49.308244 -161.932757) (xy 49.220179 -161.969239) (xy 49.129525 -161.998703)
			(xy 49.036839 -162.020967) (xy 48.942692 -162.035894) (xy 48.847665 -162.043393) (xy 48.800004 -162.043872)
			(xy 48.749836 -162.04339) (xy 48.649842 -162.035106) (xy 48.550873 -162.018593) (xy 48.453607 -161.993965)
			(xy 48.358705 -161.961389) (xy 48.266818 -161.921089) (xy 48.178572 -161.873339) (xy 48.09457 -161.818466)
			(xy 48.015385 -161.756844) (xy 47.94156 -161.688895) (xy 47.873597 -161.615081) (xy 47.811961 -161.535908)
			(xy 47.757072 -161.451916) (xy 47.709307 -161.363678) (xy 47.66899 -161.271798) (xy 47.636397 -161.176903)
			(xy 47.611752 -161.07964) (xy 47.595221 -160.980675) (xy 47.586919 -160.880682) (xy 47.586392 -160.830514)
			(xy 47.586392 -160.830006) (xy 47.586892 -160.78235) (xy 47.59436 -160.687331) (xy 47.609257 -160.593191)
			(xy 47.631492 -160.500509) (xy 47.660928 -160.409857) (xy 47.697384 -160.321793) (xy 47.740635 -160.236859)
			(xy 47.790414 -160.15558) (xy 47.846414 -160.078455) (xy 47.908292 -160.00596) (xy 47.975665 -159.938542)
			(xy 48.011588 -159.907224) (xy 48.019597 -159.899639) (xy 48.028824 -159.879632) (xy 48.029368 -159.868616)
			(xy 48.029368 -159.7914) (xy 48.02884 -159.78038) (xy 48.019615 -159.760363) (xy 48.011588 -159.752792)
			(xy 47.973975 -159.719956) (xy 47.903656 -159.649064) (xy 47.839399 -159.572633) (xy 47.781638 -159.491183)
			(xy 47.730764 -159.405262) (xy 47.68712 -159.315453) (xy 47.651001 -159.222361) (xy 47.622653 -159.126618)
			(xy 47.602266 -159.028868) (xy 47.589978 -158.929775) (xy 47.585872 -158.830006) (xy 38.088824 -158.830006)
			(xy 38.088824 -158.83001) (xy 38.088378 -158.877673) (xy 38.080891 -158.972704) (xy 38.065971 -159.066855)
			(xy 38.043711 -159.159545) (xy 38.014248 -159.250203) (xy 37.977763 -159.33827) (xy 37.934481 -159.423203)
			(xy 37.884669 -159.504479) (xy 37.828634 -159.581596) (xy 37.766722 -159.65408) (xy 37.699314 -159.721483)
			(xy 37.663374 -159.752792) (xy 37.655352 -159.760365) (xy 37.646134 -159.780381) (xy 37.645594 -159.7914)
			(xy 37.645594 -159.868616) (xy 37.646125 -159.879636) (xy 37.655349 -159.899652) (xy 37.663374 -159.907224)
			(xy 37.699313 -159.938533) (xy 37.766706 -160.005945) (xy 37.828605 -160.078436) (xy 37.884629 -160.155557)
			(xy 37.934433 -160.236834) (xy 37.977709 -160.321767) (xy 38.014192 -160.409831) (xy 38.043656 -160.500486)
			(xy 38.06592 -160.593171) (xy 38.080847 -160.687318) (xy 38.088345 -160.782345) (xy 38.088824 -160.830006)
			(xy 38.088376 -160.877669) (xy 38.080889 -160.9727) (xy 38.065969 -161.066851) (xy 38.043709 -161.159541)
			(xy 38.014246 -161.250199) (xy 37.977761 -161.338266) (xy 37.93448 -161.423199) (xy 37.884668 -161.504475)
			(xy 37.828634 -161.581592) (xy 37.766722 -161.654076) (xy 37.699314 -161.721479) (xy 37.663374 -161.752788)
			(xy 37.655354 -161.760363) (xy 37.646135 -161.780378) (xy 37.645594 -161.791396) (xy 37.645594 -161.868612)
			(xy 37.646127 -161.879631) (xy 37.65535 -161.899648) (xy 37.663374 -161.90722) (xy 37.699311 -161.938531)
			(xy 37.766704 -162.005943) (xy 37.828603 -162.078433) (xy 37.884627 -162.155554) (xy 37.934431 -162.236831)
			(xy 37.977708 -162.321764) (xy 38.01419 -162.409828) (xy 38.043655 -162.500482) (xy 38.065919 -162.593168)
			(xy 38.080847 -162.687314) (xy 38.088345 -162.782341) (xy 38.088824 -162.830002) (xy 38.088373 -162.877665)
			(xy 38.080886 -162.972696) (xy 38.065967 -163.066846) (xy 38.043707 -163.159536) (xy 38.014244 -163.250194)
			(xy 37.97776 -163.338261) (xy 37.934478 -163.423195) (xy 37.884667 -163.504471) (xy 37.828633 -163.581588)
			(xy 37.766721 -163.654072) (xy 37.699314 -163.721475) (xy 37.663374 -163.752784) (xy 37.655356 -163.76036)
			(xy 37.646136 -163.780374) (xy 37.645594 -163.791392) (xy 37.645594 -163.868608) (xy 37.646129 -163.879627)
			(xy 37.655351 -163.899644) (xy 37.663374 -163.907216) (xy 37.699309 -163.938529) (xy 37.766702 -164.005941)
			(xy 37.828602 -164.078431) (xy 37.884626 -164.155552) (xy 37.93443 -164.236829) (xy 37.977706 -164.321761)
			(xy 38.014189 -164.409825) (xy 38.043654 -164.500479) (xy 38.065919 -164.593164) (xy 38.080846 -164.68731)
			(xy 38.088345 -164.782337) (xy 38.088824 -164.829998) (xy 38.08837 -164.877661) (xy 38.080883 -164.972691)
			(xy 38.065965 -165.066842) (xy 38.043705 -165.159532) (xy 38.014243 -165.25019) (xy 37.977758 -165.338257)
			(xy 37.934477 -165.42319) (xy 37.884666 -165.504466) (xy 37.828632 -165.581584) (xy 37.766721 -165.654068)
			(xy 37.699314 -165.721471) (xy 37.663374 -165.75278) (xy 37.655358 -165.760358) (xy 37.646136 -165.780371)
			(xy 37.645594 -165.791388) (xy 37.645594 -165.868604) (xy 37.646131 -165.879623) (xy 37.655351 -165.899639)
			(xy 37.663374 -165.907212) (xy 37.699307 -165.938527) (xy 37.7667 -166.005939) (xy 37.8286 -166.078429)
			(xy 37.884624 -166.155549) (xy 37.934428 -166.236826) (xy 37.977705 -166.321758) (xy 38.014188 -166.409822)
			(xy 38.043653 -166.500475) (xy 38.065918 -166.593161) (xy 38.080846 -166.687307) (xy 38.088345 -166.782333)
			(xy 38.088824 -166.829994) (xy 38.088367 -166.877657) (xy 38.080881 -166.972687) (xy 38.065962 -167.066838)
			(xy 38.043703 -167.159528) (xy 38.014241 -167.250186) (xy 37.977757 -167.338253) (xy 37.934476 -167.423186)
			(xy 37.884665 -167.504462) (xy 37.828632 -167.58158) (xy 37.766721 -167.654063) (xy 37.736366 -167.684417)
			(xy 65.5137 -167.684417) (xy 65.5137 -167.575771) (xy 65.521631 -167.467414) (xy 65.53745 -167.359925)
			(xy 65.561073 -167.253878) (xy 65.592374 -167.149838) (xy 65.631186 -167.04836) (xy 65.677301 -166.949986)
			(xy 65.730475 -166.855241) (xy 65.790423 -166.76463) (xy 65.856825 -166.678636) (xy 65.929327 -166.597719)
			(xy 66.007542 -166.522311) (xy 66.091053 -166.452812) (xy 66.179414 -166.389595) (xy 66.272154 -166.332997)
			(xy 66.368778 -166.283319) (xy 66.46877 -166.240827) (xy 66.571598 -166.205747) (xy 66.676712 -166.178267)
			(xy 66.783551 -166.158532) (xy 66.891546 -166.146649) (xy 67.00012 -166.142682) (xy 67.108694 -166.146649)
			(xy 67.216689 -166.158532) (xy 67.323528 -166.178267) (xy 67.428642 -166.205747) (xy 67.53147 -166.240827)
			(xy 67.631462 -166.283319) (xy 67.728086 -166.332997) (xy 67.820826 -166.389595) (xy 67.909187 -166.452812)
			(xy 67.992698 -166.522311) (xy 68.070913 -166.597719) (xy 68.143415 -166.678636) (xy 68.209817 -166.76463)
			(xy 68.269765 -166.855241) (xy 68.322939 -166.949986) (xy 68.369054 -167.04836) (xy 68.407866 -167.149838)
			(xy 68.439167 -167.253878) (xy 68.46279 -167.359925) (xy 68.478609 -167.467414) (xy 68.48654 -167.575771)
			(xy 68.487036 -167.630094) (xy 68.48654 -167.684417) (xy 68.478609 -167.792774) (xy 68.46279 -167.900263)
			(xy 68.439167 -168.00631) (xy 68.407866 -168.11035) (xy 68.369054 -168.211828) (xy 68.322939 -168.310202)
			(xy 68.269765 -168.404947) (xy 68.209817 -168.495558) (xy 68.143415 -168.581552) (xy 68.070913 -168.662469)
			(xy 67.992698 -168.737877) (xy 67.909187 -168.807376) (xy 67.820826 -168.870593) (xy 67.728086 -168.927191)
			(xy 67.631462 -168.976869) (xy 67.53147 -169.019361) (xy 67.428642 -169.054441) (xy 67.323528 -169.081921)
			(xy 67.216689 -169.101656) (xy 67.108694 -169.113539) (xy 67.00012 -169.117507) (xy 66.891546 -169.113539)
			(xy 66.783551 -169.101656) (xy 66.676712 -169.081921) (xy 66.571598 -169.054441) (xy 66.46877 -169.019361)
			(xy 66.368778 -168.976869) (xy 66.272154 -168.927191) (xy 66.179414 -168.870593) (xy 66.091053 -168.807376)
			(xy 66.007542 -168.737877) (xy 65.929327 -168.662469) (xy 65.856825 -168.581552) (xy 65.790423 -168.495558)
			(xy 65.730475 -168.404947) (xy 65.677301 -168.310202) (xy 65.631186 -168.211828) (xy 65.592374 -168.11035)
			(xy 65.561073 -168.00631) (xy 65.53745 -167.900263) (xy 65.521631 -167.792774) (xy 65.5137 -167.684417)
			(xy 37.736366 -167.684417) (xy 37.699314 -167.721467) (xy 37.663374 -167.752776) (xy 37.655359 -167.760356)
			(xy 37.646137 -167.780367) (xy 37.645594 -167.791384) (xy 37.645594 -167.8686) (xy 37.646134 -167.879619)
			(xy 37.655352 -167.899635) (xy 37.663374 -167.907208) (xy 37.699305 -167.938525) (xy 37.766698 -168.005937)
			(xy 37.828598 -168.078427) (xy 37.884622 -168.155547) (xy 37.934426 -168.236823) (xy 37.977703 -168.321755)
			(xy 38.014187 -168.409818) (xy 38.043652 -168.500472) (xy 38.065917 -168.593157) (xy 38.080845 -168.687303)
			(xy 38.088345 -168.782329) (xy 38.088824 -168.82999) (xy 38.088352 -168.880176) (xy 38.080064 -168.980205)
			(xy 38.063544 -169.079208) (xy 38.038904 -169.176509) (xy 38.006313 -169.271442) (xy 37.965994 -169.36336)
			(xy 37.918222 -169.451634) (xy 37.863323 -169.535662) (xy 37.801672 -169.614869) (xy 37.733691 -169.688714)
			(xy 37.659844 -169.756693) (xy 37.580636 -169.818341) (xy 37.496607 -169.873238) (xy 37.408331 -169.921008)
			(xy 37.316412 -169.961325) (xy 37.221478 -169.993913) (xy 37.124177 -170.01855) (xy 37.025173 -170.035068)
			(xy 36.925144 -170.043353) (xy 36.874958 -170.043856) (xy 36.827296 -170.04335) (xy 36.732267 -170.035868)
			(xy 36.638118 -170.020954) (xy 36.545429 -169.9987) (xy 36.454772 -169.969242) (xy 36.366705 -169.932763)
			(xy 36.281772 -169.889487) (xy 36.200495 -169.839681) (xy 36.123377 -169.783652) (xy 36.050891 -169.721746)
			(xy 35.983486 -169.654343) (xy 35.952176 -169.618406) (xy 35.944611 -169.610375) (xy 35.924589 -169.601161)
			(xy 35.913568 -169.600626) (xy 35.836352 -169.600626) (xy 35.825335 -169.601184) (xy 35.805318 -169.610389)
			(xy 35.797744 -169.618406) (xy 35.766406 -169.654318) (xy 35.698996 -169.721711) (xy 35.626508 -169.783611)
			(xy 35.54939 -169.839636) (xy 35.468116 -169.889441) (xy 35.383187 -169.93272) (xy 35.295125 -169.969205)
			(xy 35.204474 -169.998672) (xy 35.111791 -170.02094) (xy 35.017647 -170.035872) (xy 34.922622 -170.043375)
			(xy 34.874962 -170.043856) (xy 34.824777 -170.043384) (xy 34.724749 -170.035093) (xy 34.625748 -170.018569)
			(xy 34.52845 -169.993927) (xy 34.433518 -169.961334) (xy 34.341603 -169.921014) (xy 34.253331 -169.87324)
			(xy 34.169305 -169.818341) (xy 34.0901 -169.75669) (xy 34.016256 -169.68871) (xy 33.948279 -169.614863)
			(xy 33.886631 -169.535656) (xy 33.831735 -169.451628) (xy 33.783965 -169.363354) (xy 33.743648 -169.271437)
			(xy 33.711059 -169.176504) (xy 33.686421 -169.079205) (xy 33.669902 -168.980203) (xy 33.661614 -168.880175)
			(xy 33.661096 -168.82999) (xy 32.074156 -168.82999) (xy 32.126179 -168.923115) (xy 32.226147 -169.085474)
			(xy 32.332915 -169.243443) (xy 32.446292 -169.396739) (xy 32.566073 -169.545084) (xy 32.692041 -169.688213)
			(xy 32.823971 -169.825866) (xy 32.961624 -169.957796) (xy 33.104753 -170.083765) (xy 33.253098 -170.203545)
			(xy 33.406394 -170.316922) (xy 33.564363 -170.423691) (xy 33.726721 -170.523659) (xy 33.893176 -170.616647)
			(xy 34.063427 -170.702486) (xy 34.237168 -170.781022) (xy 34.414086 -170.852113) (xy 34.593862 -170.915632)
			(xy 34.776171 -170.971463) (xy 34.960685 -171.019507) (xy 35.147073 -171.059677) (xy 35.334997 -171.0919)
			(xy 35.52412 -171.116118) (xy 35.7141 -171.132288) (xy 35.904595 -171.14038) (xy 35.999928 -171.140882)
		)
		(stroke
			(width 0)
			(type solid)
		)
		(fill yes)
		(layer "In6.Cu")
		(net "GND")
	)
	(gr_circle
		(center 34.874962 -168.82999)
		(end 36.088066 -168.82999)
		(stroke
			(width 0.2)
			(type default)
		)
		(fill no)
		(layer "In6.Cu")
	)
	(gr_circle
		(center 34.874962 -166.829994)
		(end 36.088066 -166.829994)
		(stroke
			(width 0.2)
			(type default)
		)
		(fill no)
		(layer "In6.Cu")
	)
	(gr_circle
		(center 34.874962 -164.829998)
		(end 36.088066 -164.829998)
		(stroke
			(width 0.2)
			(type default)
		)
		(fill no)
		(layer "In6.Cu")
	)
	(gr_circle
		(center 34.874962 -162.830002)
		(end 36.088066 -162.830002)
		(stroke
			(width 0.2)
			(type default)
		)
		(fill no)
		(layer "In6.Cu")
	)
	(gr_circle
		(center 34.874962 -160.830006)
		(end 36.088066 -160.830006)
		(stroke
			(width 0.2)
			(type default)
		)
		(fill no)
		(layer "In6.Cu")
	)
	(gr_circle
		(center 34.874962 -158.83001)
		(end 36.088066 -158.83001)
		(stroke
			(width 0.2)
			(type default)
		)
		(fill no)
		(layer "In6.Cu")
	)
	(gr_circle
		(center 34.874962 -156.830014)
		(end 36.088066 -156.830014)
		(stroke
			(width 0.2)
			(type default)
		)
		(fill no)
		(layer "In6.Cu")
	)
	(gr_circle
		(center 34.874962 -154.830018)
		(end 36.088066 -154.830018)
		(stroke
			(width 0.2)
			(type default)
		)
		(fill no)
		(layer "In6.Cu")
	)
	(gr_circle
		(center 34.874962 -152.830022)
		(end 36.088066 -152.830022)
		(stroke
			(width 0.2)
			(type default)
		)
		(fill no)
		(layer "In6.Cu")
	)
	(gr_circle
		(center 35.985958 -167.566594)
		(end 37.199062 -167.566594)
		(stroke
			(width 0.2)
			(type default)
		)
		(fill no)
		(layer "In6.Cu")
	)
	(gr_circle
		(center 35.985958 -165.566598)
		(end 37.199062 -165.566598)
		(stroke
			(width 0.2)
			(type default)
		)
		(fill no)
		(layer "In6.Cu")
	)
	(gr_circle
		(center 35.985958 -163.566602)
		(end 37.199062 -163.566602)
		(stroke
			(width 0.2)
			(type default)
		)
		(fill no)
		(layer "In6.Cu")
	)
	(gr_circle
		(center 35.985958 -161.566606)
		(end 37.199062 -161.566606)
		(stroke
			(width 0.2)
			(type default)
		)
		(fill no)
		(layer "In6.Cu")
	)
	(gr_circle
		(center 35.985958 -159.56661)
		(end 37.199062 -159.56661)
		(stroke
			(width 0.2)
			(type default)
		)
		(fill no)
		(layer "In6.Cu")
	)
	(gr_circle
		(center 35.985958 -157.566614)
		(end 37.199062 -157.566614)
		(stroke
			(width 0.2)
			(type default)
		)
		(fill no)
		(layer "In6.Cu")
	)
	(gr_circle
		(center 35.985958 -155.566618)
		(end 37.199062 -155.566618)
		(stroke
			(width 0.2)
			(type default)
		)
		(fill no)
		(layer "In6.Cu")
	)
	(gr_circle
		(center 35.985958 -153.566622)
		(end 37.199062 -153.566622)
		(stroke
			(width 0.2)
			(type default)
		)
		(fill no)
		(layer "In6.Cu")
	)
	(gr_circle
		(center 36.874958 -168.82999)
		(end 38.088062 -168.82999)
		(stroke
			(width 0.2)
			(type default)
		)
		(fill no)
		(layer "In6.Cu")
	)
	(gr_circle
		(center 36.874958 -166.829994)
		(end 38.088062 -166.829994)
		(stroke
			(width 0.2)
			(type default)
		)
		(fill no)
		(layer "In6.Cu")
	)
	(gr_circle
		(center 36.874958 -164.829998)
		(end 38.088062 -164.829998)
		(stroke
			(width 0.2)
			(type default)
		)
		(fill no)
		(layer "In6.Cu")
	)
	(gr_circle
		(center 36.874958 -162.830002)
		(end 38.088062 -162.830002)
		(stroke
			(width 0.2)
			(type default)
		)
		(fill no)
		(layer "In6.Cu")
	)
	(gr_circle
		(center 36.874958 -160.830006)
		(end 38.088062 -160.830006)
		(stroke
			(width 0.2)
			(type default)
		)
		(fill no)
		(layer "In6.Cu")
	)
	(gr_circle
		(center 36.874958 -158.83001)
		(end 38.088062 -158.83001)
		(stroke
			(width 0.2)
			(type default)
		)
		(fill no)
		(layer "In6.Cu")
	)
	(gr_circle
		(center 36.874958 -156.830014)
		(end 38.088062 -156.830014)
		(stroke
			(width 0.2)
			(type default)
		)
		(fill no)
		(layer "In6.Cu")
	)
	(gr_circle
		(center 36.874958 -154.830018)
		(end 38.088062 -154.830018)
		(stroke
			(width 0.2)
			(type default)
		)
		(fill no)
		(layer "In6.Cu")
	)
	(gr_circle
		(center 36.874958 -152.830022)
		(end 38.088062 -152.830022)
		(stroke
			(width 0.2)
			(type default)
		)
		(fill no)
		(layer "In6.Cu")
	)
	(gr_circle
		(center 42.36339 -139.7)
		(end 43.88739 -139.7)
		(stroke
			(width 0.2)
			(type default)
		)
		(fill no)
		(layer "In6.Cu")
	)
	(gr_circle
		(center 42.36339 -119.38)
		(end 43.88739 -119.38)
		(stroke
			(width 0.2)
			(type default)
		)
		(fill no)
		(layer "In6.Cu")
	)
	(gr_circle
		(center 42.36339 -99.06)
		(end 43.88739 -99.06)
		(stroke
			(width 0.2)
			(type default)
		)
		(fill no)
		(layer "In6.Cu")
	)
	(gr_circle
		(center 42.36339 -78.74)
		(end 43.88739 -78.74)
		(stroke
			(width 0.2)
			(type default)
		)
		(fill no)
		(layer "In6.Cu")
	)
	(gr_circle
		(center 42.36339 -58.42)
		(end 43.88739 -58.42)
		(stroke
			(width 0.2)
			(type default)
		)
		(fill no)
		(layer "In6.Cu")
	)
	(gr_circle
		(center 48.800004 -160.830006)
		(end 50.013108 -160.830006)
		(stroke
			(width 0.2)
			(type default)
		)
		(fill no)
		(layer "In6.Cu")
	)
	(gr_circle
		(center 48.800004 -158.83001)
		(end 50.013108 -158.83001)
		(stroke
			(width 0.2)
			(type default)
		)
		(fill no)
		(layer "In6.Cu")
	)
	(gr_circle
		(center 48.800004 -156.830014)
		(end 50.013108 -156.830014)
		(stroke
			(width 0.2)
			(type default)
		)
		(fill no)
		(layer "In6.Cu")
	)
	(gr_circle
		(center 49.9491 -159.99841)
		(end 51.162204 -159.99841)
		(stroke
			(width 0.2)
			(type default)
		)
		(fill no)
		(layer "In6.Cu")
	)
	(gr_circle
		(center 49.9491 -157.998414)
		(end 51.162204 -157.998414)
		(stroke
			(width 0.2)
			(type default)
		)
		(fill no)
		(layer "In6.Cu")
	)
	(gr_circle
		(center 50.8 -160.830006)
		(end 52.013104 -160.830006)
		(stroke
			(width 0.2)
			(type default)
		)
		(fill no)
		(layer "In6.Cu")
	)
	(gr_circle
		(center 50.8 -158.83001)
		(end 52.013104 -158.83001)
		(stroke
			(width 0.2)
			(type default)
		)
		(fill no)
		(layer "In6.Cu")
	)
	(gr_circle
		(center 50.8 -156.830014)
		(end 52.013104 -156.830014)
		(stroke
			(width 0.2)
			(type default)
		)
		(fill no)
		(layer "In6.Cu")
	)
	(gr_circle
		(center 54.799992 -160.830006)
		(end 56.013096 -160.830006)
		(stroke
			(width 0.2)
			(type default)
		)
		(fill no)
		(layer "In6.Cu")
	)
	(gr_circle
		(center 54.799992 -158.83001)
		(end 56.013096 -158.83001)
		(stroke
			(width 0.2)
			(type default)
		)
		(fill no)
		(layer "In6.Cu")
	)
	(gr_circle
		(center 54.799992 -156.830014)
		(end 56.013096 -156.830014)
		(stroke
			(width 0.2)
			(type default)
		)
		(fill no)
		(layer "In6.Cu")
	)
	(gr_circle
		(center 55.5625 -159.84601)
		(end 56.775604 -159.84601)
		(stroke
			(width 0.2)
			(type default)
		)
		(fill no)
		(layer "In6.Cu")
	)
	(gr_circle
		(center 55.5625 -157.846014)
		(end 56.775604 -157.846014)
		(stroke
			(width 0.2)
			(type default)
		)
		(fill no)
		(layer "In6.Cu")
	)
	(gr_circle
		(center 56.799988 -160.830006)
		(end 58.013092 -160.830006)
		(stroke
			(width 0.2)
			(type default)
		)
		(fill no)
		(layer "In6.Cu")
	)
	(gr_circle
		(center 56.799988 -158.83001)
		(end 58.013092 -158.83001)
		(stroke
			(width 0.2)
			(type default)
		)
		(fill no)
		(layer "In6.Cu")
	)
	(gr_circle
		(center 56.799988 -156.830014)
		(end 58.013092 -156.830014)
		(stroke
			(width 0.2)
			(type default)
		)
		(fill no)
		(layer "In6.Cu")
	)
	(gr_circle
		(center 61.92139 -139.7)
		(end 63.44539 -139.7)
		(stroke
			(width 0.2)
			(type default)
		)
		(fill no)
		(layer "In6.Cu")
	)
	(gr_circle
		(center 61.92139 -119.38)
		(end 63.44539 -119.38)
		(stroke
			(width 0.2)
			(type default)
		)
		(fill no)
		(layer "In6.Cu")
	)
	(gr_circle
		(center 61.92139 -99.06)
		(end 63.44539 -99.06)
		(stroke
			(width 0.2)
			(type default)
		)
		(fill no)
		(layer "In6.Cu")
	)
	(gr_circle
		(center 61.92139 -78.74)
		(end 63.44539 -78.74)
		(stroke
			(width 0.2)
			(type default)
		)
		(fill no)
		(layer "In6.Cu")
	)
	(gr_circle
		(center 61.92139 -58.42)
		(end 63.44539 -58.42)
		(stroke
			(width 0.2)
			(type default)
		)
		(fill no)
		(layer "In6.Cu")
	)
	(gr_circle
		(center 63.000128 -160.830006)
		(end 64.213232 -160.830006)
		(stroke
			(width 0.2)
			(type default)
		)
		(fill no)
		(layer "In6.Cu")
	)
	(gr_circle
		(center 63.000128 -158.83001)
		(end 64.213232 -158.83001)
		(stroke
			(width 0.2)
			(type default)
		)
		(fill no)
		(layer "In6.Cu")
	)
	(gr_circle
		(center 63.000128 -156.830014)
		(end 64.213232 -156.830014)
		(stroke
			(width 0.2)
			(type default)
		)
		(fill no)
		(layer "In6.Cu")
	)
	(gr_circle
		(center 63.719964 -2.590038)
		(end 64.933068 -2.590038)
		(stroke
			(width 0.2)
			(type default)
		)
		(fill no)
		(layer "In6.Cu")
	)
	(gr_circle
		(center 63.9699 -159.89681)
		(end 65.183004 -159.89681)
		(stroke
			(width 0.2)
			(type default)
		)
		(fill no)
		(layer "In6.Cu")
	)
	(gr_circle
		(center 63.9699 -157.896814)
		(end 65.183004 -157.896814)
		(stroke
			(width 0.2)
			(type default)
		)
		(fill no)
		(layer "In6.Cu")
	)
	(gr_circle
		(center 65.000124 -160.830006)
		(end 66.213228 -160.830006)
		(stroke
			(width 0.2)
			(type default)
		)
		(fill no)
		(layer "In6.Cu")
	)
	(gr_circle
		(center 65.000124 -158.83001)
		(end 66.213228 -158.83001)
		(stroke
			(width 0.2)
			(type default)
		)
		(fill no)
		(layer "In6.Cu")
	)
	(gr_circle
		(center 65.000124 -156.830014)
		(end 66.213228 -156.830014)
		(stroke
			(width 0.2)
			(type default)
		)
		(fill no)
		(layer "In6.Cu")
	)
	(gr_circle
		(center 66.259964 -2.590038)
		(end 67.473068 -2.590038)
		(stroke
			(width 0.2)
			(type default)
		)
		(fill no)
		(layer "In6.Cu")
	)
	(gr_circle
		(center 69.000116 -160.830006)
		(end 70.21322 -160.830006)
		(stroke
			(width 0.2)
			(type default)
		)
		(fill no)
		(layer "In6.Cu")
	)
	(gr_circle
		(center 69.000116 -158.83001)
		(end 70.21322 -158.83001)
		(stroke
			(width 0.2)
			(type default)
		)
		(fill no)
		(layer "In6.Cu")
	)
	(gr_circle
		(center 69.000116 -156.830014)
		(end 70.21322 -156.830014)
		(stroke
			(width 0.2)
			(type default)
		)
		(fill no)
		(layer "In6.Cu")
	)
	(gr_circle
		(center 69.8881 -159.79521)
		(end 71.101204 -159.79521)
		(stroke
			(width 0.2)
			(type default)
		)
		(fill no)
		(layer "In6.Cu")
	)
	(gr_circle
		(center 69.8881 -157.795214)
		(end 71.101204 -157.795214)
		(stroke
			(width 0.2)
			(type default)
		)
		(fill no)
		(layer "In6.Cu")
	)
	(gr_circle
		(center 71.000112 -160.830006)
		(end 72.213216 -160.830006)
		(stroke
			(width 0.2)
			(type default)
		)
		(fill no)
		(layer "In6.Cu")
	)
	(gr_circle
		(center 71.000112 -158.83001)
		(end 72.213216 -158.83001)
		(stroke
			(width 0.2)
			(type default)
		)
		(fill no)
		(layer "In6.Cu")
	)
	(gr_circle
		(center 71.000112 -156.830014)
		(end 72.213216 -156.830014)
		(stroke
			(width 0.2)
			(type default)
		)
		(fill no)
		(layer "In6.Cu")
	)
	(gr_circle
		(center 75.000104 -160.830006)
		(end 76.213208 -160.830006)
		(stroke
			(width 0.2)
			(type default)
		)
		(fill no)
		(layer "In6.Cu")
	)
	(gr_circle
		(center 75.000104 -158.83001)
		(end 76.213208 -158.83001)
		(stroke
			(width 0.2)
			(type default)
		)
		(fill no)
		(layer "In6.Cu")
	)
	(gr_circle
		(center 75.000104 -156.830014)
		(end 76.213208 -156.830014)
		(stroke
			(width 0.2)
			(type default)
		)
		(fill no)
		(layer "In6.Cu")
	)
	(gr_circle
		(center 75.8571 -159.74441)
		(end 77.070204 -159.74441)
		(stroke
			(width 0.2)
			(type default)
		)
		(fill no)
		(layer "In6.Cu")
	)
	(gr_circle
		(center 75.8571 -157.744414)
		(end 77.070204 -157.744414)
		(stroke
			(width 0.2)
			(type default)
		)
		(fill no)
		(layer "In6.Cu")
	)
	(gr_circle
		(center 77.0001 -160.830006)
		(end 78.213204 -160.830006)
		(stroke
			(width 0.2)
			(type default)
		)
		(fill no)
		(layer "In6.Cu")
	)
	(gr_circle
		(center 77.0001 -158.83001)
		(end 78.213204 -158.83001)
		(stroke
			(width 0.2)
			(type default)
		)
		(fill no)
		(layer "In6.Cu")
	)
	(gr_circle
		(center 77.0001 -156.830014)
		(end 78.213204 -156.830014)
		(stroke
			(width 0.2)
			(type default)
		)
		(fill no)
		(layer "In6.Cu")
	)
	(gr_circle
		(center 82.677 -5.334)
		(end 83.566 -5.334)
		(stroke
			(width 0.2)
			(type default)
		)
		(fill no)
		(layer "In6.Cu")
	)
	(gr_circle
		(center 82.677 -4.572)
		(end 83.566 -4.572)
		(stroke
			(width 0.2)
			(type default)
		)
		(fill no)
		(layer "In6.Cu")
	)
	(gr_circle
		(center 82.677 -3.81)
		(end 83.566 -3.81)
		(stroke
			(width 0.2)
			(type default)
		)
		(fill no)
		(layer "In6.Cu")
	)
	(gr_circle
		(center 83.439 -5.334)
		(end 84.328 -5.334)
		(stroke
			(width 0.2)
			(type default)
		)
		(fill no)
		(layer "In6.Cu")
	)
	(gr_circle
		(center 83.439 -4.572)
		(end 84.328 -4.572)
		(stroke
			(width 0.2)
			(type default)
		)
		(fill no)
		(layer "In6.Cu")
	)
	(gr_circle
		(center 83.439 -3.81)
		(end 84.328 -3.81)
		(stroke
			(width 0.2)
			(type default)
		)
		(fill no)
		(layer "In6.Cu")
	)
	(gr_circle
		(center 84.201 -5.334)
		(end 85.09 -5.334)
		(stroke
			(width 0.2)
			(type default)
		)
		(fill no)
		(layer "In6.Cu")
	)
	(gr_circle
		(center 84.201 -4.572)
		(end 85.09 -4.572)
		(stroke
			(width 0.2)
			(type default)
		)
		(fill no)
		(layer "In6.Cu")
	)
	(gr_circle
		(center 84.201 -3.81)
		(end 85.09 -3.81)
		(stroke
			(width 0.2)
			(type default)
		)
		(fill no)
		(layer "In6.Cu")
	)
	(gr_circle
		(center 84.963 -5.334)
		(end 85.852 -5.334)
		(stroke
			(width 0.2)
			(type default)
		)
		(fill no)
		(layer "In6.Cu")
	)
	(gr_circle
		(center 84.963 -4.572)
		(end 85.852 -4.572)
		(stroke
			(width 0.2)
			(type default)
		)
		(fill no)
		(layer "In6.Cu")
	)
	(gr_circle
		(center 84.963 -3.81)
		(end 85.852 -3.81)
		(stroke
			(width 0.2)
			(type default)
		)
		(fill no)
		(layer "In6.Cu")
	)
	(gr_circle
		(center 85.725 -5.334)
		(end 86.614 -5.334)
		(stroke
			(width 0.2)
			(type default)
		)
		(fill no)
		(layer "In6.Cu")
	)
	(gr_circle
		(center 85.725 -4.572)
		(end 86.614 -4.572)
		(stroke
			(width 0.2)
			(type default)
		)
		(fill no)
		(layer "In6.Cu")
	)
	(gr_circle
		(center 85.725 -3.81)
		(end 86.614 -3.81)
		(stroke
			(width 0.2)
			(type default)
		)
		(fill no)
		(layer "In6.Cu")
	)
	(gr_circle
		(center 86.487 -5.334)
		(end 87.376 -5.334)
		(stroke
			(width 0.2)
			(type default)
		)
		(fill no)
		(layer "In6.Cu")
	)
	(gr_circle
		(center 86.487 -4.572)
		(end 87.376 -4.572)
		(stroke
			(width 0.2)
			(type default)
		)
		(fill no)
		(layer "In6.Cu")
	)
	(gr_circle
		(center 86.487 -3.81)
		(end 87.376 -3.81)
		(stroke
			(width 0.2)
			(type default)
		)
		(fill no)
		(layer "In6.Cu")
	)
	(gr_circle
		(center 108.782358 -42.432224)
		(end 109.671358 -42.432224)
		(stroke
			(width 0.2)
			(type default)
		)
		(fill no)
		(layer "In6.Cu")
	)
	(gr_circle
		(center 109.374432 -53.692806)
		(end 110.263432 -53.692806)
		(stroke
			(width 0.2)
			(type default)
		)
		(fill no)
		(layer "In6.Cu")
	)
	(gr_circle
		(center 111.2774 -54.483)
		(end 112.1664 -54.483)
		(stroke
			(width 0.2)
			(type default)
		)
		(fill no)
		(layer "In6.Cu")
	)
	(gr_circle
		(center 111.2774 -43.18)
		(end 112.1664 -43.18)
		(stroke
			(width 0.2)
			(type default)
		)
		(fill no)
		(layer "In6.Cu")
	)
	(gr_circle
		(center 112.252252 -78.6638)
		(end 113.141252 -78.6638)
		(stroke
			(width 0.2)
			(type default)
		)
		(fill no)
		(layer "In6.Cu")
	)
	(gr_circle
		(center 112.252252 -67.3862)
		(end 113.141252 -67.3862)
		(stroke
			(width 0.2)
			(type default)
		)
		(fill no)
		(layer "In6.Cu")
	)
	(gr_circle
		(center 112.252252 -56.1086)
		(end 113.141252 -56.1086)
		(stroke
			(width 0.2)
			(type default)
		)
		(fill no)
		(layer "In6.Cu")
	)
	(gr_circle
		(center 112.252252 -44.831)
		(end 113.141252 -44.831)
		(stroke
			(width 0.2)
			(type default)
		)
		(fill no)
		(layer "In6.Cu")
	)
	(gr_circle
		(center 112.252252 -33.5534)
		(end 113.141252 -33.5534)
		(stroke
			(width 0.2)
			(type default)
		)
		(fill no)
		(layer "In6.Cu")
	)
	(gr_circle
		(center 112.252252 -22.2758)
		(end 113.141252 -22.2758)
		(stroke
			(width 0.2)
			(type default)
		)
		(fill no)
		(layer "In6.Cu")
	)
	(gr_circle
		(center 112.455452 -73.66)
		(end 113.344452 -73.66)
		(stroke
			(width 0.2)
			(type default)
		)
		(fill no)
		(layer "In6.Cu")
	)
	(gr_circle
		(center 112.455452 -72.898)
		(end 113.344452 -72.898)
		(stroke
			(width 0.2)
			(type default)
		)
		(fill no)
		(layer "In6.Cu")
	)
	(gr_circle
		(center 112.455452 -72.136)
		(end 113.344452 -72.136)
		(stroke
			(width 0.2)
			(type default)
		)
		(fill no)
		(layer "In6.Cu")
	)
	(gr_circle
		(center 112.455452 -71.374)
		(end 113.344452 -71.374)
		(stroke
			(width 0.2)
			(type default)
		)
		(fill no)
		(layer "In6.Cu")
	)
	(gr_circle
		(center 112.455452 -70.612)
		(end 113.344452 -70.612)
		(stroke
			(width 0.2)
			(type default)
		)
		(fill no)
		(layer "In6.Cu")
	)
	(gr_circle
		(center 112.455452 -62.3824)
		(end 113.344452 -62.3824)
		(stroke
			(width 0.2)
			(type default)
		)
		(fill no)
		(layer "In6.Cu")
	)
	(gr_circle
		(center 112.455452 -61.6204)
		(end 113.344452 -61.6204)
		(stroke
			(width 0.2)
			(type default)
		)
		(fill no)
		(layer "In6.Cu")
	)
	(gr_circle
		(center 112.455452 -60.8584)
		(end 113.344452 -60.8584)
		(stroke
			(width 0.2)
			(type default)
		)
		(fill no)
		(layer "In6.Cu")
	)
	(gr_circle
		(center 112.455452 -60.0964)
		(end 113.344452 -60.0964)
		(stroke
			(width 0.2)
			(type default)
		)
		(fill no)
		(layer "In6.Cu")
	)
	(gr_circle
		(center 112.455452 -59.3344)
		(end 113.344452 -59.3344)
		(stroke
			(width 0.2)
			(type default)
		)
		(fill no)
		(layer "In6.Cu")
	)
	(gr_circle
		(center 112.455452 -51.1048)
		(end 113.344452 -51.1048)
		(stroke
			(width 0.2)
			(type default)
		)
		(fill no)
		(layer "In6.Cu")
	)
	(gr_circle
		(center 112.455452 -50.3428)
		(end 113.344452 -50.3428)
		(stroke
			(width 0.2)
			(type default)
		)
		(fill no)
		(layer "In6.Cu")
	)
	(gr_circle
		(center 112.455452 -49.5808)
		(end 113.344452 -49.5808)
		(stroke
			(width 0.2)
			(type default)
		)
		(fill no)
		(layer "In6.Cu")
	)
	(gr_circle
		(center 112.455452 -48.8188)
		(end 113.344452 -48.8188)
		(stroke
			(width 0.2)
			(type default)
		)
		(fill no)
		(layer "In6.Cu")
	)
	(gr_circle
		(center 112.455452 -48.0568)
		(end 113.344452 -48.0568)
		(stroke
			(width 0.2)
			(type default)
		)
		(fill no)
		(layer "In6.Cu")
	)
	(gr_circle
		(center 112.455452 -39.8272)
		(end 113.344452 -39.8272)
		(stroke
			(width 0.2)
			(type default)
		)
		(fill no)
		(layer "In6.Cu")
	)
	(gr_circle
		(center 112.455452 -39.0652)
		(end 113.344452 -39.0652)
		(stroke
			(width 0.2)
			(type default)
		)
		(fill no)
		(layer "In6.Cu")
	)
	(gr_circle
		(center 112.455452 -38.3032)
		(end 113.344452 -38.3032)
		(stroke
			(width 0.2)
			(type default)
		)
		(fill no)
		(layer "In6.Cu")
	)
	(gr_circle
		(center 112.455452 -37.5412)
		(end 113.344452 -37.5412)
		(stroke
			(width 0.2)
			(type default)
		)
		(fill no)
		(layer "In6.Cu")
	)
	(gr_circle
		(center 112.455452 -36.7792)
		(end 113.344452 -36.7792)
		(stroke
			(width 0.2)
			(type default)
		)
		(fill no)
		(layer "In6.Cu")
	)
	(gr_circle
		(center 112.455452 -28.5496)
		(end 113.344452 -28.5496)
		(stroke
			(width 0.2)
			(type default)
		)
		(fill no)
		(layer "In6.Cu")
	)
	(gr_circle
		(center 112.455452 -27.7876)
		(end 113.344452 -27.7876)
		(stroke
			(width 0.2)
			(type default)
		)
		(fill no)
		(layer "In6.Cu")
	)
	(gr_circle
		(center 112.455452 -27.0256)
		(end 113.344452 -27.0256)
		(stroke
			(width 0.2)
			(type default)
		)
		(fill no)
		(layer "In6.Cu")
	)
	(gr_circle
		(center 112.455452 -26.2636)
		(end 113.344452 -26.2636)
		(stroke
			(width 0.2)
			(type default)
		)
		(fill no)
		(layer "In6.Cu")
	)
	(gr_circle
		(center 112.455452 -25.5016)
		(end 113.344452 -25.5016)
		(stroke
			(width 0.2)
			(type default)
		)
		(fill no)
		(layer "In6.Cu")
	)
	(gr_circle
		(center 112.455452 -17.272)
		(end 113.344452 -17.272)
		(stroke
			(width 0.2)
			(type default)
		)
		(fill no)
		(layer "In6.Cu")
	)
	(gr_circle
		(center 112.455452 -16.51)
		(end 113.344452 -16.51)
		(stroke
			(width 0.2)
			(type default)
		)
		(fill no)
		(layer "In6.Cu")
	)
	(gr_circle
		(center 112.455452 -15.748)
		(end 113.344452 -15.748)
		(stroke
			(width 0.2)
			(type default)
		)
		(fill no)
		(layer "In6.Cu")
	)
	(gr_circle
		(center 112.455452 -14.986)
		(end 113.344452 -14.986)
		(stroke
			(width 0.2)
			(type default)
		)
		(fill no)
		(layer "In6.Cu")
	)
	(gr_circle
		(center 112.455452 -14.224)
		(end 113.344452 -14.224)
		(stroke
			(width 0.2)
			(type default)
		)
		(fill no)
		(layer "In6.Cu")
	)
	(gr_circle
		(center 113.217452 -73.66)
		(end 114.106452 -73.66)
		(stroke
			(width 0.2)
			(type default)
		)
		(fill no)
		(layer "In6.Cu")
	)
	(gr_circle
		(center 113.217452 -72.898)
		(end 114.106452 -72.898)
		(stroke
			(width 0.2)
			(type default)
		)
		(fill no)
		(layer "In6.Cu")
	)
	(gr_circle
		(center 113.217452 -72.136)
		(end 114.106452 -72.136)
		(stroke
			(width 0.2)
			(type default)
		)
		(fill no)
		(layer "In6.Cu")
	)
	(gr_circle
		(center 113.217452 -71.374)
		(end 114.106452 -71.374)
		(stroke
			(width 0.2)
			(type default)
		)
		(fill no)
		(layer "In6.Cu")
	)
	(gr_circle
		(center 113.217452 -70.612)
		(end 114.106452 -70.612)
		(stroke
			(width 0.2)
			(type default)
		)
		(fill no)
		(layer "In6.Cu")
	)
	(gr_circle
		(center 113.217452 -62.3824)
		(end 114.106452 -62.3824)
		(stroke
			(width 0.2)
			(type default)
		)
		(fill no)
		(layer "In6.Cu")
	)
	(gr_circle
		(center 113.217452 -61.6204)
		(end 114.106452 -61.6204)
		(stroke
			(width 0.2)
			(type default)
		)
		(fill no)
		(layer "In6.Cu")
	)
	(gr_circle
		(center 113.217452 -60.8584)
		(end 114.106452 -60.8584)
		(stroke
			(width 0.2)
			(type default)
		)
		(fill no)
		(layer "In6.Cu")
	)
	(gr_circle
		(center 113.217452 -60.0964)
		(end 114.106452 -60.0964)
		(stroke
			(width 0.2)
			(type default)
		)
		(fill no)
		(layer "In6.Cu")
	)
	(gr_circle
		(center 113.217452 -59.3344)
		(end 114.106452 -59.3344)
		(stroke
			(width 0.2)
			(type default)
		)
		(fill no)
		(layer "In6.Cu")
	)
	(gr_circle
		(center 113.217452 -51.1048)
		(end 114.106452 -51.1048)
		(stroke
			(width 0.2)
			(type default)
		)
		(fill no)
		(layer "In6.Cu")
	)
	(gr_circle
		(center 113.217452 -50.3428)
		(end 114.106452 -50.3428)
		(stroke
			(width 0.2)
			(type default)
		)
		(fill no)
		(layer "In6.Cu")
	)
	(gr_circle
		(center 113.217452 -49.5808)
		(end 114.106452 -49.5808)
		(stroke
			(width 0.2)
			(type default)
		)
		(fill no)
		(layer "In6.Cu")
	)
	(gr_circle
		(center 113.217452 -48.8188)
		(end 114.106452 -48.8188)
		(stroke
			(width 0.2)
			(type default)
		)
		(fill no)
		(layer "In6.Cu")
	)
	(gr_circle
		(center 113.217452 -48.0568)
		(end 114.106452 -48.0568)
		(stroke
			(width 0.2)
			(type default)
		)
		(fill no)
		(layer "In6.Cu")
	)
	(gr_circle
		(center 113.217452 -39.8272)
		(end 114.106452 -39.8272)
		(stroke
			(width 0.2)
			(type default)
		)
		(fill no)
		(layer "In6.Cu")
	)
	(gr_circle
		(center 113.217452 -39.0652)
		(end 114.106452 -39.0652)
		(stroke
			(width 0.2)
			(type default)
		)
		(fill no)
		(layer "In6.Cu")
	)
	(gr_circle
		(center 113.217452 -38.3032)
		(end 114.106452 -38.3032)
		(stroke
			(width 0.2)
			(type default)
		)
		(fill no)
		(layer "In6.Cu")
	)
	(gr_circle
		(center 113.217452 -37.5412)
		(end 114.106452 -37.5412)
		(stroke
			(width 0.2)
			(type default)
		)
		(fill no)
		(layer "In6.Cu")
	)
	(gr_circle
		(center 113.217452 -36.7792)
		(end 114.106452 -36.7792)
		(stroke
			(width 0.2)
			(type default)
		)
		(fill no)
		(layer "In6.Cu")
	)
	(gr_circle
		(center 113.217452 -28.5496)
		(end 114.106452 -28.5496)
		(stroke
			(width 0.2)
			(type default)
		)
		(fill no)
		(layer "In6.Cu")
	)
	(gr_circle
		(center 113.217452 -27.7876)
		(end 114.106452 -27.7876)
		(stroke
			(width 0.2)
			(type default)
		)
		(fill no)
		(layer "In6.Cu")
	)
	(gr_circle
		(center 113.217452 -27.0256)
		(end 114.106452 -27.0256)
		(stroke
			(width 0.2)
			(type default)
		)
		(fill no)
		(layer "In6.Cu")
	)
	(gr_circle
		(center 113.217452 -26.2636)
		(end 114.106452 -26.2636)
		(stroke
			(width 0.2)
			(type default)
		)
		(fill no)
		(layer "In6.Cu")
	)
	(gr_circle
		(center 113.217452 -25.5016)
		(end 114.106452 -25.5016)
		(stroke
			(width 0.2)
			(type default)
		)
		(fill no)
		(layer "In6.Cu")
	)
	(gr_circle
		(center 113.217452 -17.272)
		(end 114.106452 -17.272)
		(stroke
			(width 0.2)
			(type default)
		)
		(fill no)
		(layer "In6.Cu")
	)
	(gr_circle
		(center 113.217452 -16.51)
		(end 114.106452 -16.51)
		(stroke
			(width 0.2)
			(type default)
		)
		(fill no)
		(layer "In6.Cu")
	)
	(gr_circle
		(center 113.217452 -15.748)
		(end 114.106452 -15.748)
		(stroke
			(width 0.2)
			(type default)
		)
		(fill no)
		(layer "In6.Cu")
	)
	(gr_circle
		(center 113.217452 -14.986)
		(end 114.106452 -14.986)
		(stroke
			(width 0.2)
			(type default)
		)
		(fill no)
		(layer "In6.Cu")
	)
	(gr_circle
		(center 113.217452 -14.224)
		(end 114.106452 -14.224)
		(stroke
			(width 0.2)
			(type default)
		)
		(fill no)
		(layer "In6.Cu")
	)
	(gr_circle
		(center 113.979452 -73.66)
		(end 114.868452 -73.66)
		(stroke
			(width 0.2)
			(type default)
		)
		(fill no)
		(layer "In6.Cu")
	)
	(gr_circle
		(center 113.979452 -72.898)
		(end 114.868452 -72.898)
		(stroke
			(width 0.2)
			(type default)
		)
		(fill no)
		(layer "In6.Cu")
	)
	(gr_circle
		(center 113.979452 -72.136)
		(end 114.868452 -72.136)
		(stroke
			(width 0.2)
			(type default)
		)
		(fill no)
		(layer "In6.Cu")
	)
	(gr_circle
		(center 113.979452 -71.374)
		(end 114.868452 -71.374)
		(stroke
			(width 0.2)
			(type default)
		)
		(fill no)
		(layer "In6.Cu")
	)
	(gr_circle
		(center 113.979452 -70.612)
		(end 114.868452 -70.612)
		(stroke
			(width 0.2)
			(type default)
		)
		(fill no)
		(layer "In6.Cu")
	)
	(gr_circle
		(center 113.979452 -62.3824)
		(end 114.868452 -62.3824)
		(stroke
			(width 0.2)
			(type default)
		)
		(fill no)
		(layer "In6.Cu")
	)
	(gr_circle
		(center 113.979452 -61.6204)
		(end 114.868452 -61.6204)
		(stroke
			(width 0.2)
			(type default)
		)
		(fill no)
		(layer "In6.Cu")
	)
	(gr_circle
		(center 113.979452 -60.8584)
		(end 114.868452 -60.8584)
		(stroke
			(width 0.2)
			(type default)
		)
		(fill no)
		(layer "In6.Cu")
	)
	(gr_circle
		(center 113.979452 -60.0964)
		(end 114.868452 -60.0964)
		(stroke
			(width 0.2)
			(type default)
		)
		(fill no)
		(layer "In6.Cu")
	)
	(gr_circle
		(center 113.979452 -59.3344)
		(end 114.868452 -59.3344)
		(stroke
			(width 0.2)
			(type default)
		)
		(fill no)
		(layer "In6.Cu")
	)
	(gr_circle
		(center 113.979452 -51.1048)
		(end 114.868452 -51.1048)
		(stroke
			(width 0.2)
			(type default)
		)
		(fill no)
		(layer "In6.Cu")
	)
	(gr_circle
		(center 113.979452 -50.3428)
		(end 114.868452 -50.3428)
		(stroke
			(width 0.2)
			(type default)
		)
		(fill no)
		(layer "In6.Cu")
	)
	(gr_circle
		(center 113.979452 -49.5808)
		(end 114.868452 -49.5808)
		(stroke
			(width 0.2)
			(type default)
		)
		(fill no)
		(layer "In6.Cu")
	)
	(gr_circle
		(center 113.979452 -48.8188)
		(end 114.868452 -48.8188)
		(stroke
			(width 0.2)
			(type default)
		)
		(fill no)
		(layer "In6.Cu")
	)
	(gr_circle
		(center 113.979452 -48.0568)
		(end 114.868452 -48.0568)
		(stroke
			(width 0.2)
			(type default)
		)
		(fill no)
		(layer "In6.Cu")
	)
	(gr_circle
		(center 113.979452 -39.8272)
		(end 114.868452 -39.8272)
		(stroke
			(width 0.2)
			(type default)
		)
		(fill no)
		(layer "In6.Cu")
	)
	(gr_circle
		(center 113.979452 -39.0652)
		(end 114.868452 -39.0652)
		(stroke
			(width 0.2)
			(type default)
		)
		(fill no)
		(layer "In6.Cu")
	)
	(gr_circle
		(center 113.979452 -38.3032)
		(end 114.868452 -38.3032)
		(stroke
			(width 0.2)
			(type default)
		)
		(fill no)
		(layer "In6.Cu")
	)
	(gr_circle
		(center 113.979452 -37.5412)
		(end 114.868452 -37.5412)
		(stroke
			(width 0.2)
			(type default)
		)
		(fill no)
		(layer "In6.Cu")
	)
	(gr_circle
		(center 113.979452 -36.7792)
		(end 114.868452 -36.7792)
		(stroke
			(width 0.2)
			(type default)
		)
		(fill no)
		(layer "In6.Cu")
	)
	(gr_circle
		(center 113.979452 -28.5496)
		(end 114.868452 -28.5496)
		(stroke
			(width 0.2)
			(type default)
		)
		(fill no)
		(layer "In6.Cu")
	)
	(gr_circle
		(center 113.979452 -27.7876)
		(end 114.868452 -27.7876)
		(stroke
			(width 0.2)
			(type default)
		)
		(fill no)
		(layer "In6.Cu")
	)
	(gr_circle
		(center 113.979452 -27.0256)
		(end 114.868452 -27.0256)
		(stroke
			(width 0.2)
			(type default)
		)
		(fill no)
		(layer "In6.Cu")
	)
	(gr_circle
		(center 113.979452 -26.2636)
		(end 114.868452 -26.2636)
		(stroke
			(width 0.2)
			(type default)
		)
		(fill no)
		(layer "In6.Cu")
	)
	(gr_circle
		(center 113.979452 -25.5016)
		(end 114.868452 -25.5016)
		(stroke
			(width 0.2)
			(type default)
		)
		(fill no)
		(layer "In6.Cu")
	)
	(gr_circle
		(center 113.979452 -17.272)
		(end 114.868452 -17.272)
		(stroke
			(width 0.2)
			(type default)
		)
		(fill no)
		(layer "In6.Cu")
	)
	(gr_circle
		(center 113.979452 -16.51)
		(end 114.868452 -16.51)
		(stroke
			(width 0.2)
			(type default)
		)
		(fill no)
		(layer "In6.Cu")
	)
	(gr_circle
		(center 113.979452 -15.748)
		(end 114.868452 -15.748)
		(stroke
			(width 0.2)
			(type default)
		)
		(fill no)
		(layer "In6.Cu")
	)
	(gr_circle
		(center 113.979452 -14.986)
		(end 114.868452 -14.986)
		(stroke
			(width 0.2)
			(type default)
		)
		(fill no)
		(layer "In6.Cu")
	)
	(gr_circle
		(center 113.979452 -14.224)
		(end 114.868452 -14.224)
		(stroke
			(width 0.2)
			(type default)
		)
		(fill no)
		(layer "In6.Cu")
	)
	(gr_circle
		(center 114.741452 -73.66)
		(end 115.630452 -73.66)
		(stroke
			(width 0.2)
			(type default)
		)
		(fill no)
		(layer "In6.Cu")
	)
	(gr_circle
		(center 114.741452 -72.898)
		(end 115.630452 -72.898)
		(stroke
			(width 0.2)
			(type default)
		)
		(fill no)
		(layer "In6.Cu")
	)
	(gr_circle
		(center 114.741452 -72.136)
		(end 115.630452 -72.136)
		(stroke
			(width 0.2)
			(type default)
		)
		(fill no)
		(layer "In6.Cu")
	)
	(gr_circle
		(center 114.741452 -71.374)
		(end 115.630452 -71.374)
		(stroke
			(width 0.2)
			(type default)
		)
		(fill no)
		(layer "In6.Cu")
	)
	(gr_circle
		(center 114.741452 -70.612)
		(end 115.630452 -70.612)
		(stroke
			(width 0.2)
			(type default)
		)
		(fill no)
		(layer "In6.Cu")
	)
	(gr_circle
		(center 114.741452 -62.3824)
		(end 115.630452 -62.3824)
		(stroke
			(width 0.2)
			(type default)
		)
		(fill no)
		(layer "In6.Cu")
	)
	(gr_circle
		(center 114.741452 -61.6204)
		(end 115.630452 -61.6204)
		(stroke
			(width 0.2)
			(type default)
		)
		(fill no)
		(layer "In6.Cu")
	)
	(gr_circle
		(center 114.741452 -60.8584)
		(end 115.630452 -60.8584)
		(stroke
			(width 0.2)
			(type default)
		)
		(fill no)
		(layer "In6.Cu")
	)
	(gr_circle
		(center 114.741452 -60.0964)
		(end 115.630452 -60.0964)
		(stroke
			(width 0.2)
			(type default)
		)
		(fill no)
		(layer "In6.Cu")
	)
	(gr_circle
		(center 114.741452 -59.3344)
		(end 115.630452 -59.3344)
		(stroke
			(width 0.2)
			(type default)
		)
		(fill no)
		(layer "In6.Cu")
	)
	(gr_circle
		(center 114.741452 -51.1048)
		(end 115.630452 -51.1048)
		(stroke
			(width 0.2)
			(type default)
		)
		(fill no)
		(layer "In6.Cu")
	)
	(gr_circle
		(center 114.741452 -50.3428)
		(end 115.630452 -50.3428)
		(stroke
			(width 0.2)
			(type default)
		)
		(fill no)
		(layer "In6.Cu")
	)
	(gr_circle
		(center 114.741452 -49.5808)
		(end 115.630452 -49.5808)
		(stroke
			(width 0.2)
			(type default)
		)
		(fill no)
		(layer "In6.Cu")
	)
	(gr_circle
		(center 114.741452 -48.8188)
		(end 115.630452 -48.8188)
		(stroke
			(width 0.2)
			(type default)
		)
		(fill no)
		(layer "In6.Cu")
	)
	(gr_circle
		(center 114.741452 -48.0568)
		(end 115.630452 -48.0568)
		(stroke
			(width 0.2)
			(type default)
		)
		(fill no)
		(layer "In6.Cu")
	)
	(gr_circle
		(center 114.741452 -39.8272)
		(end 115.630452 -39.8272)
		(stroke
			(width 0.2)
			(type default)
		)
		(fill no)
		(layer "In6.Cu")
	)
	(gr_circle
		(center 114.741452 -39.0652)
		(end 115.630452 -39.0652)
		(stroke
			(width 0.2)
			(type default)
		)
		(fill no)
		(layer "In6.Cu")
	)
	(gr_circle
		(center 114.741452 -38.3032)
		(end 115.630452 -38.3032)
		(stroke
			(width 0.2)
			(type default)
		)
		(fill no)
		(layer "In6.Cu")
	)
	(gr_circle
		(center 114.741452 -37.5412)
		(end 115.630452 -37.5412)
		(stroke
			(width 0.2)
			(type default)
		)
		(fill no)
		(layer "In6.Cu")
	)
	(gr_circle
		(center 114.741452 -36.7792)
		(end 115.630452 -36.7792)
		(stroke
			(width 0.2)
			(type default)
		)
		(fill no)
		(layer "In6.Cu")
	)
	(gr_circle
		(center 114.741452 -28.5496)
		(end 115.630452 -28.5496)
		(stroke
			(width 0.2)
			(type default)
		)
		(fill no)
		(layer "In6.Cu")
	)
	(gr_circle
		(center 114.741452 -27.7876)
		(end 115.630452 -27.7876)
		(stroke
			(width 0.2)
			(type default)
		)
		(fill no)
		(layer "In6.Cu")
	)
	(gr_circle
		(center 114.741452 -27.0256)
		(end 115.630452 -27.0256)
		(stroke
			(width 0.2)
			(type default)
		)
		(fill no)
		(layer "In6.Cu")
	)
	(gr_circle
		(center 114.741452 -26.2636)
		(end 115.630452 -26.2636)
		(stroke
			(width 0.2)
			(type default)
		)
		(fill no)
		(layer "In6.Cu")
	)
	(gr_circle
		(center 114.741452 -25.5016)
		(end 115.630452 -25.5016)
		(stroke
			(width 0.2)
			(type default)
		)
		(fill no)
		(layer "In6.Cu")
	)
	(gr_circle
		(center 114.741452 -17.272)
		(end 115.630452 -17.272)
		(stroke
			(width 0.2)
			(type default)
		)
		(fill no)
		(layer "In6.Cu")
	)
	(gr_circle
		(center 114.741452 -16.51)
		(end 115.630452 -16.51)
		(stroke
			(width 0.2)
			(type default)
		)
		(fill no)
		(layer "In6.Cu")
	)
	(gr_circle
		(center 114.741452 -15.748)
		(end 115.630452 -15.748)
		(stroke
			(width 0.2)
			(type default)
		)
		(fill no)
		(layer "In6.Cu")
	)
	(gr_circle
		(center 114.741452 -14.986)
		(end 115.630452 -14.986)
		(stroke
			(width 0.2)
			(type default)
		)
		(fill no)
		(layer "In6.Cu")
	)
	(gr_circle
		(center 114.741452 -14.224)
		(end 115.630452 -14.224)
		(stroke
			(width 0.2)
			(type default)
		)
		(fill no)
		(layer "In6.Cu")
	)
	(gr_circle
		(center 115.503452 -73.66)
		(end 116.392452 -73.66)
		(stroke
			(width 0.2)
			(type default)
		)
		(fill no)
		(layer "In6.Cu")
	)
	(gr_circle
		(center 115.503452 -72.898)
		(end 116.392452 -72.898)
		(stroke
			(width 0.2)
			(type default)
		)
		(fill no)
		(layer "In6.Cu")
	)
	(gr_circle
		(center 115.503452 -72.136)
		(end 116.392452 -72.136)
		(stroke
			(width 0.2)
			(type default)
		)
		(fill no)
		(layer "In6.Cu")
	)
	(gr_circle
		(center 115.503452 -71.374)
		(end 116.392452 -71.374)
		(stroke
			(width 0.2)
			(type default)
		)
		(fill no)
		(layer "In6.Cu")
	)
	(gr_circle
		(center 115.503452 -70.612)
		(end 116.392452 -70.612)
		(stroke
			(width 0.2)
			(type default)
		)
		(fill no)
		(layer "In6.Cu")
	)
	(gr_circle
		(center 115.503452 -62.3824)
		(end 116.392452 -62.3824)
		(stroke
			(width 0.2)
			(type default)
		)
		(fill no)
		(layer "In6.Cu")
	)
	(gr_circle
		(center 115.503452 -61.6204)
		(end 116.392452 -61.6204)
		(stroke
			(width 0.2)
			(type default)
		)
		(fill no)
		(layer "In6.Cu")
	)
	(gr_circle
		(center 115.503452 -60.8584)
		(end 116.392452 -60.8584)
		(stroke
			(width 0.2)
			(type default)
		)
		(fill no)
		(layer "In6.Cu")
	)
	(gr_circle
		(center 115.503452 -60.0964)
		(end 116.392452 -60.0964)
		(stroke
			(width 0.2)
			(type default)
		)
		(fill no)
		(layer "In6.Cu")
	)
	(gr_circle
		(center 115.503452 -59.3344)
		(end 116.392452 -59.3344)
		(stroke
			(width 0.2)
			(type default)
		)
		(fill no)
		(layer "In6.Cu")
	)
	(gr_circle
		(center 115.503452 -51.1048)
		(end 116.392452 -51.1048)
		(stroke
			(width 0.2)
			(type default)
		)
		(fill no)
		(layer "In6.Cu")
	)
	(gr_circle
		(center 115.503452 -50.3428)
		(end 116.392452 -50.3428)
		(stroke
			(width 0.2)
			(type default)
		)
		(fill no)
		(layer "In6.Cu")
	)
	(gr_circle
		(center 115.503452 -49.5808)
		(end 116.392452 -49.5808)
		(stroke
			(width 0.2)
			(type default)
		)
		(fill no)
		(layer "In6.Cu")
	)
	(gr_circle
		(center 115.503452 -48.8188)
		(end 116.392452 -48.8188)
		(stroke
			(width 0.2)
			(type default)
		)
		(fill no)
		(layer "In6.Cu")
	)
	(gr_circle
		(center 115.503452 -48.0568)
		(end 116.392452 -48.0568)
		(stroke
			(width 0.2)
			(type default)
		)
		(fill no)
		(layer "In6.Cu")
	)
	(gr_circle
		(center 115.503452 -39.8272)
		(end 116.392452 -39.8272)
		(stroke
			(width 0.2)
			(type default)
		)
		(fill no)
		(layer "In6.Cu")
	)
	(gr_circle
		(center 115.503452 -39.0652)
		(end 116.392452 -39.0652)
		(stroke
			(width 0.2)
			(type default)
		)
		(fill no)
		(layer "In6.Cu")
	)
	(gr_circle
		(center 115.503452 -38.3032)
		(end 116.392452 -38.3032)
		(stroke
			(width 0.2)
			(type default)
		)
		(fill no)
		(layer "In6.Cu")
	)
	(gr_circle
		(center 115.503452 -37.5412)
		(end 116.392452 -37.5412)
		(stroke
			(width 0.2)
			(type default)
		)
		(fill no)
		(layer "In6.Cu")
	)
	(gr_circle
		(center 115.503452 -36.7792)
		(end 116.392452 -36.7792)
		(stroke
			(width 0.2)
			(type default)
		)
		(fill no)
		(layer "In6.Cu")
	)
	(gr_circle
		(center 115.503452 -28.5496)
		(end 116.392452 -28.5496)
		(stroke
			(width 0.2)
			(type default)
		)
		(fill no)
		(layer "In6.Cu")
	)
	(gr_circle
		(center 115.503452 -27.7876)
		(end 116.392452 -27.7876)
		(stroke
			(width 0.2)
			(type default)
		)
		(fill no)
		(layer "In6.Cu")
	)
	(gr_circle
		(center 115.503452 -27.0256)
		(end 116.392452 -27.0256)
		(stroke
			(width 0.2)
			(type default)
		)
		(fill no)
		(layer "In6.Cu")
	)
	(gr_circle
		(center 115.503452 -26.2636)
		(end 116.392452 -26.2636)
		(stroke
			(width 0.2)
			(type default)
		)
		(fill no)
		(layer "In6.Cu")
	)
	(gr_circle
		(center 115.503452 -25.5016)
		(end 116.392452 -25.5016)
		(stroke
			(width 0.2)
			(type default)
		)
		(fill no)
		(layer "In6.Cu")
	)
	(gr_circle
		(center 115.503452 -17.272)
		(end 116.392452 -17.272)
		(stroke
			(width 0.2)
			(type default)
		)
		(fill no)
		(layer "In6.Cu")
	)
	(gr_circle
		(center 115.503452 -16.51)
		(end 116.392452 -16.51)
		(stroke
			(width 0.2)
			(type default)
		)
		(fill no)
		(layer "In6.Cu")
	)
	(gr_circle
		(center 115.503452 -15.748)
		(end 116.392452 -15.748)
		(stroke
			(width 0.2)
			(type default)
		)
		(fill no)
		(layer "In6.Cu")
	)
	(gr_circle
		(center 115.503452 -14.986)
		(end 116.392452 -14.986)
		(stroke
			(width 0.2)
			(type default)
		)
		(fill no)
		(layer "In6.Cu")
	)
	(gr_circle
		(center 115.503452 -14.224)
		(end 116.392452 -14.224)
		(stroke
			(width 0.2)
			(type default)
		)
		(fill no)
		(layer "In6.Cu")
	)
	(gr_line
		(start 122.8344 -79.883)
		(end 123.4694 -80.518)
		(stroke
			(width 1.016)
			(type default)
		)
		(layer "In6.Cu")
	)
	(gr_line
		(start 122.8344 -46.863)
		(end 122.8344 -79.883)
		(stroke
			(width 1.016)
			(type default)
		)
		(layer "In6.Cu")
	)
	(gr_line
		(start 122.8344 -46.863)
		(end 122.8344 -13.081)
		(stroke
			(width 1.016)
			(type default)
		)
		(layer "In6.Cu")
	)
	(gr_line
		(start 122.8344 -13.081)
		(end 123.4694 -12.446)
		(stroke
			(width 1.016)
			(type default)
		)
		(layer "In6.Cu")
	)
	(gr_line
		(start 123.3424 -46.355)
		(end 122.8344 -46.863)
		(stroke
			(width 1.016)
			(type default)
		)
		(layer "In6.Cu")
	)
	(gr_line
		(start 123.3424 -46.355)
		(end 122.8344 -45.847)
		(stroke
			(width 1.016)
			(type default)
		)
		(layer "In6.Cu")
	)
	(gr_line
		(start 123.4694 -80.518)
		(end 136.23925 -80.518)
		(stroke
			(width 1.016)
			(type default)
		)
		(layer "In6.Cu")
	)
	(gr_line
		(start 136.23925 -80.518)
		(end 136.86663 -79.89062)
		(stroke
			(width 1.016)
			(type default)
		)
		(layer "In6.Cu")
	)
	(gr_line
		(start 136.86663 -79.89062)
		(end 136.86663 -68.303902)
		(stroke
			(width 1.016)
			(type default)
		)
		(layer "In6.Cu")
	)
	(gr_line
		(start 136.86663 -68.303902)
		(end 137.855706 -67.314826)
		(stroke
			(width 1.016)
			(type default)
		)
		(layer "In6.Cu")
	)
	(gr_line
		(start 137.855706 -67.314826)
		(end 148.668232 -67.314826)
		(stroke
			(width 1.016)
			(type default)
		)
		(layer "In6.Cu")
	)
	(gr_line
		(start 138.049 -38.862)
		(end 139.1666 -39.9796)
		(stroke
			(width 1.016)
			(type default)
		)
		(layer "In6.Cu")
	)
	(gr_line
		(start 138.049 -33.8328)
		(end 138.049 -38.862)
		(stroke
			(width 1.016)
			(type default)
		)
		(layer "In6.Cu")
	)
	(gr_line
		(start 138.2268 -38.2524)
		(end 147.066 -38.2524)
		(stroke
			(width 1.016)
			(type default)
		)
		(layer "In6.Cu")
	)
	(gr_line
		(start 138.2268 -37.6682)
		(end 147.066 -37.6682)
		(stroke
			(width 1.016)
			(type default)
		)
		(layer "In6.Cu")
	)
	(gr_line
		(start 138.2522 -37.0586)
		(end 147.0914 -37.0586)
		(stroke
			(width 1.016)
			(type default)
		)
		(layer "In6.Cu")
	)
	(gr_line
		(start 138.2522 -34.8742)
		(end 147.0914 -34.8742)
		(stroke
			(width 1.016)
			(type default)
		)
		(layer "In6.Cu")
	)
	(gr_line
		(start 138.2776 -36.3474)
		(end 147.1168 -36.3474)
		(stroke
			(width 1.016)
			(type default)
		)
		(layer "In6.Cu")
	)
	(gr_line
		(start 138.303 -35.6616)
		(end 147.1422 -35.6616)
		(stroke
			(width 1.016)
			(type default)
		)
		(layer "In6.Cu")
	)
	(gr_line
		(start 138.34872 -33.53308)
		(end 138.049 -33.8328)
		(stroke
			(width 1.016)
			(type default)
		)
		(layer "In6.Cu")
	)
	(gr_line
		(start 138.3538 -34.2392)
		(end 147.193 -34.2392)
		(stroke
			(width 1.016)
			(type default)
		)
		(layer "In6.Cu")
	)
	(gr_line
		(start 138.3792 -38.7604)
		(end 147.2184 -38.7604)
		(stroke
			(width 1.016)
			(type default)
		)
		(layer "In6.Cu")
	)
	(gr_line
		(start 138.6078 -34.2646)
		(end 138.6078 -39.2938)
		(stroke
			(width 1.016)
			(type default)
		)
		(layer "In6.Cu")
	)
	(gr_line
		(start 139.0904 -34.5694)
		(end 139.0904 -39.5986)
		(stroke
			(width 1.016)
			(type default)
		)
		(layer "In6.Cu")
	)
	(gr_line
		(start 139.1666 -39.9796)
		(end 141.7066 -39.9796)
		(stroke
			(width 1.016)
			(type default)
		)
		(layer "In6.Cu")
	)
	(gr_line
		(start 141.7066 -39.9796)
		(end 142.6464 -40.9194)
		(stroke
			(width 1.016)
			(type default)
		)
		(layer "In6.Cu")
	)
	(gr_line
		(start 141.8844 -12.446)
		(end 142.6464 -13.208)
		(stroke
			(width 1.016)
			(type default)
		)
		(layer "In6.Cu")
	)
	(gr_line
		(start 142.3924 -46.355)
		(end 123.3424 -46.355)
		(stroke
			(width 1.016)
			(type default)
		)
		(layer "In6.Cu")
	)
	(gr_line
		(start 142.3924 -46.355)
		(end 142.6464 -46.609)
		(stroke
			(width 1.016)
			(type default)
		)
		(layer "In6.Cu")
	)
	(gr_line
		(start 142.621 -32.6644)
		(end 141.5034 -33.782)
		(stroke
			(width 1.016)
			(type default)
		)
		(layer "In6.Cu")
	)
	(gr_line
		(start 142.621 -32.6644)
		(end 143.7386 -33.782)
		(stroke
			(width 1.016)
			(type default)
		)
		(layer "In6.Cu")
	)
	(gr_line
		(start 142.6464 -47.498)
		(end 141.5288 -46.3804)
		(stroke
			(width 1.016)
			(type default)
		)
		(layer "In6.Cu")
	)
	(gr_line
		(start 142.6464 -45.1612)
		(end 141.5288 -46.2788)
		(stroke
			(width 1.016)
			(type default)
		)
		(layer "In6.Cu")
	)
	(gr_line
		(start 142.6464 -33.909)
		(end 142.6464 -67.437)
		(stroke
			(width 1.016)
			(type default)
		)
		(layer "In6.Cu")
	)
	(gr_line
		(start 142.6464 -33.53308)
		(end 138.34872 -33.53308)
		(stroke
			(width 1.016)
			(type default)
		)
		(layer "In6.Cu")
	)
	(gr_line
		(start 142.6464 -33.53308)
		(end 147.35048 -33.53308)
		(stroke
			(width 1.016)
			(type default)
		)
		(layer "In6.Cu")
	)
	(gr_line
		(start 142.6464 -13.208)
		(end 142.6464 -33.53308)
		(stroke
			(width 1.016)
			(type default)
		)
		(layer "In6.Cu")
	)
	(gr_line
		(start 143.4084 -12.446)
		(end 142.6464 -13.208)
		(stroke
			(width 1.016)
			(type default)
		)
		(layer "In6.Cu")
	)
	(gr_circle
		(center 143.533114 -76.858368)
		(end 144.422114 -76.858368)
		(stroke
			(width 0.2)
			(type default)
		)
		(fill no)
		(layer "In6.Cu")
	)
	(gr_line
		(start 143.5862 -39.9796)
		(end 142.6464 -40.9194)
		(stroke
			(width 1.016)
			(type default)
		)
		(layer "In6.Cu")
	)
	(gr_line
		(start 144.4244 -39.3192)
		(end 139.3952 -39.3192)
		(stroke
			(width 1.016)
			(type default)
		)
		(layer "In6.Cu")
	)
	(gr_circle
		(center 144.892522 -76.886308)
		(end 145.781522 -76.886308)
		(stroke
			(width 0.2)
			(type default)
		)
		(fill no)
		(layer "In6.Cu")
	)
	(gr_line
		(start 145.5928 -39.8272)
		(end 140.5636 -39.8272)
		(stroke
			(width 1.016)
			(type default)
		)
		(layer "In6.Cu")
	)
	(gr_line
		(start 146.05 -34.544)
		(end 146.05 -39.5732)
		(stroke
			(width 1.016)
			(type default)
		)
		(layer "In6.Cu")
	)
	(gr_line
		(start 146.2024 -39.4208)
		(end 141.1732 -39.4208)
		(stroke
			(width 1.016)
			(type default)
		)
		(layer "In6.Cu")
	)
	(gr_line
		(start 146.2532 -39.9796)
		(end 143.5862 -39.9796)
		(stroke
			(width 1.016)
			(type default)
		)
		(layer "In6.Cu")
	)
	(gr_line
		(start 146.6596 -34.1884)
		(end 146.6596 -39.2176)
		(stroke
			(width 1.016)
			(type default)
		)
		(layer "In6.Cu")
	)
	(gr_line
		(start 147.2692 -33.8582)
		(end 147.2692 -38.8874)
		(stroke
			(width 1.016)
			(type default)
		)
		(layer "In6.Cu")
	)
	(gr_line
		(start 147.35048 -33.53308)
		(end 147.8534 -34.036)
		(stroke
			(width 1.016)
			(type default)
		)
		(layer "In6.Cu")
	)
	(gr_line
		(start 147.8534 -38.3794)
		(end 146.2532 -39.9796)
		(stroke
			(width 1.016)
			(type default)
		)
		(layer "In6.Cu")
	)
	(gr_line
		(start 147.8534 -34.036)
		(end 147.8534 -38.3794)
		(stroke
			(width 1.016)
			(type default)
		)
		(layer "In6.Cu")
	)
	(gr_line
		(start 148.668232 -67.314826)
		(end 150.626826 -67.314826)
		(stroke
			(width 1.016)
			(type default)
		)
		(layer "In6.Cu")
	)
	(gr_line
		(start 148.668232 -67.314826)
		(end 160.357058 -55.626)
		(stroke
			(width 1.016)
			(type default)
		)
		(layer "In6.Cu")
	)
	(gr_line
		(start 149.86 -79.756)
		(end 150.114 -80.01)
		(stroke
			(width 1.016)
			(type default)
		)
		(layer "In6.Cu")
	)
	(gr_line
		(start 149.86 -76.2)
		(end 149.86 -79.756)
		(stroke
			(width 1.016)
			(type default)
		)
		(layer "In6.Cu")
	)
	(gr_line
		(start 149.987 -66.929)
		(end 149.987 -66.675)
		(stroke
			(width 1.016)
			(type default)
		)
		(layer "In6.Cu")
	)
	(gr_line
		(start 149.987 -66.675)
		(end 151.765 -64.897)
		(stroke
			(width 1.016)
			(type default)
		)
		(layer "In6.Cu")
	)
	(gr_circle
		(center 150.033736 -79.7052)
		(end 150.922736 -79.7052)
		(stroke
			(width 0.2)
			(type default)
		)
		(fill no)
		(layer "In6.Cu")
	)
	(gr_circle
		(center 150.033736 -78.9432)
		(end 150.922736 -78.9432)
		(stroke
			(width 0.2)
			(type default)
		)
		(fill no)
		(layer "In6.Cu")
	)
	(gr_line
		(start 150.114 -80.01)
		(end 151.257 -80.01)
		(stroke
			(width 1.016)
			(type default)
		)
		(layer "In6.Cu")
	)
	(gr_line
		(start 150.114 -66.802)
		(end 149.987 -66.929)
		(stroke
			(width 1.016)
			(type default)
		)
		(layer "In6.Cu")
	)
	(gr_line
		(start 150.495 -79.121)
		(end 150.749 -79.375)
		(stroke
			(width 1.016)
			(type default)
		)
		(layer "In6.Cu")
	)
	(gr_line
		(start 150.495 -76.581)
		(end 150.495 -79.121)
		(stroke
			(width 1.016)
			(type default)
		)
		(layer "In6.Cu")
	)
	(gr_line
		(start 150.622 -66.802)
		(end 150.114 -66.802)
		(stroke
			(width 1.016)
			(type default)
		)
		(layer "In6.Cu")
	)
	(gr_line
		(start 150.626826 -67.314826)
		(end 151.511 -68.199)
		(stroke
			(width 1.016)
			(type default)
		)
		(layer "In6.Cu")
	)
	(gr_line
		(start 150.749 -79.375)
		(end 151.003 -79.375)
		(stroke
			(width 1.016)
			(type default)
		)
		(layer "In6.Cu")
	)
	(gr_line
		(start 150.749 -78.613)
		(end 150.876 -78.74)
		(stroke
			(width 1.016)
			(type default)
		)
		(layer "In6.Cu")
	)
	(gr_line
		(start 150.749 -76.073)
		(end 150.749 -78.613)
		(stroke
			(width 1.016)
			(type default)
		)
		(layer "In6.Cu")
	)
	(gr_circle
		(center 150.801832 -60.917582)
		(end 151.690832 -60.917582)
		(stroke
			(width 0.2)
			(type default)
		)
		(fill no)
		(layer "In6.Cu")
	)
	(gr_line
		(start 150.876 -67.437)
		(end 151.892 -68.453)
		(stroke
			(width 1.016)
			(type default)
		)
		(layer "In6.Cu")
	)
	(gr_line
		(start 150.876 -66.421)
		(end 150.876 -67.437)
		(stroke
			(width 1.016)
			(type default)
		)
		(layer "In6.Cu")
	)
	(gr_line
		(start 151.003 -79.375)
		(end 151.257 -79.121)
		(stroke
			(width 1.016)
			(type default)
		)
		(layer "In6.Cu")
	)
	(gr_line
		(start 151.13 -75.692)
		(end 150.749 -76.073)
		(stroke
			(width 1.016)
			(type default)
		)
		(layer "In6.Cu")
	)
	(gr_line
		(start 151.257 -80.01)
		(end 151.892 -79.375)
		(stroke
			(width 1.016)
			(type default)
		)
		(layer "In6.Cu")
	)
	(gr_line
		(start 151.257 -79.121)
		(end 151.257 -75.692)
		(stroke
			(width 1.016)
			(type default)
		)
		(layer "In6.Cu")
	)
	(gr_line
		(start 151.257 -75.692)
		(end 151.13 -75.692)
		(stroke
			(width 1.016)
			(type default)
		)
		(layer "In6.Cu")
	)
	(gr_line
		(start 151.511 -74.549)
		(end 149.86 -76.2)
		(stroke
			(width 1.016)
			(type default)
		)
		(layer "In6.Cu")
	)
	(gr_line
		(start 151.511 -68.199)
		(end 151.511 -74.549)
		(stroke
			(width 1.016)
			(type default)
		)
		(layer "In6.Cu")
	)
	(gr_circle
		(center 151.563832 -60.917582)
		(end 152.452832 -60.917582)
		(stroke
			(width 0.2)
			(type default)
		)
		(fill no)
		(layer "In6.Cu")
	)
	(gr_line
		(start 151.765 -65.532)
		(end 150.876 -66.421)
		(stroke
			(width 1.016)
			(type default)
		)
		(layer "In6.Cu")
	)
	(gr_line
		(start 151.765 -64.897)
		(end 151.765 -65.532)
		(stroke
			(width 1.016)
			(type default)
		)
		(layer "In6.Cu")
	)
	(gr_line
		(start 151.892 -79.375)
		(end 151.892 -68.072)
		(stroke
			(width 1.016)
			(type default)
		)
		(layer "In6.Cu")
	)
	(gr_line
		(start 151.892 -68.453)
		(end 151.892 -64.135)
		(stroke
			(width 1.016)
			(type default)
		)
		(layer "In6.Cu")
	)
	(gr_line
		(start 151.892 -68.072)
		(end 150.622 -66.802)
		(stroke
			(width 1.016)
			(type default)
		)
		(layer "In6.Cu")
	)
	(gr_line
		(start 156.980382 -12.446)
		(end 123.4694 -12.446)
		(stroke
			(width 1.016)
			(type default)
		)
		(layer "In6.Cu")
	)
	(gr_circle
		(center 158.369 -96.266)
		(end 159.258 -96.266)
		(stroke
			(width 0.2)
			(type default)
		)
		(fill no)
		(layer "In6.Cu")
	)
	(gr_line
		(start 159.747204 -56.2356)
		(end 156.848556 -59.134248)
		(stroke
			(width 1.016)
			(type default)
		)
		(layer "In6.Cu")
	)
	(gr_line
		(start 160.357058 -55.626)
		(end 175.4124 -55.626)
		(stroke
			(width 1.016)
			(type default)
		)
		(layer "In6.Cu")
	)
	(gr_circle
		(center 160.575244 -86.084918)
		(end 161.464244 -86.084918)
		(stroke
			(width 0.2)
			(type default)
		)
		(fill no)
		(layer "In6.Cu")
	)
	(gr_line
		(start 160.6804 -27.182318)
		(end 161.946082 -28.448)
		(stroke
			(width 1.016)
			(type default)
		)
		(layer "In6.Cu")
	)
	(gr_line
		(start 160.6804 -16.146018)
		(end 156.980382 -12.446)
		(stroke
			(width 1.016)
			(type default)
		)
		(layer "In6.Cu")
	)
	(gr_line
		(start 160.6804 -16.146018)
		(end 160.6804 -27.182318)
		(stroke
			(width 1.016)
			(type default)
		)
		(layer "In6.Cu")
	)
	(gr_line
		(start 160.966658 -56.2356)
		(end 159.747204 -56.2356)
		(stroke
			(width 1.016)
			(type default)
		)
		(layer "In6.Cu")
	)
	(gr_line
		(start 160.966658 -56.2356)
		(end 160.357058 -55.626)
		(stroke
			(width 1.016)
			(type default)
		)
		(layer "In6.Cu")
	)
	(gr_line
		(start 161.946082 -28.448)
		(end 209.1944 -28.448)
		(stroke
			(width 1.016)
			(type default)
		)
		(layer "In6.Cu")
	)
	(gr_circle
		(center 166.5224 -60.3758)
		(end 167.4114 -60.3758)
		(stroke
			(width 0.2)
			(type default)
		)
		(fill no)
		(layer "In6.Cu")
	)
	(gr_circle
		(center 167.2844 -60.3758)
		(end 168.1734 -60.3758)
		(stroke
			(width 0.2)
			(type default)
		)
		(fill no)
		(layer "In6.Cu")
	)
	(gr_line
		(start 172.174662 -50.696622)
		(end 172.174662 -43.570398)
		(stroke
			(width 1.016)
			(type default)
		)
		(layer "In6.Cu")
	)
	(gr_line
		(start 172.174662 -43.570398)
		(end 173.915832 -41.829228)
		(stroke
			(width 1.016)
			(type default)
		)
		(layer "In6.Cu")
	)
	(gr_line
		(start 172.583348 -51.105308)
		(end 172.174662 -50.696622)
		(stroke
			(width 1.016)
			(type default)
		)
		(layer "In6.Cu")
	)
	(gr_line
		(start 173.915832 -41.829228)
		(end 191.747394 -41.829228)
		(stroke
			(width 1.016)
			(type default)
		)
		(layer "In6.Cu")
	)
	(gr_line
		(start 173.980348 -51.105308)
		(end 172.583348 -51.105308)
		(stroke
			(width 1.016)
			(type default)
		)
		(layer "In6.Cu")
	)
	(gr_line
		(start 174.8028 -56.2356)
		(end 160.966658 -56.2356)
		(stroke
			(width 1.016)
			(type default)
		)
		(layer "In6.Cu")
	)
	(gr_circle
		(center 174.9044 -82.296)
		(end 175.7934 -82.296)
		(stroke
			(width 0.2)
			(type default)
		)
		(fill no)
		(layer "In6.Cu")
	)
	(gr_line
		(start 175.4124 -55.626)
		(end 174.8028 -56.2356)
		(stroke
			(width 1.016)
			(type default)
		)
		(layer "In6.Cu")
	)
	(gr_line
		(start 175.4124 -55.626)
		(end 176.302162 -54.736238)
		(stroke
			(width 1.016)
			(type default)
		)
		(layer "In6.Cu")
	)
	(gr_circle
		(center 175.6664 -82.296)
		(end 176.5554 -82.296)
		(stroke
			(width 0.2)
			(type default)
		)
		(fill no)
		(layer "In6.Cu")
	)
	(gr_line
		(start 176.302162 -54.736238)
		(end 176.302162 -53.427122)
		(stroke
			(width 1.016)
			(type default)
		)
		(layer "In6.Cu")
	)
	(gr_line
		(start 176.302162 -53.427122)
		(end 173.980348 -51.105308)
		(stroke
			(width 1.016)
			(type default)
		)
		(layer "In6.Cu")
	)
	(gr_circle
		(center 177.1904 -82.296)
		(end 178.0794 -82.296)
		(stroke
			(width 0.2)
			(type default)
		)
		(fill no)
		(layer "In6.Cu")
	)
	(gr_circle
		(center 177.9524 -82.296)
		(end 178.8414 -82.296)
		(stroke
			(width 0.2)
			(type default)
		)
		(fill no)
		(layer "In6.Cu")
	)
	(gr_circle
		(center 178.87696 -46.99)
		(end 179.76596 -46.99)
		(stroke
			(width 0.2)
			(type default)
		)
		(fill no)
		(layer "In6.Cu")
	)
	(gr_line
		(start 182.1434 -50.894996)
		(end 182.1434 -50.419)
		(stroke
			(width 1.016)
			(type default)
		)
		(layer "In6.Cu")
	)
	(gr_line
		(start 182.1434 -50.419)
		(end 182.1434 -47.879)
		(stroke
			(width 1.016)
			(type default)
		)
		(layer "In6.Cu")
	)
	(gr_line
		(start 182.1434 -47.879)
		(end 182.1434 -46.609)
		(stroke
			(width 1.016)
			(type default)
		)
		(layer "In6.Cu")
	)
	(gr_line
		(start 182.1434 -46.609)
		(end 185.8264 -42.926)
		(stroke
			(width 1.016)
			(type default)
		)
		(layer "In6.Cu")
	)
	(gr_circle
		(center 182.215536 -69.4436)
		(end 183.104536 -69.4436)
		(stroke
			(width 0.2)
			(type default)
		)
		(fill no)
		(layer "In6.Cu")
	)
	(gr_line
		(start 182.815484 -51.56708)
		(end 182.1434 -50.894996)
		(stroke
			(width 1.016)
			(type default)
		)
		(layer "In6.Cu")
	)
	(gr_circle
		(center 184.8104 -68.58)
		(end 185.6994 -68.58)
		(stroke
			(width 0.2)
			(type default)
		)
		(fill no)
		(layer "In6.Cu")
	)
	(gr_circle
		(center 185.5724 -68.58)
		(end 186.4614 -68.58)
		(stroke
			(width 0.2)
			(type default)
		)
		(fill no)
		(layer "In6.Cu")
	)
	(gr_line
		(start 185.8264 -42.926)
		(end 189.847982 -42.926)
		(stroke
			(width 1.016)
			(type default)
		)
		(layer "In6.Cu")
	)
	(gr_line
		(start 189.847982 -42.926)
		(end 193.576448 -46.654466)
		(stroke
			(width 1.016)
			(type default)
		)
		(layer "In6.Cu")
	)
	(gr_line
		(start 191.747394 -41.829228)
		(end 197.797166 -47.879)
		(stroke
			(width 1.016)
			(type default)
		)
		(layer "In6.Cu")
	)
	(gr_line
		(start 193.031618 -51.56708)
		(end 182.815484 -51.56708)
		(stroke
			(width 1.016)
			(type default)
		)
		(layer "In6.Cu")
	)
	(gr_line
		(start 193.576448 -51.02225)
		(end 193.031618 -51.56708)
		(stroke
			(width 1.016)
			(type default)
		)
		(layer "In6.Cu")
	)
	(gr_line
		(start 193.576448 -47.879)
		(end 193.576448 -51.02225)
		(stroke
			(width 1.016)
			(type default)
		)
		(layer "In6.Cu")
	)
	(gr_line
		(start 193.576448 -46.654466)
		(end 193.576448 -47.879)
		(stroke
			(width 1.016)
			(type default)
		)
		(layer "In6.Cu")
	)
	(gr_line
		(start 197.797166 -47.879)
		(end 210.0834 -47.879)
		(stroke
			(width 1.016)
			(type default)
		)
		(layer "In6.Cu")
	)
	(gr_circle
		(center 208.810098 -51.049936)
		(end 210.20913 -51.049936)
		(stroke
			(width 0.2)
			(type default)
		)
		(fill no)
		(layer "In6.Cu")
	)
	(gr_line
		(start 209.1944 -28.448)
		(end 210.9724 -30.226)
		(stroke
			(width 1.016)
			(type default)
		)
		(layer "In6.Cu")
	)
	(gr_line
		(start 210.9724 -46.99)
		(end 210.0834 -47.879)
		(stroke
			(width 1.016)
			(type default)
		)
		(layer "In6.Cu")
	)
	(gr_line
		(start 210.9724 -30.226)
		(end 210.9724 -46.99)
		(stroke
			(width 1.016)
			(type default)
		)
		(layer "In6.Cu")
	)
	(gr_line
		(start 229.362 -46.99)
		(end 230.251 -47.879)
		(stroke
			(width 1.016)
			(type default)
		)
		(layer "In6.Cu")
	)
	(gr_line
		(start 229.362 -30.226)
		(end 229.362 -46.99)
		(stroke
			(width 1.016)
			(type default)
		)
		(layer "In6.Cu")
	)
	(gr_line
		(start 230.251 -47.879)
		(end 242.963954 -47.879)
		(stroke
			(width 1.016)
			(type default)
		)
		(layer "In6.Cu")
	)
	(gr_line
		(start 231.14 -28.448)
		(end 229.362 -30.226)
		(stroke
			(width 1.016)
			(type default)
		)
		(layer "In6.Cu")
	)
	(gr_circle
		(center 238.810038 -51.049936)
		(end 240.20907 -51.049936)
		(stroke
			(width 0.2)
			(type default)
		)
		(fill no)
		(layer "In6.Cu")
	)
	(gr_line
		(start 246.757952 -51.02225)
		(end 247.302782 -51.56708)
		(stroke
			(width 1.016)
			(type default)
		)
		(layer "In6.Cu")
	)
	(gr_line
		(start 246.757952 -47.879)
		(end 246.757952 -51.02225)
		(stroke
			(width 1.016)
			(type default)
		)
		(layer "In6.Cu")
	)
	(gr_line
		(start 246.757952 -46.654466)
		(end 246.757952 -47.879)
		(stroke
			(width 1.016)
			(type default)
		)
		(layer "In6.Cu")
	)
	(gr_line
		(start 246.757952 -46.654466)
		(end 250.867418 -42.545)
		(stroke
			(width 1.016)
			(type default)
		)
		(layer "In6.Cu")
	)
	(gr_line
		(start 247.302782 -51.56708)
		(end 257.518916 -51.56708)
		(stroke
			(width 1.016)
			(type default)
		)
		(layer "In6.Cu")
	)
	(gr_line
		(start 248.993406 -41.849548)
		(end 242.963954 -47.879)
		(stroke
			(width 1.016)
			(type default)
		)
		(layer "In6.Cu")
	)
	(gr_line
		(start 250.486418 -42.926)
		(end 246.757952 -46.654466)
		(stroke
			(width 1.016)
			(type default)
		)
		(layer "In6.Cu")
	)
	(gr_line
		(start 250.867418 -42.545)
		(end 256.07899 -42.545)
		(stroke
			(width 1.016)
			(type default)
		)
		(layer "In6.Cu")
	)
	(gr_line
		(start 254.508 -42.926)
		(end 250.486418 -42.926)
		(stroke
			(width 1.016)
			(type default)
		)
		(layer "In6.Cu")
	)
	(gr_line
		(start 254.508 -42.926)
		(end 258.191 -46.609)
		(stroke
			(width 1.016)
			(type default)
		)
		(layer "In6.Cu")
	)
	(gr_line
		(start 255.397 -42.926)
		(end 250.486418 -42.926)
		(stroke
			(width 1.016)
			(type default)
		)
		(layer "In6.Cu")
	)
	(gr_line
		(start 255.891538 -41.849548)
		(end 248.993406 -41.849548)
		(stroke
			(width 1.016)
			(type default)
		)
		(layer "In6.Cu")
	)
	(gr_line
		(start 256.07899 -42.545)
		(end 258.61899 -45.085)
		(stroke
			(width 1.016)
			(type default)
		)
		(layer "In6.Cu")
	)
	(gr_line
		(start 257.518916 -51.56708)
		(end 258.191 -50.894996)
		(stroke
			(width 1.016)
			(type default)
		)
		(layer "In6.Cu")
	)
	(gr_line
		(start 257.556 -45.085)
		(end 255.397 -42.926)
		(stroke
			(width 1.016)
			(type default)
		)
		(layer "In6.Cu")
	)
	(gr_line
		(start 258.191 -50.894996)
		(end 258.191 -50.419)
		(stroke
			(width 1.016)
			(type default)
		)
		(layer "In6.Cu")
	)
	(gr_line
		(start 258.191 -50.419)
		(end 258.191 -47.879)
		(stroke
			(width 1.016)
			(type default)
		)
		(layer "In6.Cu")
	)
	(gr_line
		(start 258.191 -47.879)
		(end 258.191 -46.609)
		(stroke
			(width 1.016)
			(type default)
		)
		(layer "In6.Cu")
	)
	(gr_line
		(start 258.191 -46.609)
		(end 254.508 -42.926)
		(stroke
			(width 1.016)
			(type default)
		)
		(layer "In6.Cu")
	)
	(gr_line
		(start 258.191 -46.609)
		(end 258.191 -45.72)
		(stroke
			(width 1.016)
			(type default)
		)
		(layer "In6.Cu")
	)
	(gr_line
		(start 258.191 -45.72)
		(end 257.556 -45.085)
		(stroke
			(width 1.016)
			(type default)
		)
		(layer "In6.Cu")
	)
	(gr_line
		(start 258.61899 -47.03699)
		(end 260.51383 -48.93183)
		(stroke
			(width 1.016)
			(type default)
		)
		(layer "In6.Cu")
	)
	(gr_line
		(start 258.61899 -45.085)
		(end 257.556 -45.085)
		(stroke
			(width 1.016)
			(type default)
		)
		(layer "In6.Cu")
	)
	(gr_line
		(start 258.61899 -45.085)
		(end 258.61899 -47.03699)
		(stroke
			(width 1.016)
			(type default)
		)
		(layer "In6.Cu")
	)
	(gr_line
		(start 258.61899 -44.577)
		(end 255.891538 -41.849548)
		(stroke
			(width 1.016)
			(type default)
		)
		(layer "In6.Cu")
	)
	(gr_line
		(start 259.334 -46.482)
		(end 261.239 -48.387)
		(stroke
			(width 1.27)
			(type default)
		)
		(layer "In6.Cu")
	)
	(gr_line
		(start 259.334 -45.847)
		(end 259.334 -46.482)
		(stroke
			(width 1.27)
			(type default)
		)
		(layer "In6.Cu")
	)
	(gr_line
		(start 259.461 -45.974)
		(end 259.334 -45.847)
		(stroke
			(width 1.27)
			(type default)
		)
		(layer "In6.Cu")
	)
	(gr_circle
		(center 260.2484 -46.99)
		(end 261.1374 -46.99)
		(stroke
			(width 0.2)
			(type default)
		)
		(fill no)
		(layer "In6.Cu")
	)
	(gr_line
		(start 260.35 -46.736)
		(end 261.366 -47.752)
		(stroke
			(width 1.27)
			(type default)
		)
		(layer "In6.Cu")
	)
	(gr_line
		(start 260.51383 -85.493606)
		(end 263.66343 -88.643206)
		(stroke
			(width 1.016)
			(type default)
		)
		(layer "In6.Cu")
	)
	(gr_line
		(start 260.51383 -48.93183)
		(end 260.51383 -85.493606)
		(stroke
			(width 1.016)
			(type default)
		)
		(layer "In6.Cu")
	)
	(gr_line
		(start 261.239 -85.09)
		(end 263.906 -87.757)
		(stroke
			(width 1.27)
			(type default)
		)
		(layer "In6.Cu")
	)
	(gr_line
		(start 261.239 -48.387)
		(end 261.239 -85.09)
		(stroke
			(width 1.27)
			(type default)
		)
		(layer "In6.Cu")
	)
	(gr_line
		(start 261.366 -47.752)
		(end 262.001 -47.752)
		(stroke
			(width 1.27)
			(type default)
		)
		(layer "In6.Cu")
	)
	(gr_circle
		(center 261.493 -71.5772)
		(end 262.382 -71.5772)
		(stroke
			(width 0.2)
			(type default)
		)
		(fill no)
		(layer "In6.Cu")
	)
	(gr_line
		(start 261.874 -84.455)
		(end 264.287 -86.868)
		(stroke
			(width 1.27)
			(type default)
		)
		(layer "In6.Cu")
	)
	(gr_line
		(start 261.874 -50.419)
		(end 261.874 -84.455)
		(stroke
			(width 1.27)
			(type default)
		)
		(layer "In6.Cu")
	)
	(gr_line
		(start 262.001 -50.292)
		(end 261.874 -50.419)
		(stroke
			(width 1.27)
			(type default)
		)
		(layer "In6.Cu")
	)
	(gr_line
		(start 262.001 -47.752)
		(end 262.001 -50.292)
		(stroke
			(width 1.27)
			(type default)
		)
		(layer "In6.Cu")
	)
	(gr_circle
		(center 262.255 -71.5772)
		(end 263.144 -71.5772)
		(stroke
			(width 0.2)
			(type default)
		)
		(fill no)
		(layer "In6.Cu")
	)
	(gr_line
		(start 262.255 -50.292)
		(end 262.255 -47.498)
		(stroke
			(width 1.27)
			(type default)
		)
		(layer "In6.Cu")
	)
	(gr_line
		(start 262.255 -47.498)
		(end 264.795 -47.498)
		(stroke
			(width 1.27)
			(type default)
		)
		(layer "In6.Cu")
	)
	(gr_line
		(start 262.509 -50.546)
		(end 262.255 -50.292)
		(stroke
			(width 1.27)
			(type default)
		)
		(layer "In6.Cu")
	)
	(gr_line
		(start 262.636 -49.403)
		(end 262.636 -48.768)
		(stroke
			(width 1.27)
			(type default)
		)
		(layer "In6.Cu")
	)
	(gr_line
		(start 262.636 -48.768)
		(end 263.271 -48.133)
		(stroke
			(width 1.27)
			(type default)
		)
		(layer "In6.Cu")
	)
	(gr_line
		(start 262.763 -84.328)
		(end 262.763 -51.308)
		(stroke
			(width 1.27)
			(type default)
		)
		(layer "In6.Cu")
	)
	(gr_line
		(start 262.763 -51.308)
		(end 265.176 -48.895)
		(stroke
			(width 1.27)
			(type default)
		)
		(layer "In6.Cu")
	)
	(gr_line
		(start 263.144 -49.403)
		(end 262.636 -49.403)
		(stroke
			(width 1.27)
			(type default)
		)
		(layer "In6.Cu")
	)
	(gr_line
		(start 263.525 -83.693)
		(end 263.525 -51.689)
		(stroke
			(width 1.27)
			(type default)
		)
		(layer "In6.Cu")
	)
	(gr_line
		(start 263.525 -51.689)
		(end 265.684 -49.53)
		(stroke
			(width 1.27)
			(type default)
		)
		(layer "In6.Cu")
	)
	(gr_line
		(start 263.66343 -88.643206)
		(end 278.853392 -88.643206)
		(stroke
			(width 1.016)
			(type default)
		)
		(layer "In6.Cu")
	)
	(gr_line
		(start 263.906 -87.757)
		(end 277.114 -87.757)
		(stroke
			(width 1.27)
			(type default)
		)
		(layer "In6.Cu")
	)
	(gr_line
		(start 263.906 -87.757)
		(end 278.384 -87.757)
		(stroke
			(width 1.27)
			(type default)
		)
		(layer "In6.Cu")
	)
	(gr_line
		(start 264.16 -83.185)
		(end 264.16 -52.07)
		(stroke
			(width 1.27)
			(type default)
		)
		(layer "In6.Cu")
	)
	(gr_line
		(start 264.16 -52.07)
		(end 265.938 -50.292)
		(stroke
			(width 1.27)
			(type default)
		)
		(layer "In6.Cu")
	)
	(gr_line
		(start 264.287 -86.868)
		(end 276.733 -86.868)
		(stroke
			(width 1.27)
			(type default)
		)
		(layer "In6.Cu")
	)
	(gr_line
		(start 264.414 -85.979)
		(end 262.763 -84.328)
		(stroke
			(width 1.27)
			(type default)
		)
		(layer "In6.Cu")
	)
	(gr_line
		(start 264.696702 -82.761074)
		(end 264.696702 -52.959)
		(stroke
			(width 1.016)
			(type default)
		)
		(layer "In6.Cu")
	)
	(gr_line
		(start 264.696702 -52.959)
		(end 266.41679 -51.238912)
		(stroke
			(width 1.016)
			(type default)
		)
		(layer "In6.Cu")
	)
	(gr_line
		(start 264.795 -47.498)
		(end 264.922 -47.625)
		(stroke
			(width 1.27)
			(type default)
		)
		(layer "In6.Cu")
	)
	(gr_line
		(start 264.922 -47.625)
		(end 263.144 -49.403)
		(stroke
			(width 1.27)
			(type default)
		)
		(layer "In6.Cu")
	)
	(gr_line
		(start 265.049 -48.006)
		(end 262.509 -50.546)
		(stroke
			(width 1.27)
			(type default)
		)
		(layer "In6.Cu")
	)
	(gr_line
		(start 265.176 -85.344)
		(end 263.525 -83.693)
		(stroke
			(width 1.27)
			(type default)
		)
		(layer "In6.Cu")
	)
	(gr_line
		(start 265.176 -48.895)
		(end 269.24 -48.895)
		(stroke
			(width 1.27)
			(type default)
		)
		(layer "In6.Cu")
	)
	(gr_circle
		(center 265.4046 -70.7644)
		(end 266.2936 -70.7644)
		(stroke
			(width 0.2)
			(type default)
		)
		(fill no)
		(layer "In6.Cu")
	)
	(gr_line
		(start 265.684 -84.709)
		(end 264.16 -83.185)
		(stroke
			(width 1.27)
			(type default)
		)
		(layer "In6.Cu")
	)
	(gr_line
		(start 265.684 -49.53)
		(end 270.637 -49.53)
		(stroke
			(width 1.27)
			(type default)
		)
		(layer "In6.Cu")
	)
	(gr_line
		(start 265.824716 -83.889088)
		(end 264.696702 -82.761074)
		(stroke
			(width 1.016)
			(type default)
		)
		(layer "In6.Cu")
	)
	(gr_line
		(start 265.938 -50.292)
		(end 272.796 -50.292)
		(stroke
			(width 1.27)
			(type default)
		)
		(layer "In6.Cu")
	)
	(gr_line
		(start 266.41679 -51.238912)
		(end 274.733512 -51.238912)
		(stroke
			(width 1.016)
			(type default)
		)
		(layer "In6.Cu")
	)
	(gr_line
		(start 267.97 -46.736)
		(end 260.35 -46.736)
		(stroke
			(width 1.27)
			(type default)
		)
		(layer "In6.Cu")
	)
	(gr_line
		(start 268.097 -44.577)
		(end 258.61899 -44.577)
		(stroke
			(width 1.016)
			(type default)
		)
		(layer "In6.Cu")
	)
	(gr_line
		(start 268.224 -45.974)
		(end 259.461 -45.974)
		(stroke
			(width 1.27)
			(type default)
		)
		(layer "In6.Cu")
	)
	(gr_line
		(start 268.351 -48.006)
		(end 265.049 -48.006)
		(stroke
			(width 1.27)
			(type default)
		)
		(layer "In6.Cu")
	)
	(gr_line
		(start 268.5796 -45.085)
		(end 258.61899 -45.085)
		(stroke
			(width 1.016)
			(type default)
		)
		(layer "In6.Cu")
	)
	(gr_line
		(start 269.24 -48.895)
		(end 268.351 -48.006)
		(stroke
			(width 1.27)
			(type default)
		)
		(layer "In6.Cu")
	)
	(gr_circle
		(center 269.6464 -57.912)
		(end 270.5354 -57.912)
		(stroke
			(width 0.2)
			(type default)
		)
		(fill no)
		(layer "In6.Cu")
	)
	(gr_circle
		(center 270.0782 -86.233)
		(end 270.9672 -86.233)
		(stroke
			(width 0.2)
			(type default)
		)
		(fill no)
		(layer "In6.Cu")
	)
	(gr_circle
		(center 270.4084 -57.912)
		(end 271.2974 -57.912)
		(stroke
			(width 0.2)
			(type default)
		)
		(fill no)
		(layer "In6.Cu")
	)
	(gr_line
		(start 270.637 -49.53)
		(end 270.764 -49.657)
		(stroke
			(width 1.27)
			(type default)
		)
		(layer "In6.Cu")
	)
	(gr_circle
		(center 270.7132 -86.233)
		(end 271.6022 -86.233)
		(stroke
			(width 0.2)
			(type default)
		)
		(fill no)
		(layer "In6.Cu")
	)
	(gr_line
		(start 270.764 -49.657)
		(end 270.764 -49.53)
		(stroke
			(width 1.27)
			(type default)
		)
		(layer "In6.Cu")
	)
	(gr_line
		(start 270.764 -49.53)
		(end 267.97 -46.736)
		(stroke
			(width 1.27)
			(type default)
		)
		(layer "In6.Cu")
	)
	(gr_circle
		(center 271.9324 -57.912)
		(end 272.8214 -57.912)
		(stroke
			(width 0.2)
			(type default)
		)
		(fill no)
		(layer "In6.Cu")
	)
	(gr_circle
		(center 272.1102 -86.233)
		(end 272.9992 -86.233)
		(stroke
			(width 0.2)
			(type default)
		)
		(fill no)
		(layer "In6.Cu")
	)
	(gr_circle
		(center 272.6944 -57.912)
		(end 273.5834 -57.912)
		(stroke
			(width 0.2)
			(type default)
		)
		(fill no)
		(layer "In6.Cu")
	)
	(gr_circle
		(center 272.7452 -86.233)
		(end 273.6342 -86.233)
		(stroke
			(width 0.2)
			(type default)
		)
		(fill no)
		(layer "In6.Cu")
	)
	(gr_line
		(start 272.796 -50.292)
		(end 273.304 -50.8)
		(stroke
			(width 1.27)
			(type default)
		)
		(layer "In6.Cu")
	)
	(gr_line
		(start 273.05 -50.8)
		(end 268.224 -45.974)
		(stroke
			(width 1.27)
			(type default)
		)
		(layer "In6.Cu")
	)
	(gr_line
		(start 273.304 -50.8)
		(end 273.05 -50.8)
		(stroke
			(width 1.27)
			(type default)
		)
		(layer "In6.Cu")
	)
	(gr_circle
		(center 274.1422 -86.233)
		(end 275.0312 -86.233)
		(stroke
			(width 0.2)
			(type default)
		)
		(fill no)
		(layer "In6.Cu")
	)
	(gr_line
		(start 274.733512 -51.238912)
		(end 268.5796 -45.085)
		(stroke
			(width 1.016)
			(type default)
		)
		(layer "In6.Cu")
	)
	(gr_circle
		(center 274.7772 -86.233)
		(end 275.6662 -86.233)
		(stroke
			(width 0.2)
			(type default)
		)
		(fill no)
		(layer "In6.Cu")
	)
	(gr_circle
		(center 276.0472 -86.233)
		(end 276.9362 -86.233)
		(stroke
			(width 0.2)
			(type default)
		)
		(fill no)
		(layer "In6.Cu")
	)
	(gr_circle
		(center 276.6822 -86.233)
		(end 277.5712 -86.233)
		(stroke
			(width 0.2)
			(type default)
		)
		(fill no)
		(layer "In6.Cu")
	)
	(gr_line
		(start 276.733 -86.868)
		(end 277.241 -86.36)
		(stroke
			(width 1.27)
			(type default)
		)
		(layer "In6.Cu")
	)
	(gr_line
		(start 276.86 -85.979)
		(end 264.414 -85.979)
		(stroke
			(width 1.27)
			(type default)
		)
		(layer "In6.Cu")
	)
	(gr_line
		(start 277.114 -87.757)
		(end 278.003 -86.868)
		(stroke
			(width 1.27)
			(type default)
		)
		(layer "In6.Cu")
	)
	(gr_line
		(start 277.241 -86.36)
		(end 276.86 -85.979)
		(stroke
			(width 1.27)
			(type default)
		)
		(layer "In6.Cu")
	)
	(gr_line
		(start 277.876 -85.344)
		(end 265.176 -85.344)
		(stroke
			(width 1.27)
			(type default)
		)
		(layer "In6.Cu")
	)
	(gr_line
		(start 278.003 -86.868)
		(end 278.003 -85.471)
		(stroke
			(width 1.27)
			(type default)
		)
		(layer "In6.Cu")
	)
	(gr_line
		(start 278.003 -85.471)
		(end 277.876 -85.344)
		(stroke
			(width 1.27)
			(type default)
		)
		(layer "In6.Cu")
	)
	(gr_line
		(start 278.213566 -85.260434)
		(end 277.876 -85.598)
		(stroke
			(width 0.508)
			(type default)
		)
		(layer "In6.Cu")
	)
	(gr_line
		(start 278.384 -87.757)
		(end 278.892 -87.249)
		(stroke
			(width 1.27)
			(type default)
		)
		(layer "In6.Cu")
	)
	(gr_line
		(start 278.388318 -28.448)
		(end 231.14 -28.448)
		(stroke
			(width 1.016)
			(type default)
		)
		(layer "In6.Cu")
	)
	(gr_line
		(start 278.638 -84.709)
		(end 265.684 -84.709)
		(stroke
			(width 1.27)
			(type default)
		)
		(layer "In6.Cu")
	)
	(gr_line
		(start 278.853392 -88.643206)
		(end 279.653238 -87.84336)
		(stroke
			(width 1.016)
			(type default)
		)
		(layer "In6.Cu")
	)
	(gr_line
		(start 278.892 -87.249)
		(end 278.892 -84.963)
		(stroke
			(width 1.27)
			(type default)
		)
		(layer "In6.Cu")
	)
	(gr_line
		(start 278.892 -84.963)
		(end 278.638 -84.709)
		(stroke
			(width 1.27)
			(type default)
		)
		(layer "In6.Cu")
	)
	(gr_line
		(start 278.892 -84.455)
		(end 278.554434 -84.792566)
		(stroke
			(width 0.508)
			(type default)
		)
		(layer "In6.Cu")
	)
	(gr_line
		(start 278.975566 -84.244434)
		(end 278.638 -84.582)
		(stroke
			(width 0.508)
			(type default)
		)
		(layer "In6.Cu")
	)
	(gr_line
		(start 279.229566 -84.625434)
		(end 278.892 -84.963)
		(stroke
			(width 0.508)
			(type default)
		)
		(layer "In6.Cu")
	)
	(gr_line
		(start 279.229566 -83.889088)
		(end 265.824716 -83.889088)
		(stroke
			(width 1.016)
			(type default)
		)
		(layer "In6.Cu")
	)
	(gr_line
		(start 279.229566 -83.889088)
		(end 279.229566 -84.625434)
		(stroke
			(width 0.508)
			(type default)
		)
		(layer "In6.Cu")
	)
	(gr_line
		(start 279.653238 -87.84336)
		(end 279.653238 -84.31276)
		(stroke
			(width 1.016)
			(type default)
		)
		(layer "In6.Cu")
	)
	(gr_line
		(start 279.653238 -84.31276)
		(end 279.229566 -83.889088)
		(stroke
			(width 1.016)
			(type default)
		)
		(layer "In6.Cu")
	)
	(gr_line
		(start 279.654 -27.182318)
		(end 278.388318 -28.448)
		(stroke
			(width 1.016)
			(type default)
		)
		(layer "In6.Cu")
	)
	(gr_line
		(start 279.654 -16.146018)
		(end 279.654 -27.182318)
		(stroke
			(width 1.016)
			(type default)
		)
		(layer "In6.Cu")
	)
	(gr_line
		(start 279.764998 -84.201)
		(end 279.653238 -84.31276)
		(stroke
			(width 0.508)
			(type default)
		)
		(layer "In6.Cu")
	)
	(gr_line
		(start 279.764998 -84.201)
		(end 280.714958 -85.15096)
		(stroke
			(width 0.508)
			(type default)
		)
		(layer "In6.Cu")
	)
	(gr_line
		(start 280.289 -85.4964)
		(end 279.908 -85.8774)
		(stroke
			(width 0.508)
			(type default)
		)
		(layer "In6.Cu")
	)
	(gr_circle
		(center 280.329894 -78.1558)
		(end 281.218894 -78.1558)
		(stroke
			(width 0.2)
			(type default)
		)
		(fill no)
		(layer "In6.Cu")
	)
	(gr_line
		(start 280.714958 -85.15096)
		(end 281.74696 -85.15096)
		(stroke
			(width 0.508)
			(type default)
		)
		(layer "In6.Cu")
	)
	(gr_circle
		(center 281.091894 -78.1558)
		(end 281.980894 -78.1558)
		(stroke
			(width 0.2)
			(type default)
		)
		(fill no)
		(layer "In6.Cu")
	)
	(gr_line
		(start 281.74696 -85.15096)
		(end 278.06904 -85.15096)
		(stroke
			(width 1.016)
			(type default)
		)
		(layer "In6.Cu")
	)
	(gr_line
		(start 282.0162 -88.38184)
		(end 282.0162 -87.26424)
		(stroke
			(width 0.254)
			(type default)
		)
		(layer "In6.Cu")
	)
	(gr_line
		(start 282.0162 -87.26424)
		(end 283.3878 -87.26424)
		(stroke
			(width 0.254)
			(type default)
		)
		(layer "In6.Cu")
	)
	(gr_line
		(start 282.2448 -87.4014)
		(end 282.2448 -88.2396)
		(stroke
			(width 0.508)
			(type default)
		)
		(layer "In6.Cu")
	)
	(gr_line
		(start 282.2448 -58.7248)
		(end 268.097 -44.577)
		(stroke
			(width 1.016)
			(type default)
		)
		(layer "In6.Cu")
	)
	(gr_line
		(start 282.2702 -88.1634)
		(end 283.1084 -88.1634)
		(stroke
			(width 0.508)
			(type default)
		)
		(layer "In6.Cu")
	)
	(gr_line
		(start 282.2702 -87.4776)
		(end 283.1084 -87.4776)
		(stroke
			(width 0.508)
			(type default)
		)
		(layer "In6.Cu")
	)
	(gr_line
		(start 282.5242 -86.9442)
		(end 282.1432 -87.3252)
		(stroke
			(width 0.508)
			(type default)
		)
		(layer "In6.Cu")
	)
	(gr_line
		(start 282.6258 -87.2998)
		(end 282.6258 -88.138)
		(stroke
			(width 0.508)
			(type default)
		)
		(layer "In6.Cu")
	)
	(gr_line
		(start 282.702 -87.82304)
		(end 282.702 -86.106)
		(stroke
			(width 1.016)
			(type default)
		)
		(layer "In6.Cu")
	)
	(gr_line
		(start 282.702 -86.106)
		(end 281.74696 -85.15096)
		(stroke
			(width 1.016)
			(type default)
		)
		(layer "In6.Cu")
	)
	(gr_line
		(start 283.0322 -87.376)
		(end 283.0322 -88.2142)
		(stroke
			(width 0.508)
			(type default)
		)
		(layer "In6.Cu")
	)
	(gr_line
		(start 283.2608 -87.3252)
		(end 282.8798 -86.9442)
		(stroke
			(width 0.508)
			(type default)
		)
		(layer "In6.Cu")
	)
	(gr_line
		(start 283.354018 -12.446)
		(end 279.654 -16.146018)
		(stroke
			(width 1.016)
			(type default)
		)
		(layer "In6.Cu")
	)
	(gr_line
		(start 283.3878 -88.38184)
		(end 282.0162 -88.38184)
		(stroke
			(width 0.254)
			(type default)
		)
		(layer "In6.Cu")
	)
	(gr_line
		(start 283.3878 -87.26424)
		(end 283.3878 -88.38184)
		(stroke
			(width 0.254)
			(type default)
		)
		(layer "In6.Cu")
	)
	(gr_line
		(start 293.4208 -58.7248)
		(end 282.2448 -58.7248)
		(stroke
			(width 1.016)
			(type default)
		)
		(layer "In6.Cu")
	)
	(gr_line
		(start 296.7228 -65.7098)
		(end 296.7228 -62.0268)
		(stroke
			(width 1.016)
			(type default)
		)
		(layer "In6.Cu")
	)
	(gr_line
		(start 296.7228 -62.0268)
		(end 293.4208 -58.7248)
		(stroke
			(width 1.016)
			(type default)
		)
		(layer "In6.Cu")
	)
	(gr_circle
		(center 297.9928 -80.391)
		(end 298.8818 -80.391)
		(stroke
			(width 0.2)
			(type default)
		)
		(fill no)
		(layer "In6.Cu")
	)
	(gr_circle
		(center 298.069 -75.819)
		(end 298.958 -75.819)
		(stroke
			(width 0.2)
			(type default)
		)
		(fill no)
		(layer "In6.Cu")
	)
	(gr_line
		(start 298.35729 -67.34429)
		(end 296.7228 -65.7098)
		(stroke
			(width 1.016)
			(type default)
		)
		(layer "In6.Cu")
	)
	(gr_circle
		(center 298.7548 -80.391)
		(end 299.6438 -80.391)
		(stroke
			(width 0.2)
			(type default)
		)
		(fill no)
		(layer "In6.Cu")
	)
	(gr_line
		(start 299.168312 -38.996112)
		(end 300.6852 -40.513)
		(stroke
			(width 1.016)
			(type default)
		)
		(layer "In6.Cu")
	)
	(gr_line
		(start 299.168312 -33.576768)
		(end 299.168312 -38.996112)
		(stroke
			(width 1.016)
			(type default)
		)
		(layer "In6.Cu")
	)
	(gr_line
		(start 299.265086 -33.479994)
		(end 299.168312 -33.576768)
		(stroke
			(width 1.016)
			(type default)
		)
		(layer "In6.Cu")
	)
	(gr_line
		(start 300.446694 -34.461958)
		(end 300.126654 -34.781998)
		(stroke
			(width 2.54)
			(type default)
		)
		(layer "In6.Cu")
	)
	(gr_line
		(start 300.6852 -40.513)
		(end 303.4792 -40.513)
		(stroke
			(width 1.016)
			(type default)
		)
		(layer "In6.Cu")
	)
	(gr_line
		(start 302.078136 -36.06165)
		(end 301.822104 -36.317682)
		(stroke
			(width 2.54)
			(type default)
		)
		(layer "In6.Cu")
	)
	(gr_line
		(start 303.101756 -37.821108)
		(end 303.069752 -37.853112)
		(stroke
			(width 2.54)
			(type default)
		)
		(layer "In6.Cu")
	)
	(gr_line
		(start 303.391316 -40.2844)
		(end 305.5366 -40.2844)
		(stroke
			(width 1.016)
			(type default)
		)
		(layer "In6.Cu")
	)
	(gr_line
		(start 303.4792 -40.513)
		(end 304.8 -41.8338)
		(stroke
			(width 1.016)
			(type default)
		)
		(layer "In6.Cu")
	)
	(gr_line
		(start 304.038 -12.446)
		(end 304.8 -13.208)
		(stroke
			(width 1.016)
			(type default)
		)
		(layer "In6.Cu")
	)
	(gr_circle
		(center 304.070258 -79.823056)
		(end 304.959258 -79.823056)
		(stroke
			(width 0.2)
			(type default)
		)
		(fill no)
		(layer "In6.Cu")
	)
	(gr_line
		(start 304.546 -39.053516)
		(end 304.546 -41.1988)
		(stroke
			(width 1.016)
			(type default)
		)
		(layer "In6.Cu")
	)
	(gr_line
		(start 304.779934 -32.938466)
		(end 303.7586 -33.9598)
		(stroke
			(width 1.016)
			(type default)
		)
		(layer "In6.Cu")
	)
	(gr_line
		(start 304.794666 -32.938466)
		(end 305.816 -33.9598)
		(stroke
			(width 1.016)
			(type default)
		)
		(layer "In6.Cu")
	)
	(gr_line
		(start 304.8 -67.065144)
		(end 305.079146 -67.34429)
		(stroke
			(width 1.016)
			(type default)
		)
		(layer "In6.Cu")
	)
	(gr_line
		(start 304.8 -33.909)
		(end 304.8 -67.065144)
		(stroke
			(width 1.016)
			(type default)
		)
		(layer "In6.Cu")
	)
	(gr_line
		(start 304.8 -33.479994)
		(end 299.265086 -33.479994)
		(stroke
			(width 1.016)
			(type default)
		)
		(layer "In6.Cu")
	)
	(gr_line
		(start 304.8 -33.479994)
		(end 309.723028 -33.479994)
		(stroke
			(width 1.016)
			(type default)
		)
		(layer "In6.Cu")
	)
	(gr_line
		(start 304.8 -13.208)
		(end 304.8 -33.479994)
		(stroke
			(width 1.016)
			(type default)
		)
		(layer "In6.Cu")
	)
	(gr_line
		(start 304.824638 -66.421762)
		(end 303.911 -67.3354)
		(stroke
			(width 1.016)
			(type default)
		)
		(layer "In6.Cu")
	)
	(gr_line
		(start 304.826162 -66.396362)
		(end 305.7398 -67.31)
		(stroke
			(width 1.016)
			(type default)
		)
		(layer "In6.Cu")
	)
	(gr_circle
		(center 305.063398 -81.003648)
		(end 305.952398 -81.003648)
		(stroke
			(width 0.2)
			(type default)
		)
		(fill no)
		(layer "In6.Cu")
	)
	(gr_line
		(start 305.562 -12.446)
		(end 304.8 -13.208)
		(stroke
			(width 1.016)
			(type default)
		)
		(layer "In6.Cu")
	)
	(gr_line
		(start 305.6128 -40.513)
		(end 304.8 -41.3258)
		(stroke
			(width 1.016)
			(type default)
		)
		(layer "In6.Cu")
	)
	(gr_line
		(start 305.6636 -46.2534)
		(end 304.8508 -45.4406)
		(stroke
			(width 1.016)
			(type default)
		)
		(layer "In6.Cu")
	)
	(gr_line
		(start 306.076858 -37.821108)
		(end 303.101756 -37.821108)
		(stroke
			(width 2.54)
			(type default)
		)
		(layer "In6.Cu")
	)
	(gr_line
		(start 306.17287 -37.91712)
		(end 306.076858 -37.821108)
		(stroke
			(width 2.54)
			(type default)
		)
		(layer "In6.Cu")
	)
	(gr_line
		(start 307.388514 -36.06165)
		(end 302.078136 -36.06165)
		(stroke
			(width 2.54)
			(type default)
		)
		(layer "In6.Cu")
	)
	(gr_line
		(start 307.836316 -36.509452)
		(end 307.388514 -36.06165)
		(stroke
			(width 2.54)
			(type default)
		)
		(layer "In6.Cu")
	)
	(gr_line
		(start 308.3052 -37.5412)
		(end 300.083728 -37.5412)
		(stroke
			(width 2.54)
			(type default)
		)
		(layer "In6.Cu")
	)
	(gr_line
		(start 308.3306 -36.068)
		(end 300.109128 -36.068)
		(stroke
			(width 2.54)
			(type default)
		)
		(layer "In6.Cu")
	)
	(gr_line
		(start 308.5592 -38.7858)
		(end 300.337728 -38.7858)
		(stroke
			(width 2.54)
			(type default)
		)
		(layer "In6.Cu")
	)
	(gr_line
		(start 308.668166 -34.461958)
		(end 300.446694 -34.461958)
		(stroke
			(width 2.54)
			(type default)
		)
		(layer "In6.Cu")
	)
	(gr_line
		(start 309.1688 -39.2938)
		(end 300.947328 -39.2938)
		(stroke
			(width 2.54)
			(type default)
		)
		(layer "In6.Cu")
	)
	(gr_line
		(start 309.2704 -40.513)
		(end 305.6128 -40.513)
		(stroke
			(width 1.016)
			(type default)
		)
		(layer "In6.Cu")
	)
	(gr_line
		(start 309.448962 -34.323528)
		(end 309.448962 -38.861238)
		(stroke
			(width 1.016)
			(type default)
		)
		(layer "In6.Cu")
	)
	(gr_line
		(start 309.627778 -35.42157)
		(end 308.668166 -34.461958)
		(stroke
			(width 2.54)
			(type default)
		)
		(layer "In6.Cu")
	)
	(gr_line
		(start 309.723028 -33.479994)
		(end 310.744362 -34.501328)
		(stroke
			(width 1.016)
			(type default)
		)
		(layer "In6.Cu")
	)
	(gr_line
		(start 309.804562 -34.425128)
		(end 309.804562 -38.962838)
		(stroke
			(width 1.016)
			(type default)
		)
		(layer "In6.Cu")
	)
	(gr_line
		(start 309.808372 -67.34429)
		(end 298.35729 -67.34429)
		(stroke
			(width 1.016)
			(type default)
		)
		(layer "In6.Cu")
	)
	(gr_line
		(start 309.808372 -67.34429)
		(end 310.72201 -68.257928)
		(stroke
			(width 1.016)
			(type default)
		)
		(layer "In6.Cu")
	)
	(gr_line
		(start 310.236362 -34.501328)
		(end 310.236362 -39.039038)
		(stroke
			(width 1.016)
			(type default)
		)
		(layer "In6.Cu")
	)
	(gr_line
		(start 310.72201 -79.844646)
		(end 311.395364 -80.518)
		(stroke
			(width 1.016)
			(type default)
		)
		(layer "In6.Cu")
	)
	(gr_line
		(start 310.72201 -68.257928)
		(end 310.72201 -79.844646)
		(stroke
			(width 1.016)
			(type default)
		)
		(layer "In6.Cu")
	)
	(gr_line
		(start 310.744362 -39.039038)
		(end 309.2704 -40.513)
		(stroke
			(width 1.016)
			(type default)
		)
		(layer "In6.Cu")
	)
	(gr_line
		(start 310.744362 -34.501328)
		(end 310.744362 -39.039038)
		(stroke
			(width 1.016)
			(type default)
		)
		(layer "In6.Cu")
	)
	(gr_line
		(start 311.395364 -80.518)
		(end 323.977 -80.518)
		(stroke
			(width 1.016)
			(type default)
		)
		(layer "In6.Cu")
	)
	(gr_line
		(start 323.977 -80.518)
		(end 324.612 -79.883)
		(stroke
			(width 1.016)
			(type default)
		)
		(layer "In6.Cu")
	)
	(gr_line
		(start 323.977 -12.446)
		(end 283.354018 -12.446)
		(stroke
			(width 1.016)
			(type default)
		)
		(layer "In6.Cu")
	)
	(gr_line
		(start 324.104 -46.355)
		(end 305.010058 -46.355)
		(stroke
			(width 1.016)
			(type default)
		)
		(layer "In6.Cu")
	)
	(gr_line
		(start 324.104 -46.355)
		(end 324.612 -45.847)
		(stroke
			(width 1.016)
			(type default)
		)
		(layer "In6.Cu")
	)
	(gr_line
		(start 324.612 -79.883)
		(end 324.612 -46.863)
		(stroke
			(width 1.016)
			(type default)
		)
		(layer "In6.Cu")
	)
	(gr_line
		(start 324.612 -46.863)
		(end 324.104 -46.355)
		(stroke
			(width 1.016)
			(type default)
		)
		(layer "In6.Cu")
	)
	(gr_line
		(start 324.612 -46.863)
		(end 324.612 -13.081)
		(stroke
			(width 1.016)
			(type default)
		)
		(layer "In6.Cu")
	)
	(gr_line
		(start 324.612 -13.081)
		(end 323.977 -12.446)
		(stroke
			(width 1.016)
			(type default)
		)
		(layer "In6.Cu")
	)
	(gr_circle
		(center 332.1558 -79.4766)
		(end 333.0448 -79.4766)
		(stroke
			(width 0.2)
			(type default)
		)
		(fill no)
		(layer "In6.Cu")
	)
	(gr_circle
		(center 332.1558 -78.7146)
		(end 333.0448 -78.7146)
		(stroke
			(width 0.2)
			(type default)
		)
		(fill no)
		(layer "In6.Cu")
	)
	(gr_circle
		(center 332.1558 -77.9526)
		(end 333.0448 -77.9526)
		(stroke
			(width 0.2)
			(type default)
		)
		(fill no)
		(layer "In6.Cu")
	)
	(gr_circle
		(center 332.1558 -77.1906)
		(end 333.0448 -77.1906)
		(stroke
			(width 0.2)
			(type default)
		)
		(fill no)
		(layer "In6.Cu")
	)
	(gr_circle
		(center 332.1558 -76.4286)
		(end 333.0448 -76.4286)
		(stroke
			(width 0.2)
			(type default)
		)
		(fill no)
		(layer "In6.Cu")
	)
	(gr_circle
		(center 332.1558 -68.199)
		(end 333.0448 -68.199)
		(stroke
			(width 0.2)
			(type default)
		)
		(fill no)
		(layer "In6.Cu")
	)
	(gr_circle
		(center 332.1558 -67.437)
		(end 333.0448 -67.437)
		(stroke
			(width 0.2)
			(type default)
		)
		(fill no)
		(layer "In6.Cu")
	)
	(gr_circle
		(center 332.1558 -66.675)
		(end 333.0448 -66.675)
		(stroke
			(width 0.2)
			(type default)
		)
		(fill no)
		(layer "In6.Cu")
	)
	(gr_circle
		(center 332.1558 -65.913)
		(end 333.0448 -65.913)
		(stroke
			(width 0.2)
			(type default)
		)
		(fill no)
		(layer "In6.Cu")
	)
	(gr_circle
		(center 332.1558 -65.151)
		(end 333.0448 -65.151)
		(stroke
			(width 0.2)
			(type default)
		)
		(fill no)
		(layer "In6.Cu")
	)
	(gr_circle
		(center 332.1558 -56.9214)
		(end 333.0448 -56.9214)
		(stroke
			(width 0.2)
			(type default)
		)
		(fill no)
		(layer "In6.Cu")
	)
	(gr_circle
		(center 332.1558 -56.1594)
		(end 333.0448 -56.1594)
		(stroke
			(width 0.2)
			(type default)
		)
		(fill no)
		(layer "In6.Cu")
	)
	(gr_circle
		(center 332.1558 -55.3974)
		(end 333.0448 -55.3974)
		(stroke
			(width 0.2)
			(type default)
		)
		(fill no)
		(layer "In6.Cu")
	)
	(gr_circle
		(center 332.1558 -54.6354)
		(end 333.0448 -54.6354)
		(stroke
			(width 0.2)
			(type default)
		)
		(fill no)
		(layer "In6.Cu")
	)
	(gr_circle
		(center 332.1558 -53.8734)
		(end 333.0448 -53.8734)
		(stroke
			(width 0.2)
			(type default)
		)
		(fill no)
		(layer "In6.Cu")
	)
	(gr_circle
		(center 332.1558 -45.6438)
		(end 333.0448 -45.6438)
		(stroke
			(width 0.2)
			(type default)
		)
		(fill no)
		(layer "In6.Cu")
	)
	(gr_circle
		(center 332.1558 -44.8818)
		(end 333.0448 -44.8818)
		(stroke
			(width 0.2)
			(type default)
		)
		(fill no)
		(layer "In6.Cu")
	)
	(gr_circle
		(center 332.1558 -44.1198)
		(end 333.0448 -44.1198)
		(stroke
			(width 0.2)
			(type default)
		)
		(fill no)
		(layer "In6.Cu")
	)
	(gr_circle
		(center 332.1558 -43.3578)
		(end 333.0448 -43.3578)
		(stroke
			(width 0.2)
			(type default)
		)
		(fill no)
		(layer "In6.Cu")
	)
	(gr_circle
		(center 332.1558 -42.5958)
		(end 333.0448 -42.5958)
		(stroke
			(width 0.2)
			(type default)
		)
		(fill no)
		(layer "In6.Cu")
	)
	(gr_circle
		(center 332.1558 -34.3662)
		(end 333.0448 -34.3662)
		(stroke
			(width 0.2)
			(type default)
		)
		(fill no)
		(layer "In6.Cu")
	)
	(gr_circle
		(center 332.1558 -33.6042)
		(end 333.0448 -33.6042)
		(stroke
			(width 0.2)
			(type default)
		)
		(fill no)
		(layer "In6.Cu")
	)
	(gr_circle
		(center 332.1558 -32.8422)
		(end 333.0448 -32.8422)
		(stroke
			(width 0.2)
			(type default)
		)
		(fill no)
		(layer "In6.Cu")
	)
	(gr_circle
		(center 332.1558 -32.0802)
		(end 333.0448 -32.0802)
		(stroke
			(width 0.2)
			(type default)
		)
		(fill no)
		(layer "In6.Cu")
	)
	(gr_circle
		(center 332.1558 -31.3182)
		(end 333.0448 -31.3182)
		(stroke
			(width 0.2)
			(type default)
		)
		(fill no)
		(layer "In6.Cu")
	)
	(gr_circle
		(center 332.1558 -23.0886)
		(end 333.0448 -23.0886)
		(stroke
			(width 0.2)
			(type default)
		)
		(fill no)
		(layer "In6.Cu")
	)
	(gr_circle
		(center 332.1558 -22.3266)
		(end 333.0448 -22.3266)
		(stroke
			(width 0.2)
			(type default)
		)
		(fill no)
		(layer "In6.Cu")
	)
	(gr_circle
		(center 332.1558 -21.5646)
		(end 333.0448 -21.5646)
		(stroke
			(width 0.2)
			(type default)
		)
		(fill no)
		(layer "In6.Cu")
	)
	(gr_circle
		(center 332.1558 -20.8026)
		(end 333.0448 -20.8026)
		(stroke
			(width 0.2)
			(type default)
		)
		(fill no)
		(layer "In6.Cu")
	)
	(gr_circle
		(center 332.1558 -20.0406)
		(end 333.0448 -20.0406)
		(stroke
			(width 0.2)
			(type default)
		)
		(fill no)
		(layer "In6.Cu")
	)
	(gr_circle
		(center 332.9178 -79.4766)
		(end 333.8068 -79.4766)
		(stroke
			(width 0.2)
			(type default)
		)
		(fill no)
		(layer "In6.Cu")
	)
	(gr_circle
		(center 332.9178 -78.7146)
		(end 333.8068 -78.7146)
		(stroke
			(width 0.2)
			(type default)
		)
		(fill no)
		(layer "In6.Cu")
	)
	(gr_circle
		(center 332.9178 -77.9526)
		(end 333.8068 -77.9526)
		(stroke
			(width 0.2)
			(type default)
		)
		(fill no)
		(layer "In6.Cu")
	)
	(gr_circle
		(center 332.9178 -77.1906)
		(end 333.8068 -77.1906)
		(stroke
			(width 0.2)
			(type default)
		)
		(fill no)
		(layer "In6.Cu")
	)
	(gr_circle
		(center 332.9178 -76.4286)
		(end 333.8068 -76.4286)
		(stroke
			(width 0.2)
			(type default)
		)
		(fill no)
		(layer "In6.Cu")
	)
	(gr_circle
		(center 332.9178 -68.199)
		(end 333.8068 -68.199)
		(stroke
			(width 0.2)
			(type default)
		)
		(fill no)
		(layer "In6.Cu")
	)
	(gr_circle
		(center 332.9178 -67.437)
		(end 333.8068 -67.437)
		(stroke
			(width 0.2)
			(type default)
		)
		(fill no)
		(layer "In6.Cu")
	)
	(gr_circle
		(center 332.9178 -66.675)
		(end 333.8068 -66.675)
		(stroke
			(width 0.2)
			(type default)
		)
		(fill no)
		(layer "In6.Cu")
	)
	(gr_circle
		(center 332.9178 -65.913)
		(end 333.8068 -65.913)
		(stroke
			(width 0.2)
			(type default)
		)
		(fill no)
		(layer "In6.Cu")
	)
	(gr_circle
		(center 332.9178 -65.151)
		(end 333.8068 -65.151)
		(stroke
			(width 0.2)
			(type default)
		)
		(fill no)
		(layer "In6.Cu")
	)
	(gr_circle
		(center 332.9178 -56.9214)
		(end 333.8068 -56.9214)
		(stroke
			(width 0.2)
			(type default)
		)
		(fill no)
		(layer "In6.Cu")
	)
	(gr_circle
		(center 332.9178 -56.1594)
		(end 333.8068 -56.1594)
		(stroke
			(width 0.2)
			(type default)
		)
		(fill no)
		(layer "In6.Cu")
	)
	(gr_circle
		(center 332.9178 -55.3974)
		(end 333.8068 -55.3974)
		(stroke
			(width 0.2)
			(type default)
		)
		(fill no)
		(layer "In6.Cu")
	)
	(gr_circle
		(center 332.9178 -54.6354)
		(end 333.8068 -54.6354)
		(stroke
			(width 0.2)
			(type default)
		)
		(fill no)
		(layer "In6.Cu")
	)
	(gr_circle
		(center 332.9178 -53.8734)
		(end 333.8068 -53.8734)
		(stroke
			(width 0.2)
			(type default)
		)
		(fill no)
		(layer "In6.Cu")
	)
	(gr_circle
		(center 332.9178 -45.6438)
		(end 333.8068 -45.6438)
		(stroke
			(width 0.2)
			(type default)
		)
		(fill no)
		(layer "In6.Cu")
	)
	(gr_circle
		(center 332.9178 -44.8818)
		(end 333.8068 -44.8818)
		(stroke
			(width 0.2)
			(type default)
		)
		(fill no)
		(layer "In6.Cu")
	)
	(gr_circle
		(center 332.9178 -44.1198)
		(end 333.8068 -44.1198)
		(stroke
			(width 0.2)
			(type default)
		)
		(fill no)
		(layer "In6.Cu")
	)
	(gr_circle
		(center 332.9178 -43.3578)
		(end 333.8068 -43.3578)
		(stroke
			(width 0.2)
			(type default)
		)
		(fill no)
		(layer "In6.Cu")
	)
	(gr_circle
		(center 332.9178 -42.5958)
		(end 333.8068 -42.5958)
		(stroke
			(width 0.2)
			(type default)
		)
		(fill no)
		(layer "In6.Cu")
	)
	(gr_circle
		(center 332.9178 -34.3662)
		(end 333.8068 -34.3662)
		(stroke
			(width 0.2)
			(type default)
		)
		(fill no)
		(layer "In6.Cu")
	)
	(gr_circle
		(center 332.9178 -33.6042)
		(end 333.8068 -33.6042)
		(stroke
			(width 0.2)
			(type default)
		)
		(fill no)
		(layer "In6.Cu")
	)
	(gr_circle
		(center 332.9178 -32.8422)
		(end 333.8068 -32.8422)
		(stroke
			(width 0.2)
			(type default)
		)
		(fill no)
		(layer "In6.Cu")
	)
	(gr_circle
		(center 332.9178 -32.0802)
		(end 333.8068 -32.0802)
		(stroke
			(width 0.2)
			(type default)
		)
		(fill no)
		(layer "In6.Cu")
	)
	(gr_circle
		(center 332.9178 -31.3182)
		(end 333.8068 -31.3182)
		(stroke
			(width 0.2)
			(type default)
		)
		(fill no)
		(layer "In6.Cu")
	)
	(gr_circle
		(center 332.9178 -23.0886)
		(end 333.8068 -23.0886)
		(stroke
			(width 0.2)
			(type default)
		)
		(fill no)
		(layer "In6.Cu")
	)
	(gr_circle
		(center 332.9178 -22.3266)
		(end 333.8068 -22.3266)
		(stroke
			(width 0.2)
			(type default)
		)
		(fill no)
		(layer "In6.Cu")
	)
	(gr_circle
		(center 332.9178 -21.5646)
		(end 333.8068 -21.5646)
		(stroke
			(width 0.2)
			(type default)
		)
		(fill no)
		(layer "In6.Cu")
	)
	(gr_circle
		(center 332.9178 -20.8026)
		(end 333.8068 -20.8026)
		(stroke
			(width 0.2)
			(type default)
		)
		(fill no)
		(layer "In6.Cu")
	)
	(gr_circle
		(center 332.9178 -20.0406)
		(end 333.8068 -20.0406)
		(stroke
			(width 0.2)
			(type default)
		)
		(fill no)
		(layer "In6.Cu")
	)
	(gr_circle
		(center 333.6798 -78.7146)
		(end 334.5688 -78.7146)
		(stroke
			(width 0.2)
			(type default)
		)
		(fill no)
		(layer "In6.Cu")
	)
	(gr_circle
		(center 333.6798 -77.9526)
		(end 334.5688 -77.9526)
		(stroke
			(width 0.2)
			(type default)
		)
		(fill no)
		(layer "In6.Cu")
	)
	(gr_circle
		(center 333.6798 -77.1906)
		(end 334.5688 -77.1906)
		(stroke
			(width 0.2)
			(type default)
		)
		(fill no)
		(layer "In6.Cu")
	)
	(gr_circle
		(center 333.6798 -76.4286)
		(end 334.5688 -76.4286)
		(stroke
			(width 0.2)
			(type default)
		)
		(fill no)
		(layer "In6.Cu")
	)
	(gr_circle
		(center 333.6798 -68.199)
		(end 334.5688 -68.199)
		(stroke
			(width 0.2)
			(type default)
		)
		(fill no)
		(layer "In6.Cu")
	)
	(gr_circle
		(center 333.6798 -67.437)
		(end 334.5688 -67.437)
		(stroke
			(width 0.2)
			(type default)
		)
		(fill no)
		(layer "In6.Cu")
	)
	(gr_circle
		(center 333.6798 -66.675)
		(end 334.5688 -66.675)
		(stroke
			(width 0.2)
			(type default)
		)
		(fill no)
		(layer "In6.Cu")
	)
	(gr_circle
		(center 333.6798 -65.913)
		(end 334.5688 -65.913)
		(stroke
			(width 0.2)
			(type default)
		)
		(fill no)
		(layer "In6.Cu")
	)
	(gr_circle
		(center 333.6798 -65.151)
		(end 334.5688 -65.151)
		(stroke
			(width 0.2)
			(type default)
		)
		(fill no)
		(layer "In6.Cu")
	)
	(gr_circle
		(center 333.6798 -56.9214)
		(end 334.5688 -56.9214)
		(stroke
			(width 0.2)
			(type default)
		)
		(fill no)
		(layer "In6.Cu")
	)
	(gr_circle
		(center 333.6798 -56.1594)
		(end 334.5688 -56.1594)
		(stroke
			(width 0.2)
			(type default)
		)
		(fill no)
		(layer "In6.Cu")
	)
	(gr_circle
		(center 333.6798 -55.3974)
		(end 334.5688 -55.3974)
		(stroke
			(width 0.2)
			(type default)
		)
		(fill no)
		(layer "In6.Cu")
	)
	(gr_circle
		(center 333.6798 -54.6354)
		(end 334.5688 -54.6354)
		(stroke
			(width 0.2)
			(type default)
		)
		(fill no)
		(layer "In6.Cu")
	)
	(gr_circle
		(center 333.6798 -53.8734)
		(end 334.5688 -53.8734)
		(stroke
			(width 0.2)
			(type default)
		)
		(fill no)
		(layer "In6.Cu")
	)
	(gr_circle
		(center 333.6798 -45.6438)
		(end 334.5688 -45.6438)
		(stroke
			(width 0.2)
			(type default)
		)
		(fill no)
		(layer "In6.Cu")
	)
	(gr_circle
		(center 333.6798 -44.8818)
		(end 334.5688 -44.8818)
		(stroke
			(width 0.2)
			(type default)
		)
		(fill no)
		(layer "In6.Cu")
	)
	(gr_circle
		(center 333.6798 -44.1198)
		(end 334.5688 -44.1198)
		(stroke
			(width 0.2)
			(type default)
		)
		(fill no)
		(layer "In6.Cu")
	)
	(gr_circle
		(center 333.6798 -43.3578)
		(end 334.5688 -43.3578)
		(stroke
			(width 0.2)
			(type default)
		)
		(fill no)
		(layer "In6.Cu")
	)
	(gr_circle
		(center 333.6798 -42.5958)
		(end 334.5688 -42.5958)
		(stroke
			(width 0.2)
			(type default)
		)
		(fill no)
		(layer "In6.Cu")
	)
	(gr_circle
		(center 333.6798 -34.3662)
		(end 334.5688 -34.3662)
		(stroke
			(width 0.2)
			(type default)
		)
		(fill no)
		(layer "In6.Cu")
	)
	(gr_circle
		(center 333.6798 -33.6042)
		(end 334.5688 -33.6042)
		(stroke
			(width 0.2)
			(type default)
		)
		(fill no)
		(layer "In6.Cu")
	)
	(gr_circle
		(center 333.6798 -32.8422)
		(end 334.5688 -32.8422)
		(stroke
			(width 0.2)
			(type default)
		)
		(fill no)
		(layer "In6.Cu")
	)
	(gr_circle
		(center 333.6798 -32.0802)
		(end 334.5688 -32.0802)
		(stroke
			(width 0.2)
			(type default)
		)
		(fill no)
		(layer "In6.Cu")
	)
	(gr_circle
		(center 333.6798 -31.3182)
		(end 334.5688 -31.3182)
		(stroke
			(width 0.2)
			(type default)
		)
		(fill no)
		(layer "In6.Cu")
	)
	(gr_circle
		(center 333.6798 -23.0886)
		(end 334.5688 -23.0886)
		(stroke
			(width 0.2)
			(type default)
		)
		(fill no)
		(layer "In6.Cu")
	)
	(gr_circle
		(center 333.6798 -22.3266)
		(end 334.5688 -22.3266)
		(stroke
			(width 0.2)
			(type default)
		)
		(fill no)
		(layer "In6.Cu")
	)
	(gr_circle
		(center 333.6798 -21.5646)
		(end 334.5688 -21.5646)
		(stroke
			(width 0.2)
			(type default)
		)
		(fill no)
		(layer "In6.Cu")
	)
	(gr_circle
		(center 333.6798 -20.8026)
		(end 334.5688 -20.8026)
		(stroke
			(width 0.2)
			(type default)
		)
		(fill no)
		(layer "In6.Cu")
	)
	(gr_circle
		(center 333.6798 -20.0406)
		(end 334.5688 -20.0406)
		(stroke
			(width 0.2)
			(type default)
		)
		(fill no)
		(layer "In6.Cu")
	)
	(gr_circle
		(center 334.4418 -77.9526)
		(end 335.3308 -77.9526)
		(stroke
			(width 0.2)
			(type default)
		)
		(fill no)
		(layer "In6.Cu")
	)
	(gr_circle
		(center 334.4418 -77.1906)
		(end 335.3308 -77.1906)
		(stroke
			(width 0.2)
			(type default)
		)
		(fill no)
		(layer "In6.Cu")
	)
	(gr_circle
		(center 334.4418 -76.4286)
		(end 335.3308 -76.4286)
		(stroke
			(width 0.2)
			(type default)
		)
		(fill no)
		(layer "In6.Cu")
	)
	(gr_circle
		(center 334.4418 -68.199)
		(end 335.3308 -68.199)
		(stroke
			(width 0.2)
			(type default)
		)
		(fill no)
		(layer "In6.Cu")
	)
	(gr_circle
		(center 334.4418 -67.437)
		(end 335.3308 -67.437)
		(stroke
			(width 0.2)
			(type default)
		)
		(fill no)
		(layer "In6.Cu")
	)
	(gr_circle
		(center 334.4418 -66.675)
		(end 335.3308 -66.675)
		(stroke
			(width 0.2)
			(type default)
		)
		(fill no)
		(layer "In6.Cu")
	)
	(gr_circle
		(center 334.4418 -65.913)
		(end 335.3308 -65.913)
		(stroke
			(width 0.2)
			(type default)
		)
		(fill no)
		(layer "In6.Cu")
	)
	(gr_circle
		(center 334.4418 -65.151)
		(end 335.3308 -65.151)
		(stroke
			(width 0.2)
			(type default)
		)
		(fill no)
		(layer "In6.Cu")
	)
	(gr_circle
		(center 334.4418 -56.9214)
		(end 335.3308 -56.9214)
		(stroke
			(width 0.2)
			(type default)
		)
		(fill no)
		(layer "In6.Cu")
	)
	(gr_circle
		(center 334.4418 -56.1594)
		(end 335.3308 -56.1594)
		(stroke
			(width 0.2)
			(type default)
		)
		(fill no)
		(layer "In6.Cu")
	)
	(gr_circle
		(center 334.4418 -55.3974)
		(end 335.3308 -55.3974)
		(stroke
			(width 0.2)
			(type default)
		)
		(fill no)
		(layer "In6.Cu")
	)
	(gr_circle
		(center 334.4418 -54.6354)
		(end 335.3308 -54.6354)
		(stroke
			(width 0.2)
			(type default)
		)
		(fill no)
		(layer "In6.Cu")
	)
	(gr_circle
		(center 334.4418 -53.8734)
		(end 335.3308 -53.8734)
		(stroke
			(width 0.2)
			(type default)
		)
		(fill no)
		(layer "In6.Cu")
	)
	(gr_circle
		(center 334.4418 -44.8818)
		(end 335.3308 -44.8818)
		(stroke
			(width 0.2)
			(type default)
		)
		(fill no)
		(layer "In6.Cu")
	)
	(gr_circle
		(center 334.4418 -44.1198)
		(end 335.3308 -44.1198)
		(stroke
			(width 0.2)
			(type default)
		)
		(fill no)
		(layer "In6.Cu")
	)
	(gr_circle
		(center 334.4418 -43.3578)
		(end 335.3308 -43.3578)
		(stroke
			(width 0.2)
			(type default)
		)
		(fill no)
		(layer "In6.Cu")
	)
	(gr_circle
		(center 334.4418 -42.5958)
		(end 335.3308 -42.5958)
		(stroke
			(width 0.2)
			(type default)
		)
		(fill no)
		(layer "In6.Cu")
	)
	(gr_circle
		(center 334.4418 -34.3662)
		(end 335.3308 -34.3662)
		(stroke
			(width 0.2)
			(type default)
		)
		(fill no)
		(layer "In6.Cu")
	)
	(gr_circle
		(center 334.4418 -33.6042)
		(end 335.3308 -33.6042)
		(stroke
			(width 0.2)
			(type default)
		)
		(fill no)
		(layer "In6.Cu")
	)
	(gr_circle
		(center 334.4418 -32.8422)
		(end 335.3308 -32.8422)
		(stroke
			(width 0.2)
			(type default)
		)
		(fill no)
		(layer "In6.Cu")
	)
	(gr_circle
		(center 334.4418 -32.0802)
		(end 335.3308 -32.0802)
		(stroke
			(width 0.2)
			(type default)
		)
		(fill no)
		(layer "In6.Cu")
	)
	(gr_circle
		(center 334.4418 -31.3182)
		(end 335.3308 -31.3182)
		(stroke
			(width 0.2)
			(type default)
		)
		(fill no)
		(layer "In6.Cu")
	)
	(gr_circle
		(center 334.4418 -23.0886)
		(end 335.3308 -23.0886)
		(stroke
			(width 0.2)
			(type default)
		)
		(fill no)
		(layer "In6.Cu")
	)
	(gr_circle
		(center 334.4418 -22.3266)
		(end 335.3308 -22.3266)
		(stroke
			(width 0.2)
			(type default)
		)
		(fill no)
		(layer "In6.Cu")
	)
	(gr_circle
		(center 334.4418 -21.5646)
		(end 335.3308 -21.5646)
		(stroke
			(width 0.2)
			(type default)
		)
		(fill no)
		(layer "In6.Cu")
	)
	(gr_circle
		(center 334.4418 -20.8026)
		(end 335.3308 -20.8026)
		(stroke
			(width 0.2)
			(type default)
		)
		(fill no)
		(layer "In6.Cu")
	)
	(gr_circle
		(center 334.4418 -20.0406)
		(end 335.3308 -20.0406)
		(stroke
			(width 0.2)
			(type default)
		)
		(fill no)
		(layer "In6.Cu")
	)
	(gr_circle
		(center 335.2038 -77.1906)
		(end 336.0928 -77.1906)
		(stroke
			(width 0.2)
			(type default)
		)
		(fill no)
		(layer "In6.Cu")
	)
	(gr_circle
		(center 335.2038 -76.4286)
		(end 336.0928 -76.4286)
		(stroke
			(width 0.2)
			(type default)
		)
		(fill no)
		(layer "In6.Cu")
	)
	(gr_circle
		(center 335.2038 -68.199)
		(end 336.0928 -68.199)
		(stroke
			(width 0.2)
			(type default)
		)
		(fill no)
		(layer "In6.Cu")
	)
	(gr_circle
		(center 335.2038 -67.437)
		(end 336.0928 -67.437)
		(stroke
			(width 0.2)
			(type default)
		)
		(fill no)
		(layer "In6.Cu")
	)
	(gr_circle
		(center 335.2038 -66.675)
		(end 336.0928 -66.675)
		(stroke
			(width 0.2)
			(type default)
		)
		(fill no)
		(layer "In6.Cu")
	)
	(gr_circle
		(center 335.2038 -65.913)
		(end 336.0928 -65.913)
		(stroke
			(width 0.2)
			(type default)
		)
		(fill no)
		(layer "In6.Cu")
	)
	(gr_circle
		(center 335.2038 -65.151)
		(end 336.0928 -65.151)
		(stroke
			(width 0.2)
			(type default)
		)
		(fill no)
		(layer "In6.Cu")
	)
	(gr_circle
		(center 335.2038 -56.9214)
		(end 336.0928 -56.9214)
		(stroke
			(width 0.2)
			(type default)
		)
		(fill no)
		(layer "In6.Cu")
	)
	(gr_circle
		(center 335.2038 -56.1594)
		(end 336.0928 -56.1594)
		(stroke
			(width 0.2)
			(type default)
		)
		(fill no)
		(layer "In6.Cu")
	)
	(gr_circle
		(center 335.2038 -55.3974)
		(end 336.0928 -55.3974)
		(stroke
			(width 0.2)
			(type default)
		)
		(fill no)
		(layer "In6.Cu")
	)
	(gr_circle
		(center 335.2038 -54.6354)
		(end 336.0928 -54.6354)
		(stroke
			(width 0.2)
			(type default)
		)
		(fill no)
		(layer "In6.Cu")
	)
	(gr_circle
		(center 335.2038 -53.8734)
		(end 336.0928 -53.8734)
		(stroke
			(width 0.2)
			(type default)
		)
		(fill no)
		(layer "In6.Cu")
	)
	(gr_circle
		(center 335.2038 -44.8818)
		(end 336.0928 -44.8818)
		(stroke
			(width 0.2)
			(type default)
		)
		(fill no)
		(layer "In6.Cu")
	)
	(gr_circle
		(center 335.2038 -44.1198)
		(end 336.0928 -44.1198)
		(stroke
			(width 0.2)
			(type default)
		)
		(fill no)
		(layer "In6.Cu")
	)
	(gr_circle
		(center 335.2038 -43.3578)
		(end 336.0928 -43.3578)
		(stroke
			(width 0.2)
			(type default)
		)
		(fill no)
		(layer "In6.Cu")
	)
	(gr_circle
		(center 335.2038 -42.5958)
		(end 336.0928 -42.5958)
		(stroke
			(width 0.2)
			(type default)
		)
		(fill no)
		(layer "In6.Cu")
	)
	(gr_circle
		(center 335.2038 -34.3662)
		(end 336.0928 -34.3662)
		(stroke
			(width 0.2)
			(type default)
		)
		(fill no)
		(layer "In6.Cu")
	)
	(gr_circle
		(center 335.2038 -33.6042)
		(end 336.0928 -33.6042)
		(stroke
			(width 0.2)
			(type default)
		)
		(fill no)
		(layer "In6.Cu")
	)
	(gr_circle
		(center 335.2038 -32.8422)
		(end 336.0928 -32.8422)
		(stroke
			(width 0.2)
			(type default)
		)
		(fill no)
		(layer "In6.Cu")
	)
	(gr_circle
		(center 335.2038 -32.0802)
		(end 336.0928 -32.0802)
		(stroke
			(width 0.2)
			(type default)
		)
		(fill no)
		(layer "In6.Cu")
	)
	(gr_circle
		(center 335.2038 -31.3182)
		(end 336.0928 -31.3182)
		(stroke
			(width 0.2)
			(type default)
		)
		(fill no)
		(layer "In6.Cu")
	)
	(gr_circle
		(center 335.2038 -23.0886)
		(end 336.0928 -23.0886)
		(stroke
			(width 0.2)
			(type default)
		)
		(fill no)
		(layer "In6.Cu")
	)
	(gr_circle
		(center 335.2038 -22.3266)
		(end 336.0928 -22.3266)
		(stroke
			(width 0.2)
			(type default)
		)
		(fill no)
		(layer "In6.Cu")
	)
	(gr_circle
		(center 335.2038 -21.5646)
		(end 336.0928 -21.5646)
		(stroke
			(width 0.2)
			(type default)
		)
		(fill no)
		(layer "In6.Cu")
	)
	(gr_circle
		(center 335.2038 -20.8026)
		(end 336.0928 -20.8026)
		(stroke
			(width 0.2)
			(type default)
		)
		(fill no)
		(layer "In6.Cu")
	)
	(gr_circle
		(center 335.2038 -20.0406)
		(end 336.0928 -20.0406)
		(stroke
			(width 0.2)
			(type default)
		)
		(fill no)
		(layer "In6.Cu")
	)
	(gr_circle
		(center 335.367884 -73.6346)
		(end 336.256884 -73.6346)
		(stroke
			(width 0.2)
			(type default)
		)
		(fill no)
		(layer "In6.Cu")
	)
	(gr_circle
		(center 335.367884 -62.357)
		(end 336.256884 -62.357)
		(stroke
			(width 0.2)
			(type default)
		)
		(fill no)
		(layer "In6.Cu")
	)
	(gr_circle
		(center 335.367884 -51.0794)
		(end 336.256884 -51.0794)
		(stroke
			(width 0.2)
			(type default)
		)
		(fill no)
		(layer "In6.Cu")
	)
	(gr_circle
		(center 335.367884 -39.8018)
		(end 336.256884 -39.8018)
		(stroke
			(width 0.2)
			(type default)
		)
		(fill no)
		(layer "In6.Cu")
	)
	(gr_circle
		(center 335.367884 -28.5242)
		(end 336.256884 -28.5242)
		(stroke
			(width 0.2)
			(type default)
		)
		(fill no)
		(layer "In6.Cu")
	)
	(gr_circle
		(center 335.367884 -17.2466)
		(end 336.256884 -17.2466)
		(stroke
			(width 0.2)
			(type default)
		)
		(fill no)
		(layer "In6.Cu")
	)
	(gr_circle
		(center 336.3214 -49.5046)
		(end 337.2104 -49.5046)
		(stroke
			(width 0.2)
			(type default)
		)
		(fill no)
		(layer "In6.Cu")
	)
	(gr_circle
		(center 336.3214 -38.227)
		(end 337.2104 -38.227)
		(stroke
			(width 0.2)
			(type default)
		)
		(fill no)
		(layer "In6.Cu")
	)
	(gr_circle
		(center 338.498434 -48.423576)
		(end 339.387434 -48.423576)
		(stroke
			(width 0.2)
			(type default)
		)
		(fill no)
		(layer "In6.Cu")
	)
	(gr_circle
		(center 338.87156 -37.247068)
		(end 339.76056 -37.247068)
		(stroke
			(width 0.2)
			(type default)
		)
		(fill no)
		(layer "In6.Cu")
	)
	(gr_circle
		(center 354.89642 -5.353304)
		(end 355.78542 -5.353304)
		(stroke
			(width 0.2)
			(type default)
		)
		(fill no)
		(layer "In6.Cu")
	)
	(gr_circle
		(center 354.89642 -4.591304)
		(end 355.78542 -4.591304)
		(stroke
			(width 0.2)
			(type default)
		)
		(fill no)
		(layer "In6.Cu")
	)
	(gr_circle
		(center 354.89642 -3.829304)
		(end 355.78542 -3.829304)
		(stroke
			(width 0.2)
			(type default)
		)
		(fill no)
		(layer "In6.Cu")
	)
	(gr_circle
		(center 355.65842 -5.353304)
		(end 356.54742 -5.353304)
		(stroke
			(width 0.2)
			(type default)
		)
		(fill no)
		(layer "In6.Cu")
	)
	(gr_circle
		(center 355.65842 -4.591304)
		(end 356.54742 -4.591304)
		(stroke
			(width 0.2)
			(type default)
		)
		(fill no)
		(layer "In6.Cu")
	)
	(gr_circle
		(center 355.65842 -3.829304)
		(end 356.54742 -3.829304)
		(stroke
			(width 0.2)
			(type default)
		)
		(fill no)
		(layer "In6.Cu")
	)
	(gr_circle
		(center 356.42042 -5.353304)
		(end 357.30942 -5.353304)
		(stroke
			(width 0.2)
			(type default)
		)
		(fill no)
		(layer "In6.Cu")
	)
	(gr_circle
		(center 356.42042 -4.591304)
		(end 357.30942 -4.591304)
		(stroke
			(width 0.2)
			(type default)
		)
		(fill no)
		(layer "In6.Cu")
	)
	(gr_circle
		(center 356.42042 -3.829304)
		(end 357.30942 -3.829304)
		(stroke
			(width 0.2)
			(type default)
		)
		(fill no)
		(layer "In6.Cu")
	)
	(gr_circle
		(center 357.18242 -5.353304)
		(end 358.07142 -5.353304)
		(stroke
			(width 0.2)
			(type default)
		)
		(fill no)
		(layer "In6.Cu")
	)
	(gr_circle
		(center 357.18242 -4.591304)
		(end 358.07142 -4.591304)
		(stroke
			(width 0.2)
			(type default)
		)
		(fill no)
		(layer "In6.Cu")
	)
	(gr_circle
		(center 357.18242 -3.829304)
		(end 358.07142 -3.829304)
		(stroke
			(width 0.2)
			(type default)
		)
		(fill no)
		(layer "In6.Cu")
	)
	(gr_circle
		(center 357.94442 -5.353304)
		(end 358.83342 -5.353304)
		(stroke
			(width 0.2)
			(type default)
		)
		(fill no)
		(layer "In6.Cu")
	)
	(gr_circle
		(center 357.94442 -4.591304)
		(end 358.83342 -4.591304)
		(stroke
			(width 0.2)
			(type default)
		)
		(fill no)
		(layer "In6.Cu")
	)
	(gr_circle
		(center 357.94442 -3.829304)
		(end 358.83342 -3.829304)
		(stroke
			(width 0.2)
			(type default)
		)
		(fill no)
		(layer "In6.Cu")
	)
	(gr_circle
		(center 358.70642 -5.353304)
		(end 359.59542 -5.353304)
		(stroke
			(width 0.2)
			(type default)
		)
		(fill no)
		(layer "In6.Cu")
	)
	(gr_circle
		(center 358.70642 -4.591304)
		(end 359.59542 -4.591304)
		(stroke
			(width 0.2)
			(type default)
		)
		(fill no)
		(layer "In6.Cu")
	)
	(gr_circle
		(center 358.70642 -3.829304)
		(end 359.59542 -3.829304)
		(stroke
			(width 0.2)
			(type default)
		)
		(fill no)
		(layer "In6.Cu")
	)
	(gr_circle
		(center 363.000036 -160.830006)
		(end 364.21314 -160.830006)
		(stroke
			(width 0.2)
			(type default)
		)
		(fill no)
		(layer "In6.Cu")
	)
	(gr_circle
		(center 363.000036 -158.83001)
		(end 364.21314 -158.83001)
		(stroke
			(width 0.2)
			(type default)
		)
		(fill no)
		(layer "In6.Cu")
	)
	(gr_circle
		(center 363.000036 -156.830014)
		(end 364.21314 -156.830014)
		(stroke
			(width 0.2)
			(type default)
		)
		(fill no)
		(layer "In6.Cu")
	)
	(gr_circle
		(center 364.123478 -159.82061)
		(end 365.336582 -159.82061)
		(stroke
			(width 0.2)
			(type default)
		)
		(fill no)
		(layer "In6.Cu")
	)
	(gr_circle
		(center 364.123478 -157.820614)
		(end 365.336582 -157.820614)
		(stroke
			(width 0.2)
			(type default)
		)
		(fill no)
		(layer "In6.Cu")
	)
	(gr_circle
		(center 365.000032 -160.830006)
		(end 366.213136 -160.830006)
		(stroke
			(width 0.2)
			(type default)
		)
		(fill no)
		(layer "In6.Cu")
	)
	(gr_circle
		(center 365.000032 -158.83001)
		(end 366.213136 -158.83001)
		(stroke
			(width 0.2)
			(type default)
		)
		(fill no)
		(layer "In6.Cu")
	)
	(gr_circle
		(center 365.000032 -156.830014)
		(end 366.213136 -156.830014)
		(stroke
			(width 0.2)
			(type default)
		)
		(fill no)
		(layer "In6.Cu")
	)
	(gr_circle
		(center 366.119918 -2.590038)
		(end 367.333022 -2.590038)
		(stroke
			(width 0.2)
			(type default)
		)
		(fill no)
		(layer "In6.Cu")
	)
	(gr_circle
		(center 368.659918 -2.590038)
		(end 369.873022 -2.590038)
		(stroke
			(width 0.2)
			(type default)
		)
		(fill no)
		(layer "In6.Cu")
	)
	(gr_circle
		(center 369.000024 -160.830006)
		(end 370.213128 -160.830006)
		(stroke
			(width 0.2)
			(type default)
		)
		(fill no)
		(layer "In6.Cu")
	)
	(gr_circle
		(center 369.000024 -158.83001)
		(end 370.213128 -158.83001)
		(stroke
			(width 0.2)
			(type default)
		)
		(fill no)
		(layer "In6.Cu")
	)
	(gr_circle
		(center 369.000024 -156.830014)
		(end 370.213128 -156.830014)
		(stroke
			(width 0.2)
			(type default)
		)
		(fill no)
		(layer "In6.Cu")
	)
	(gr_circle
		(center 369.990878 -159.87141)
		(end 371.203982 -159.87141)
		(stroke
			(width 0.2)
			(type default)
		)
		(fill no)
		(layer "In6.Cu")
	)
	(gr_circle
		(center 369.990878 -157.871414)
		(end 371.203982 -157.871414)
		(stroke
			(width 0.2)
			(type default)
		)
		(fill no)
		(layer "In6.Cu")
	)
	(gr_circle
		(center 371.00002 -160.830006)
		(end 372.213124 -160.830006)
		(stroke
			(width 0.2)
			(type default)
		)
		(fill no)
		(layer "In6.Cu")
	)
	(gr_circle
		(center 371.00002 -158.83001)
		(end 372.213124 -158.83001)
		(stroke
			(width 0.2)
			(type default)
		)
		(fill no)
		(layer "In6.Cu")
	)
	(gr_circle
		(center 371.00002 -156.830014)
		(end 372.213124 -156.830014)
		(stroke
			(width 0.2)
			(type default)
		)
		(fill no)
		(layer "In6.Cu")
	)
	(gr_circle
		(center 375.000012 -160.830006)
		(end 376.213116 -160.830006)
		(stroke
			(width 0.2)
			(type default)
		)
		(fill no)
		(layer "In6.Cu")
	)
	(gr_circle
		(center 375.000012 -158.83001)
		(end 376.213116 -158.83001)
		(stroke
			(width 0.2)
			(type default)
		)
		(fill no)
		(layer "In6.Cu")
	)
	(gr_circle
		(center 375.000012 -156.830014)
		(end 376.213116 -156.830014)
		(stroke
			(width 0.2)
			(type default)
		)
		(fill no)
		(layer "In6.Cu")
	)
	(gr_circle
		(center 375.909078 -159.79521)
		(end 377.122182 -159.79521)
		(stroke
			(width 0.2)
			(type default)
		)
		(fill no)
		(layer "In6.Cu")
	)
	(gr_circle
		(center 375.909078 -157.795214)
		(end 377.122182 -157.795214)
		(stroke
			(width 0.2)
			(type default)
		)
		(fill no)
		(layer "In6.Cu")
	)
	(gr_circle
		(center 377.000008 -160.830006)
		(end 378.213112 -160.830006)
		(stroke
			(width 0.2)
			(type default)
		)
		(fill no)
		(layer "In6.Cu")
	)
	(gr_circle
		(center 377.000008 -158.83001)
		(end 378.213112 -158.83001)
		(stroke
			(width 0.2)
			(type default)
		)
		(fill no)
		(layer "In6.Cu")
	)
	(gr_circle
		(center 377.000008 -156.830014)
		(end 378.213112 -156.830014)
		(stroke
			(width 0.2)
			(type default)
		)
		(fill no)
		(layer "In6.Cu")
	)
	(gr_circle
		(center 378.079 -139.7)
		(end 379.603 -139.7)
		(stroke
			(width 0.2)
			(type default)
		)
		(fill no)
		(layer "In6.Cu")
	)
	(gr_circle
		(center 378.079 -119.38)
		(end 379.603 -119.38)
		(stroke
			(width 0.2)
			(type default)
		)
		(fill no)
		(layer "In6.Cu")
	)
	(gr_circle
		(center 378.079 -99.06)
		(end 379.603 -99.06)
		(stroke
			(width 0.2)
			(type default)
		)
		(fill no)
		(layer "In6.Cu")
	)
	(gr_circle
		(center 378.079 -78.74)
		(end 379.603 -78.74)
		(stroke
			(width 0.2)
			(type default)
		)
		(fill no)
		(layer "In6.Cu")
	)
	(gr_circle
		(center 378.079 -58.42)
		(end 379.603 -58.42)
		(stroke
			(width 0.2)
			(type default)
		)
		(fill no)
		(layer "In6.Cu")
	)
	(gr_circle
		(center 383.199894 -160.830006)
		(end 384.412998 -160.830006)
		(stroke
			(width 0.2)
			(type default)
		)
		(fill no)
		(layer "In6.Cu")
	)
	(gr_circle
		(center 383.199894 -158.83001)
		(end 384.412998 -158.83001)
		(stroke
			(width 0.2)
			(type default)
		)
		(fill no)
		(layer "In6.Cu")
	)
	(gr_circle
		(center 383.199894 -156.830014)
		(end 384.412998 -156.830014)
		(stroke
			(width 0.2)
			(type default)
		)
		(fill no)
		(layer "In6.Cu")
	)
	(gr_circle
		(center 384.062478 -159.64281)
		(end 385.275582 -159.64281)
		(stroke
			(width 0.2)
			(type default)
		)
		(fill no)
		(layer "In6.Cu")
	)
	(gr_circle
		(center 384.062478 -157.642814)
		(end 385.275582 -157.642814)
		(stroke
			(width 0.2)
			(type default)
		)
		(fill no)
		(layer "In6.Cu")
	)
	(gr_circle
		(center 385.19989 -160.830006)
		(end 386.412994 -160.830006)
		(stroke
			(width 0.2)
			(type default)
		)
		(fill no)
		(layer "In6.Cu")
	)
	(gr_circle
		(center 385.19989 -158.83001)
		(end 386.412994 -158.83001)
		(stroke
			(width 0.2)
			(type default)
		)
		(fill no)
		(layer "In6.Cu")
	)
	(gr_circle
		(center 385.19989 -156.830014)
		(end 386.412994 -156.830014)
		(stroke
			(width 0.2)
			(type default)
		)
		(fill no)
		(layer "In6.Cu")
	)
	(gr_circle
		(center 389.199882 -160.830006)
		(end 390.412986 -160.830006)
		(stroke
			(width 0.2)
			(type default)
		)
		(fill no)
		(layer "In6.Cu")
	)
	(gr_circle
		(center 389.199882 -158.83001)
		(end 390.412986 -158.83001)
		(stroke
			(width 0.2)
			(type default)
		)
		(fill no)
		(layer "In6.Cu")
	)
	(gr_circle
		(center 389.199882 -156.830014)
		(end 390.412986 -156.830014)
		(stroke
			(width 0.2)
			(type default)
		)
		(fill no)
		(layer "In6.Cu")
	)
	(gr_circle
		(center 390.158478 -159.71901)
		(end 391.371582 -159.71901)
		(stroke
			(width 0.2)
			(type default)
		)
		(fill no)
		(layer "In6.Cu")
	)
	(gr_circle
		(center 390.158478 -157.719014)
		(end 391.371582 -157.719014)
		(stroke
			(width 0.2)
			(type default)
		)
		(fill no)
		(layer "In6.Cu")
	)
	(gr_circle
		(center 391.199878 -160.830006)
		(end 392.412982 -160.830006)
		(stroke
			(width 0.2)
			(type default)
		)
		(fill no)
		(layer "In6.Cu")
	)
	(gr_circle
		(center 391.199878 -158.83001)
		(end 392.412982 -158.83001)
		(stroke
			(width 0.2)
			(type default)
		)
		(fill no)
		(layer "In6.Cu")
	)
	(gr_circle
		(center 391.199878 -156.830014)
		(end 392.412982 -156.830014)
		(stroke
			(width 0.2)
			(type default)
		)
		(fill no)
		(layer "In6.Cu")
	)
	(gr_circle
		(center 397.637 -139.7)
		(end 399.161 -139.7)
		(stroke
			(width 0.2)
			(type default)
		)
		(fill no)
		(layer "In6.Cu")
	)
	(gr_circle
		(center 397.637 -119.38)
		(end 399.161 -119.38)
		(stroke
			(width 0.2)
			(type default)
		)
		(fill no)
		(layer "In6.Cu")
	)
	(gr_circle
		(center 397.637 -99.06)
		(end 399.161 -99.06)
		(stroke
			(width 0.2)
			(type default)
		)
		(fill no)
		(layer "In6.Cu")
	)
	(gr_circle
		(center 397.637 -78.74)
		(end 399.161 -78.74)
		(stroke
			(width 0.2)
			(type default)
		)
		(fill no)
		(layer "In6.Cu")
	)
	(gr_circle
		(center 397.637 -58.42)
		(end 399.161 -58.42)
		(stroke
			(width 0.2)
			(type default)
		)
		(fill no)
		(layer "In6.Cu")
	)
	(gr_circle
		(center 398.375124 -168.82999)
		(end 399.588228 -168.82999)
		(stroke
			(width 0.2)
			(type default)
		)
		(fill no)
		(layer "In6.Cu")
	)
	(gr_circle
		(center 398.375124 -166.829994)
		(end 399.588228 -166.829994)
		(stroke
			(width 0.2)
			(type default)
		)
		(fill no)
		(layer "In6.Cu")
	)
	(gr_circle
		(center 398.375124 -164.829998)
		(end 399.588228 -164.829998)
		(stroke
			(width 0.2)
			(type default)
		)
		(fill no)
		(layer "In6.Cu")
	)
	(gr_circle
		(center 398.375124 -162.830002)
		(end 399.588228 -162.830002)
		(stroke
			(width 0.2)
			(type default)
		)
		(fill no)
		(layer "In6.Cu")
	)
	(gr_circle
		(center 398.375124 -160.830006)
		(end 399.588228 -160.830006)
		(stroke
			(width 0.2)
			(type default)
		)
		(fill no)
		(layer "In6.Cu")
	)
	(gr_circle
		(center 398.375124 -158.83001)
		(end 399.588228 -158.83001)
		(stroke
			(width 0.2)
			(type default)
		)
		(fill no)
		(layer "In6.Cu")
	)
	(gr_circle
		(center 398.375124 -156.830014)
		(end 399.588228 -156.830014)
		(stroke
			(width 0.2)
			(type default)
		)
		(fill no)
		(layer "In6.Cu")
	)
	(gr_circle
		(center 398.375124 -154.830018)
		(end 399.588228 -154.830018)
		(stroke
			(width 0.2)
			(type default)
		)
		(fill no)
		(layer "In6.Cu")
	)
	(gr_circle
		(center 398.375124 -152.830022)
		(end 399.588228 -152.830022)
		(stroke
			(width 0.2)
			(type default)
		)
		(fill no)
		(layer "In6.Cu")
	)
	(gr_circle
		(center 399.40992 -167.591994)
		(end 400.623024 -167.591994)
		(stroke
			(width 0.2)
			(type default)
		)
		(fill no)
		(layer "In6.Cu")
	)
	(gr_circle
		(center 399.40992 -165.591998)
		(end 400.623024 -165.591998)
		(stroke
			(width 0.2)
			(type default)
		)
		(fill no)
		(layer "In6.Cu")
	)
	(gr_circle
		(center 399.40992 -163.592002)
		(end 400.623024 -163.592002)
		(stroke
			(width 0.2)
			(type default)
		)
		(fill no)
		(layer "In6.Cu")
	)
	(gr_circle
		(center 399.40992 -161.592006)
		(end 400.623024 -161.592006)
		(stroke
			(width 0.2)
			(type default)
		)
		(fill no)
		(layer "In6.Cu")
	)
	(gr_circle
		(center 399.40992 -159.59201)
		(end 400.623024 -159.59201)
		(stroke
			(width 0.2)
			(type default)
		)
		(fill no)
		(layer "In6.Cu")
	)
	(gr_circle
		(center 399.40992 -157.592014)
		(end 400.623024 -157.592014)
		(stroke
			(width 0.2)
			(type default)
		)
		(fill no)
		(layer "In6.Cu")
	)
	(gr_circle
		(center 399.40992 -155.592018)
		(end 400.623024 -155.592018)
		(stroke
			(width 0.2)
			(type default)
		)
		(fill no)
		(layer "In6.Cu")
	)
	(gr_circle
		(center 399.40992 -153.592022)
		(end 400.623024 -153.592022)
		(stroke
			(width 0.2)
			(type default)
		)
		(fill no)
		(layer "In6.Cu")
	)
	(gr_circle
		(center 400.37512 -168.82999)
		(end 401.588224 -168.82999)
		(stroke
			(width 0.2)
			(type default)
		)
		(fill no)
		(layer "In6.Cu")
	)
	(gr_circle
		(center 400.37512 -166.829994)
		(end 401.588224 -166.829994)
		(stroke
			(width 0.2)
			(type default)
		)
		(fill no)
		(layer "In6.Cu")
	)
	(gr_circle
		(center 400.37512 -164.829998)
		(end 401.588224 -164.829998)
		(stroke
			(width 0.2)
			(type default)
		)
		(fill no)
		(layer "In6.Cu")
	)
	(gr_circle
		(center 400.37512 -162.830002)
		(end 401.588224 -162.830002)
		(stroke
			(width 0.2)
			(type default)
		)
		(fill no)
		(layer "In6.Cu")
	)
	(gr_circle
		(center 400.37512 -160.830006)
		(end 401.588224 -160.830006)
		(stroke
			(width 0.2)
			(type default)
		)
		(fill no)
		(layer "In6.Cu")
	)
	(gr_circle
		(center 400.37512 -158.83001)
		(end 401.588224 -158.83001)
		(stroke
			(width 0.2)
			(type default)
		)
		(fill no)
		(layer "In6.Cu")
	)
	(gr_circle
		(center 400.37512 -156.830014)
		(end 401.588224 -156.830014)
		(stroke
			(width 0.2)
			(type default)
		)
		(fill no)
		(layer "In6.Cu")
	)
	(gr_circle
		(center 400.37512 -154.830018)
		(end 401.588224 -154.830018)
		(stroke
			(width 0.2)
			(type default)
		)
		(fill no)
		(layer "In6.Cu")
	)
	(gr_circle
		(center 400.37512 -152.830022)
		(end 401.588224 -152.830022)
		(stroke
			(width 0.2)
			(type default)
		)
		(fill no)
		(layer "In6.Cu")
	)
	(gr_circle
		(center 468.920068 -76.309982)
		(end 470.329768 -76.309982)
		(stroke
			(width 0.2)
			(type default)
		)
		(fill no)
		(layer "In6.Cu")
	)
	(gr_circle
		(center 468.920068 -73.769982)
		(end 470.329768 -73.769982)
		(stroke
			(width 0.2)
			(type default)
		)
		(fill no)
		(layer "In6.Cu")
	)
	(gr_circle
		(center 468.920068 -71.229982)
		(end 470.329768 -71.229982)
		(stroke
			(width 0.2)
			(type default)
		)
		(fill no)
		(layer "In6.Cu")
	)
	(gr_circle
		(center 468.920068 -68.689982)
		(end 470.329768 -68.689982)
		(stroke
			(width 0.2)
			(type default)
		)
		(fill no)
		(layer "In6.Cu")
	)
	(gr_circle
		(center 469.994488 -74.785982)
		(end 471.404188 -74.785982)
		(stroke
			(width 0.2)
			(type default)
		)
		(fill no)
		(layer "In6.Cu")
	)
	(gr_circle
		(center 469.994488 -72.245982)
		(end 471.404188 -72.245982)
		(stroke
			(width 0.2)
			(type default)
		)
		(fill no)
		(layer "In6.Cu")
	)
	(gr_circle
		(center 469.994488 -69.705982)
		(end 471.404188 -69.705982)
		(stroke
			(width 0.2)
			(type default)
		)
		(fill no)
		(layer "In6.Cu")
	)
	(gr_circle
		(center 471.620088 -76.309982)
		(end 473.029788 -76.309982)
		(stroke
			(width 0.2)
			(type default)
		)
		(fill no)
		(layer "In6.Cu")
	)
	(gr_circle
		(center 471.620088 -73.769982)
		(end 473.029788 -73.769982)
		(stroke
			(width 0.2)
			(type default)
		)
		(fill no)
		(layer "In6.Cu")
	)
	(gr_circle
		(center 471.620088 -71.229982)
		(end 473.029788 -71.229982)
		(stroke
			(width 0.2)
			(type default)
		)
		(fill no)
		(layer "In6.Cu")
	)
	(gr_circle
		(center 471.620088 -68.689982)
		(end 473.029788 -68.689982)
		(stroke
			(width 0.2)
			(type default)
		)
		(fill no)
		(layer "In6.Cu")
	)
	(gr_poly
		(pts
			(xy 193.11239 -50.557684) (xy 193.11239 -46.692312) (xy 189.727078 -43.307) (xy 186.12612 -43.307)
			(xy 182.695342 -46.737778) (xy 182.695342 -50.684938) (xy 182.942484 -50.93208) (xy 192.737994 -50.93208)
		)
		(stroke
			(width 0)
			(type solid)
		)
		(fill yes)
		(layer "In7.Cu")
		(net "P52V_2_FUSE_1")
	)
	(gr_poly
		(pts
			(xy 257.683 -50.557684) (xy 257.683 -46.692312) (xy 254.297688 -43.307) (xy 250.69673 -43.307) (xy 247.265952 -46.737778)
			(xy 247.265952 -50.684938) (xy 247.513094 -50.93208) (xy 257.308604 -50.93208)
		)
		(stroke
			(width 0)
			(type solid)
		)
		(fill yes)
		(layer "In7.Cu")
		(net "P52V_1_FUSE_1")
	)
	(gr_poly
		(pts
			(xy 324.104 -79.7052) (xy 324.104 -47.0662) (xy 323.7738 -46.736) (xy 305.773328 -46.736) (xy 305.6382 -46.871128)
			(xy 305.6382 -66.680588) (xy 305.785012 -66.8274) (xy 310.0324 -66.8274) (xy 311.2516 -68.0466) (xy 311.2516 -79.629)
			(xy 311.6072 -79.9846) (xy 323.8246 -79.9846)
		)
		(stroke
			(width 0)
			(type solid)
		)
		(fill yes)
		(layer "In7.Cu")
		(net "P52V_HS1_DRAIN_1")
	)
	(gr_poly
		(pts
			(xy 324.104 -45.8724) (xy 324.104 -13.2334) (xy 323.7738 -12.9032) (xy 305.767486 -12.9032) (xy 305.6382 -13.032486)
			(xy 305.6382 -32.91332) (xy 305.71948 -32.9946) (xy 310.0324 -32.9946) (xy 311.2516 -34.2138) (xy 311.2516 -45.7962)
			(xy 311.6072 -46.1518) (xy 323.8246 -46.1518)
		)
		(stroke
			(width 0)
			(type solid)
		)
		(fill yes)
		(layer "In7.Cu")
		(net "P52V_HS1_DRAIN_2")
	)
	(gr_poly
		(pts
			(xy 136.368536 -79.629) (xy 136.368536 -68.0466) (xy 137.587736 -66.8274) (xy 142.312136 -66.8274)
			(xy 142.362936 -66.7766) (xy 142.362936 -64.0588) (xy 141.981936 -63.6778) (xy 141.981936 -63.6524)
			(xy 141.981936 -63.627) (xy 141.981936 -63.0936) (xy 142.354046 -62.72149) (xy 142.354046 -62.592712)
			(xy 142.354046 -46.90491) (xy 142.185136 -46.736) (xy 132.025136 -46.736) (xy 123.846336 -46.736)
			(xy 123.516136 -47.0662) (xy 123.516136 -79.7052) (xy 123.795536 -79.9846) (xy 132.050536 -79.9846)
			(xy 134.565136 -79.9846) (xy 136.012936 -79.9846)
		)
		(stroke
			(width 0)
			(type solid)
		)
		(fill yes)
		(layer "In7.Cu")
		(net "P52V_HS2_DRAIN_1")
	)
	(gr_poly
		(pts
			(xy 136.357868 -45.806868) (xy 141.818868 -45.806868) (xy 141.859 -45.847) (xy 142.494 -45.212) (xy 142.494 -42.2148)
			(xy 140.6652 -40.386) (xy 138.811 -40.386) (xy 137.414 -38.989) (xy 137.414 -33.168336) (xy 137.587736 -32.9946)
			(xy 142.312136 -32.9946) (xy 142.362936 -32.9438) (xy 142.362936 -30.226) (xy 141.981936 -29.845)
			(xy 141.981936 -29.8196) (xy 141.981936 -29.7942) (xy 141.981936 -29.2608) (xy 142.354046 -28.88869)
			(xy 142.354046 -28.759912) (xy 142.354046 -13.07211) (xy 142.185136 -12.9032) (xy 132.025136 -12.9032)
			(xy 123.846336 -12.9032) (xy 123.516136 -13.2334) (xy 123.516136 -45.8724) (xy 123.795536 -46.1518)
			(xy 132.050536 -46.1518) (xy 134.565136 -46.1518) (xy 136.012936 -46.1518)
		)
		(stroke
			(width 0)
			(type solid)
		)
		(fill yes)
		(layer "In7.Cu")
		(net "P52V_HS2_DRAIN_2")
	)
	(gr_poly
		(pts
			(xy 303.572672 -66.637408) (xy 303.572672 -44.09059)
			(arc
				(start 300.503082 -41.021)
				(mid 300.483559 -41.017099)
				(end 300.467014 -41.006014)
			)
			(arc
				(start 298.64685 -39.18585)
				(mid 298.635739 -39.169316)
				(end 298.631864 -39.149782)
			)
			(xy 298.631864 -33.31337) (xy 298.984162 -32.961072) (xy 303.489868 -32.961072) (xy 303.572672 -32.878268)
			(xy 303.572672 -12.999212) (xy 303.379632 -12.806172) (xy 282.954222 -12.806172) (xy 279.484836 -16.275558)
			(xy 279.484836 -26.865072) (xy 277.128478 -29.22143)
			(arc
				(start 230.533956 -29.22143)
				(mid 230.514433 -29.225331)
				(end 230.497888 -29.236416)
			)
			(arc
				(start 230.011986 -29.722318)
				(mid 230.000875 -29.738852)
				(end 229.997 -29.758386)
			)
			(arc
				(start 229.997 -46.841918)
				(mid 230.000901 -46.861441)
				(end 230.011986 -46.877986)
			)
			(arc
				(start 230.363014 -47.229014)
				(mid 230.379548 -47.240125)
				(end 230.399082 -47.244)
			)
			(xy 242.8494 -47.244) (xy 248.777252 -41.316148) (xy 256.3622 -41.316148) (xy 259.140452 -44.0944)
			(xy 268.332712 -44.0944) (xy 277.756112 -53.5178) (xy 296.286936 -53.5178) (xy 297.125136 -54.356)
			(xy 297.125136 -65.302892) (xy 298.616116 -66.793872) (xy 303.416208 -66.793872)
		)
		(stroke
			(width 0)
			(type solid)
		)
		(fill yes)
		(layer "In7.Cu")
		(net "P52V_1")
	)
	(gr_poly
		(pts
			(xy 148.834856 -66.411856) (xy 148.834856 -59.826144) (xy 152.527 -56.134) (xy 159.112966 -56.134)
			(xy 160.255966 -54.991) (xy 175.3362 -54.991) (xy 175.768762 -54.558438) (xy 175.768762 -53.66639)
			(xy 173.769782 -51.66741) (xy 172.350938 -51.66741) (xy 171.671488 -50.98796) (xy 171.671488 -43.334686)
			(xy 173.690026 -41.316148) (xy 192.0113 -41.316148) (xy 197.939152 -47.244)
			(arc
				(start 209.601054 -47.244)
				(mid 209.620577 -47.240099)
				(end 209.637122 -47.229014)
			)
			(arc
				(start 209.98815 -46.877986)
				(mid 209.999261 -46.861452)
				(end 210.003136 -46.841918)
			)
			(xy 210.003136 -30.415484) (xy 209.995516 -30.407864)
			(arc
				(start 209.995516 -30.311598)
				(mid 209.991615 -30.292075)
				(end 209.98053 -30.27553)
			)
			(xy 208.92643 -29.22143) (xy 161.90595 -29.22143) (xy 160.253426 -27.568906) (xy 160.253426 -15.386304)
			(xy 157.673294 -12.806172) (xy 143.898366 -12.806172) (xy 143.650716 -13.053822) (xy 143.650716 -28.89377)
			(xy 144.047464 -29.290518) (xy 144.047464 -29.815536) (xy 143.65097 -30.21203) (xy 143.65097 -32.928052)
			(xy 143.68399 -32.961072) (xy 147.828 -32.961072) (xy 148.336 -33.469072) (xy 148.336 -38.862) (xy 146.685 -40.513)
			(xy 145.2118 -40.513) (xy 143.650716 -42.074084) (xy 143.650716 -62.72657) (xy 144.047464 -63.123318)
			(xy 144.047464 -63.648336) (xy 143.65097 -64.04483) (xy 143.65097 -66.760852) (xy 143.68399 -66.793872)
			(xy 148.453094 -66.793872)
		)
		(stroke
			(width 0)
			(type solid)
		)
		(fill yes)
		(layer "In7.Cu")
		(net "P52V_2")
	)
	(gr_poly
		(pts
			(xy 391.88644 -169.87266) (xy 391.896506 -169.872228) (xy 391.915096 -169.864499) (xy 391.922508 -169.857674)
			(xy 392.292332 -169.48785) (xy 392.299178 -169.480452) (xy 392.306905 -169.461853) (xy 392.307318 -169.451782)
			(xy 392.307318 -164.263578) (xy 392.306891 -164.253509) (xy 392.299173 -164.234909) (xy 392.292332 -164.22751)
			(xy 391.858246 -163.793424) (xy 391.850846 -163.786584) (xy 391.832247 -163.778865) (xy 391.822178 -163.778438)
			(xy 387.392164 -163.778438) (xy 387.388862 -163.778946) (xy 387.34183 -163.784701) (xy 387.247267 -163.790842)
			(xy 387.152505 -163.790842) (xy 387.057942 -163.784701) (xy 387.01091 -163.778946) (xy 387.007608 -163.778438)
			(xy 362.849922 -163.778438) (xy 362.839859 -163.778876) (xy 362.821279 -163.786615) (xy 362.813854 -163.793424)
			(xy 362.332016 -164.275262) (xy 362.325178 -164.282663) (xy 362.317463 -164.301262) (xy 362.31703 -164.31133)
			(xy 362.31703 -167.684408) (xy 365.513862 -167.684408) (xy 365.513862 -167.57578) (xy 365.521791 -167.467442)
			(xy 365.537608 -167.359971) (xy 365.561227 -167.253942) (xy 365.592523 -167.14992) (xy 365.631328 -167.048459)
			(xy 365.677436 -166.950102) (xy 365.7306 -166.855373) (xy 365.790538 -166.764778) (xy 365.856928 -166.678799)
			(xy 365.929418 -166.597896) (xy 366.007619 -166.5225) (xy 366.091116 -166.453014) (xy 366.179462 -166.389807)
			(xy 366.272186 -166.333219) (xy 366.368794 -166.283549) (xy 366.468769 -166.241064) (xy 366.571579 -166.205991)
			(xy 366.676675 -166.178515) (xy 366.783496 -166.158784) (xy 366.891472 -166.146903) (xy 367.000028 -166.142936)
			(xy 367.108584 -166.146903) (xy 367.21656 -166.158784) (xy 367.323381 -166.178515) (xy 367.428477 -166.205991)
			(xy 367.531287 -166.241064) (xy 367.631262 -166.283549) (xy 367.72787 -166.333219) (xy 367.820594 -166.389807)
			(xy 367.90894 -166.453014) (xy 367.992437 -166.5225) (xy 368.070638 -166.597896) (xy 368.143128 -166.678799)
			(xy 368.209518 -166.764778) (xy 368.269456 -166.855373) (xy 368.32262 -166.950102) (xy 368.368728 -167.048459)
			(xy 368.407533 -167.14992) (xy 368.438829 -167.253942) (xy 368.462448 -167.359971) (xy 368.478265 -167.467442)
			(xy 368.486194 -167.57578) (xy 368.48669 -167.630094) (xy 368.486194 -167.684408) (xy 368.478265 -167.792746)
			(xy 368.462448 -167.900217) (xy 368.438829 -168.006246) (xy 368.407533 -168.110268) (xy 368.368728 -168.211729)
			(xy 368.32262 -168.310086) (xy 368.269456 -168.404815) (xy 368.209518 -168.49541) (xy 368.143128 -168.581389)
			(xy 368.070638 -168.662292) (xy 367.992437 -168.737688) (xy 367.90894 -168.807174) (xy 367.820594 -168.870381)
			(xy 367.72787 -168.926969) (xy 367.631262 -168.976639) (xy 367.531287 -169.019124) (xy 367.428477 -169.054197)
			(xy 367.323381 -169.081673) (xy 367.21656 -169.101404) (xy 367.108584 -169.113285) (xy 367.000028 -169.117252)
			(xy 366.891472 -169.113285) (xy 366.783496 -169.101404) (xy 366.676675 -169.081673) (xy 366.571579 -169.054197)
			(xy 366.468769 -169.019124) (xy 366.368794 -168.976639) (xy 366.272186 -168.926969) (xy 366.179462 -168.870381)
			(xy 366.091116 -168.807174) (xy 366.007619 -168.737688) (xy 365.929418 -168.662292) (xy 365.856928 -168.581389)
			(xy 365.790538 -168.49541) (xy 365.7306 -168.404815) (xy 365.677436 -168.310086) (xy 365.631328 -168.211729)
			(xy 365.592523 -168.110268) (xy 365.561227 -168.006246) (xy 365.537608 -167.900217) (xy 365.521791 -167.792746)
			(xy 365.513862 -167.684408) (xy 362.31703 -167.684408) (xy 362.31703 -168.974516) (xy 362.317457 -168.984584)
			(xy 362.325179 -169.003182) (xy 362.332016 -169.010584) (xy 363.179106 -169.857674) (xy 363.186504 -169.864522)
			(xy 363.205102 -169.872259) (xy 363.215174 -169.87266)
		)
		(stroke
			(width 0)
			(type solid)
		)
		(fill yes)
		(layer "In7.Cu")
		(net "GND")
	)
	(gr_poly
		(pts
			(xy 77.314298 -170.113198) (xy 77.324368 -170.112775) (xy 77.342973 -170.105061) (xy 77.350366 -170.098212)
			(xy 77.64018 -169.808398) (xy 77.647028 -169.801) (xy 77.654765 -169.782402) (xy 77.655166 -169.77233)
			(xy 77.655166 -164.344096) (xy 77.654741 -164.334027) (xy 77.647022 -164.315427) (xy 77.64018 -164.308028)
			(xy 77.286358 -163.954206) (xy 77.278957 -163.947365) (xy 77.260359 -163.939645) (xy 77.25029 -163.93922)
			(xy 48.277018 -163.93922) (xy 48.266968 -163.938714) (xy 48.248408 -163.930991) (xy 48.24095 -163.924234)
			(xy 46.27245 -161.955734) (xy 46.265608 -161.948334) (xy 46.25789 -161.929736) (xy 46.257464 -161.919666)
			(xy 46.257464 -152.206198) (xy 46.25704 -152.196129) (xy 46.249321 -152.177528) (xy 46.242478 -152.17013)
			(xy 45.903896 -151.831548) (xy 45.8965 -151.824697) (xy 45.877901 -151.816956) (xy 45.867828 -151.816562)
			(xy 39.319962 -151.816562) (xy 39.309896 -151.816994) (xy 39.291308 -151.824725) (xy 39.283894 -151.831548)
			(xy 38.834314 -152.281128) (xy 38.82747 -152.288527) (xy 38.819744 -152.307126) (xy 38.819328 -152.317196)
			(xy 38.819328 -167.684408) (xy 65.513954 -167.684408) (xy 65.513954 -167.57578) (xy 65.521883 -167.467442)
			(xy 65.5377 -167.359971) (xy 65.561319 -167.253942) (xy 65.592615 -167.14992) (xy 65.63142 -167.048459)
			(xy 65.677528 -166.950102) (xy 65.730692 -166.855373) (xy 65.79063 -166.764778) (xy 65.85702 -166.678799)
			(xy 65.92951 -166.597896) (xy 66.007711 -166.5225) (xy 66.091208 -166.453014) (xy 66.179554 -166.389807)
			(xy 66.272278 -166.333219) (xy 66.368886 -166.283549) (xy 66.468861 -166.241064) (xy 66.571671 -166.205991)
			(xy 66.676767 -166.178515) (xy 66.783588 -166.158784) (xy 66.891564 -166.146903) (xy 67.00012 -166.142936)
			(xy 67.108676 -166.146903) (xy 67.216652 -166.158784) (xy 67.323473 -166.178515) (xy 67.428569 -166.205991)
			(xy 67.531379 -166.241064) (xy 67.631354 -166.283549) (xy 67.727962 -166.333219) (xy 67.820686 -166.389807)
			(xy 67.909032 -166.453014) (xy 67.992529 -166.5225) (xy 68.07073 -166.597896) (xy 68.14322 -166.678799)
			(xy 68.20961 -166.764778) (xy 68.269548 -166.855373) (xy 68.322712 -166.950102) (xy 68.36882 -167.048459)
			(xy 68.407625 -167.14992) (xy 68.438921 -167.253942) (xy 68.46254 -167.359971) (xy 68.478357 -167.467442)
			(xy 68.486286 -167.57578) (xy 68.486782 -167.630094) (xy 68.486286 -167.684408) (xy 68.478357 -167.792746)
			(xy 68.46254 -167.900217) (xy 68.438921 -168.006246) (xy 68.407625 -168.110268) (xy 68.36882 -168.211729)
			(xy 68.322712 -168.310086) (xy 68.269548 -168.404815) (xy 68.20961 -168.49541) (xy 68.14322 -168.581389)
			(xy 68.07073 -168.662292) (xy 67.992529 -168.737688) (xy 67.909032 -168.807174) (xy 67.820686 -168.870381)
			(xy 67.727962 -168.926969) (xy 67.631354 -168.976639) (xy 67.531379 -169.019124) (xy 67.428569 -169.054197)
			(xy 67.323473 -169.081673) (xy 67.216652 -169.101404) (xy 67.108676 -169.113285) (xy 67.00012 -169.117252)
			(xy 66.891564 -169.113285) (xy 66.783588 -169.101404) (xy 66.676767 -169.081673) (xy 66.571671 -169.054197)
			(xy 66.468861 -169.019124) (xy 66.368886 -168.976639) (xy 66.272278 -168.926969) (xy 66.179554 -168.870381)
			(xy 66.091208 -168.807174) (xy 66.007711 -168.737688) (xy 65.92951 -168.662292) (xy 65.85702 -168.581389)
			(xy 65.79063 -168.49541) (xy 65.730692 -168.404815) (xy 65.677528 -168.310086) (xy 65.63142 -168.211729)
			(xy 65.592615 -168.110268) (xy 65.561319 -168.006246) (xy 65.5377 -167.900217) (xy 65.521883 -167.792746)
			(xy 65.513954 -167.684408) (xy 38.819328 -167.684408) (xy 38.819328 -169.581576) (xy 38.819766 -169.591639)
			(xy 38.827503 -169.610221) (xy 38.834314 -169.617644) (xy 39.299896 -170.083226) (xy 39.307291 -170.090081)
			(xy 39.325889 -170.097829) (xy 39.335964 -170.098212) (xy 48.668432 -170.098212) (xy 48.678499 -170.098641)
			(xy 48.697094 -170.106365) (xy 48.7045 -170.113198)
		)
		(stroke
			(width 0)
			(type solid)
		)
		(fill yes)
		(layer "In7.Cu")
		(net "GND")
	)
	(gr_poly
		(pts
			(arc
				(start 311.736486 -85.2932)
				(mid 311.756009 -85.289299)
				(end 311.772554 -85.278214)
			)
			(arc
				(start 314.501022 -82.549746)
				(mid 314.517556 -82.538635)
				(end 314.53709 -82.53476)
			)
			(arc
				(start 325.345806 -82.53476)
				(mid 325.365329 -82.530859)
				(end 325.381874 -82.519774)
			)
			(arc
				(start 327.477374 -80.424274)
				(mid 327.488485 -80.40774)
				(end 327.49236 -80.388206)
			)
			(arc
				(start 327.49236 -52.198778)
				(mid 327.496261 -52.179255)
				(end 327.507346 -52.16271)
			)
			(arc
				(start 329.088496 -50.58156)
				(mid 329.10503 -50.570449)
				(end 329.124564 -50.566574)
			)
			(arc
				(start 336.27695 -50.566574)
				(mid 336.296473 -50.562673)
				(end 336.313018 -50.551588)
			)
			(arc
				(start 337.158838 -49.705768)
				(mid 337.169949 -49.689234)
				(end 337.173824 -49.6697)
			)
			(arc
				(start 337.173824 -48.507396)
				(mid 337.169923 -48.487873)
				(end 337.158838 -48.471328)
			)
			(arc
				(start 336.625692 -47.938182)
				(mid 336.609158 -47.927071)
				(end 336.589624 -47.923196)
			)
			(arc
				(start 327.982326 -47.923196)
				(mid 327.962803 -47.919295)
				(end 327.946258 -47.90821)
			)
			(arc
				(start 327.507346 -47.469298)
				(mid 327.496235 -47.452764)
				(end 327.49236 -47.43323)
			)
			(arc
				(start 327.49236 -41.12514)
				(mid 327.496261 -41.105617)
				(end 327.507346 -41.089072)
			)
			(arc
				(start 329.307444 -39.288974)
				(mid 329.323978 -39.277863)
				(end 329.343512 -39.273988)
			)
			(arc
				(start 336.746088 -39.273988)
				(mid 336.765611 -39.270087)
				(end 336.782156 -39.259002)
			)
			(arc
				(start 336.924142 -39.117016)
				(mid 336.935253 -39.100482)
				(end 336.939128 -39.080948)
			)
			(arc
				(start 336.939128 -37.183314)
				(mid 336.935227 -37.163791)
				(end 336.924142 -37.147246)
			)
			(arc
				(start 336.875882 -37.098986)
				(mid 336.859348 -37.087875)
				(end 336.839814 -37.084)
			)
			(arc
				(start 326.027288 -37.084)
				(mid 326.007765 -37.087901)
				(end 325.99122 -37.098986)
			)
			(arc
				(start 325.473822 -37.616384)
				(mid 325.462711 -37.632918)
				(end 325.458836 -37.652452)
			)
			(arc
				(start 325.458836 -79.746856)
				(mid 325.454935 -79.766379)
				(end 325.44385 -79.782924)
			)
			(arc
				(start 324.36308 -80.863694)
				(mid 324.346546 -80.874805)
				(end 324.327012 -80.87868)
			)
			(arc
				(start 312.010044 -80.87868)
				(mid 311.990521 -80.882581)
				(end 311.973976 -80.893666)
			)
			(arc
				(start 308.910228 -83.957414)
				(mid 308.893694 -83.968525)
				(end 308.87416 -83.9724)
			)
			(arc
				(start 269.870682 -83.9724)
				(mid 269.851159 -83.968499)
				(end 269.834614 -83.957414)
			)
			(arc
				(start 266.486386 -80.609186)
				(mid 266.475275 -80.592652)
				(end 266.4714 -80.573118)
			)
			(arc
				(start 266.4714 -74.314812)
				(mid 266.469988 -74.302919)
				(end 266.465812 -74.291698)
			)
			(arc
				(start 266.465812 -74.291698)
				(mid 266.393719 -74.095852)
				(end 266.369292 -73.8886)
			)
			(arc
				(start 266.369292 -73.8886)
				(mid 266.393771 -73.68136)
				(end 266.465812 -73.485502)
			)
			(arc
				(start 266.465812 -73.485502)
				(mid 266.469967 -73.474275)
				(end 266.4714 -73.462388)
			)
			(arc
				(start 266.4714 -70.734682)
				(mid 266.467499 -70.715159)
				(end 266.456414 -70.698614)
			)
			(arc
				(start 266.029186 -70.271386)
				(mid 266.012652 -70.260275)
				(end 265.993118 -70.2564)
			)
			(arc
				(start 264.816082 -70.2564)
				(mid 264.796559 -70.260301)
				(end 264.780014 -70.271386)
			)
			(arc
				(start 264.530586 -70.520814)
				(mid 264.519475 -70.537348)
				(end 264.5156 -70.556882)
			)
			(arc
				(start 264.5156 -81.106518)
				(mid 264.519501 -81.126041)
				(end 264.530586 -81.142586)
			)
			(arc
				(start 268.666214 -85.278214)
				(mid 268.682748 -85.289325)
				(end 268.702282 -85.2932)
			)
		)
		(stroke
			(width 0)
			(type solid)
		)
		(fill yes)
		(layer "In7.Cu")
		(net "P52V_HS1_1272_GATE")
	)
	(gr_poly
		(pts
			(xy 133.989318 -86.5632) (xy 133.999387 -86.562773) (xy 134.017986 -86.555054) (xy 134.025386 -86.548214)
			(xy 136.643872 -83.929728) (xy 136.651273 -83.92289) (xy 136.669872 -83.915177) (xy 136.67994 -83.914742)
			(xy 156.686504 -83.914742) (xy 156.692293 -83.914615) (xy 156.703582 -83.912051) (xy 156.708856 -83.909662)
			(xy 156.745359 -83.892353) (xy 156.820877 -83.863644) (xy 156.898687 -83.841896) (xy 156.978147 -83.827287)
			(xy 157.058604 -83.819939) (xy 157.099 -83.819492) (xy 157.139397 -83.819945) (xy 157.219857 -83.827269)
			(xy 157.299321 -83.841867) (xy 157.377131 -83.863617) (xy 157.452646 -83.892341) (xy 157.489144 -83.909662)
			(xy 157.494422 -83.912042) (xy 157.505708 -83.914614) (xy 157.511496 -83.914742) (xy 160.37052 -83.914742)
			(xy 160.380587 -83.914314) (xy 160.399181 -83.906588) (xy 160.406588 -83.899756) (xy 161.808414 -82.49793)
			(xy 161.815259 -82.490532) (xy 161.822981 -82.471933) (xy 161.8234 -82.461862) (xy 161.8234 -76.268834)
			(xy 161.823835 -76.258769) (xy 161.831567 -76.240182) (xy 161.838386 -76.232766) (xy 164.446204 -73.624948)
			(xy 164.453042 -73.617546) (xy 164.460757 -73.598948) (xy 164.46119 -73.58888) (xy 164.46119 -67.207892)
			(xy 164.461614 -67.197822) (xy 164.469329 -67.179219) (xy 164.476176 -67.171824) (xy 165.593014 -66.054986)
			(xy 165.600409 -66.048132) (xy 165.619008 -66.04039) (xy 165.629082 -66.04) (xy 165.675564 -66.04)
			(xy 165.688264 -66.036444) (xy 165.694106 -66.033142) (xy 165.728084 -66.013865) (xy 165.7988 -65.980656)
			(xy 165.872157 -65.953777) (xy 165.947588 -65.933434) (xy 166.024512 -65.919784) (xy 166.102337 -65.912933)
			(xy 166.1414 -65.912492) (xy 166.180613 -65.912933) (xy 166.258732 -65.919858) (xy 166.335939 -65.933629)
			(xy 166.411636 -65.954138) (xy 166.485234 -65.981227) (xy 166.520876 -65.997582) (xy 166.531316 -66.001892)
			(xy 166.55387 -66.001892) (xy 166.56431 -65.997582) (xy 166.599953 -65.981228) (xy 166.673546 -65.954121)
			(xy 166.749242 -65.933604) (xy 166.826451 -65.919836) (xy 166.904573 -65.912925) (xy 166.943786 -65.912492)
			(xy 166.981768 -65.912878) (xy 167.057456 -65.919333) (xy 167.132318 -65.932223) (xy 167.205807 -65.951454)
			(xy 167.241728 -65.9638) (xy 167.253664 -65.967372) (xy 167.278286 -65.963758) (xy 167.288718 -65.956942)
			(xy 167.321366 -65.933619) (xy 167.390142 -65.892283) (xy 167.462361 -65.857311) (xy 167.537437 -65.828986)
			(xy 167.61476 -65.80754) (xy 167.6937 -65.793146) (xy 167.773615 -65.785921) (xy 167.813736 -65.785492)
			(xy 167.855633 -65.785976) (xy 167.939055 -65.793861) (xy 168.021366 -65.809557) (xy 168.101835 -65.832925)
			(xy 168.17975 -65.863758) (xy 168.254419 -65.901783) (xy 168.325182 -65.946662) (xy 168.391409 -65.997998)
			(xy 168.42232 -66.026284) (xy 168.429612 -66.032563) (xy 168.447503 -66.039607) (xy 168.457118 -66.04)
			(xy 172.713142 -66.04) (xy 172.742606 -66.011298) (xy 172.743114 -65.990724) (xy 172.744892 -65.947896)
			(xy 172.755651 -65.862851) (xy 172.774539 -65.779235) (xy 172.80138 -65.697822) (xy 172.835926 -65.619368)
			(xy 172.877856 -65.544599) (xy 172.926781 -65.47421) (xy 172.982249 -65.408851) (xy 173.043745 -65.349129)
			(xy 173.110699 -65.295598) (xy 173.182491 -65.248753) (xy 173.258455 -65.209029) (xy 173.337886 -65.176794)
			(xy 173.420049 -65.152348) (xy 173.504183 -65.135915) (xy 173.589507 -65.127649) (xy 173.632368 -65.127124)
			(xy 173.672889 -65.127602) (xy 173.753592 -65.135004) (xy 173.833288 -65.149715) (xy 173.911316 -65.17161)
			(xy 173.98703 -65.200511) (xy 174.059802 -65.236176) (xy 174.12903 -65.278311) (xy 174.19414 -65.326566)
			(xy 174.224696 -65.353184) (xy 174.232062 -65.359534) (xy 174.250096 -65.366138) (xy 174.339504 -65.363852)
			(xy 174.357284 -65.356232) (xy 174.364142 -65.349374) (xy 174.395378 -65.31898) (xy 174.462825 -65.263774)
			(xy 174.535348 -65.21543) (xy 174.612252 -65.174413) (xy 174.692801 -65.141115) (xy 174.77622 -65.115856)
			(xy 174.86171 -65.098879) (xy 174.94845 -65.090346) (xy 174.99203 -65.089786) (xy 175.034975 -65.090304)
			(xy 175.120466 -65.098587) (xy 175.20476 -65.115073) (xy 175.287072 -65.139608) (xy 175.366635 -65.171963)
			(xy 175.442709 -65.211838) (xy 175.514584 -65.258861) (xy 175.581592 -65.312594) (xy 175.643108 -65.372536)
			(xy 175.671226 -65.405) (xy 175.678864 -65.413182) (xy 175.699161 -65.422551) (xy 175.710342 -65.423034)
			(xy 175.715676 -65.423034) (xy 175.757412 -65.423513) (xy 175.840516 -65.431341) (xy 175.92252 -65.446922)
			(xy 176.002704 -65.470117) (xy 176.080362 -65.500724) (xy 176.15481 -65.538473) (xy 176.225394 -65.583031)
			(xy 176.291492 -65.634007) (xy 176.352523 -65.690952) (xy 176.40795 -65.753365) (xy 176.457285 -65.820697)
			(xy 176.500094 -65.892355) (xy 176.536001 -65.967709) (xy 176.550828 -66.006726) (xy 176.55486 -66.016295)
			(xy 176.569134 -66.031347) (xy 176.588206 -66.039505) (xy 176.59858 -66.04) (xy 178.693572 -66.04)
			(xy 178.703876 -66.039522) (xy 178.722818 -66.031402) (xy 178.737019 -66.016468) (xy 178.74107 -66.00698)
			(xy 178.756083 -65.968319) (xy 178.792317 -65.893711) (xy 178.835339 -65.822801) (xy 178.884776 -65.756203)
			(xy 178.940197 -65.694497) (xy 179.001123 -65.638218) (xy 179.067023 -65.587855) (xy 179.137325 -65.543845)
			(xy 179.211419 -65.506571) (xy 179.288661 -65.476357) (xy 179.36838 -65.453464) (xy 179.449884 -65.438092)
			(xy 179.532465 -65.430375) (xy 179.573936 -65.429892) (xy 179.612364 -65.430312) (xy 179.68893 -65.436969)
			(xy 179.764638 -65.450205) (xy 179.838922 -65.46992) (xy 179.911228 -65.495969) (xy 179.9463 -65.51168)
			(xy 179.956573 -65.51582) (xy 179.978699 -65.51582) (xy 179.988972 -65.51168) (xy 180.024036 -65.49595)
			(xy 180.096343 -65.469895) (xy 180.170628 -65.450178) (xy 180.246338 -65.436946) (xy 180.322907 -65.430298)
			(xy 180.361336 -65.429892) (xy 180.402437 -65.430368) (xy 180.484289 -65.437956) (xy 180.565092 -65.453064)
			(xy 180.644156 -65.475562) (xy 180.720807 -65.50526) (xy 180.794391 -65.541903) (xy 180.86428 -65.585179)
			(xy 180.929878 -65.634719) (xy 180.990626 -65.6901) (xy 181.046004 -65.750849) (xy 181.095542 -65.81645)
			(xy 181.138815 -65.88634) (xy 181.175455 -65.959926) (xy 181.205149 -66.036578) (xy 181.227645 -66.115643)
			(xy 181.242749 -66.196446) (xy 181.250333 -66.278299) (xy 181.250844 -66.3194) (xy 181.250343 -66.361703)
			(xy 181.24231 -66.445927) (xy 181.226318 -66.529008) (xy 181.20251 -66.610195) (xy 181.171102 -66.688756)
			(xy 181.132377 -66.763979) (xy 181.086685 -66.835186) (xy 181.03444 -66.901734) (xy 180.976112 -66.963021)
			(xy 180.912229 -67.018493) (xy 180.843368 -67.06765) (xy 180.770152 -67.110047) (xy 180.693241 -67.145302)
			(xy 180.653436 -67.159632) (xy 180.643687 -67.163579) (xy 180.628284 -67.177866) (xy 180.619908 -67.197132)
			(xy 180.6194 -67.207638) (xy 180.6194 -69.701918) (xy 180.619827 -69.711987) (xy 180.627546 -69.730586)
			(xy 180.634386 -69.737986) (xy 180.985414 -70.089014) (xy 180.992809 -70.095868) (xy 181.011408 -70.10361)
			(xy 181.021482 -70.104) (xy 183.011318 -70.104) (xy 183.021387 -70.103573) (xy 183.039986 -70.095854)
			(xy 183.047386 -70.089014) (xy 183.271414 -69.864986) (xy 183.278268 -69.857591) (xy 183.28601 -69.838992)
			(xy 183.2864 -69.828918) (xy 183.2864 -65.045082) (xy 183.285973 -65.035013) (xy 183.278254 -65.016414)
			(xy 183.271414 -65.009014) (xy 182.539386 -64.276986) (xy 182.531991 -64.270132) (xy 182.513392 -64.26239)
			(xy 182.503318 -64.262) (xy 165.960806 -64.262) (xy 165.951515 -64.262419) (xy 165.934152 -64.269041)
			(xy 165.920266 -64.28139) (xy 165.915594 -64.289432) (xy 165.898159 -64.322346) (xy 165.858567 -64.385441)
			(xy 165.81384 -64.445006) (xy 165.789356 -64.473074) (xy 165.782372 -64.481774) (xy 165.77593 -64.503108)
			(xy 165.77691 -64.514222) (xy 165.781309 -64.546235) (xy 165.78601 -64.610688) (xy 165.786308 -64.643)
			(xy 165.785804 -64.685348) (xy 165.777753 -64.769662) (xy 165.761724 -64.852828) (xy 165.737863 -64.934095)
			(xy 165.706384 -65.012725) (xy 165.667573 -65.088006) (xy 165.621783 -65.159258) (xy 165.569427 -65.225834)
			(xy 165.510979 -65.287132) (xy 165.446969 -65.342597) (xy 165.377977 -65.391726) (xy 165.304627 -65.434075)
			(xy 165.227584 -65.469259) (xy 165.147545 -65.496961) (xy 165.065236 -65.516929) (xy 164.981401 -65.528982)
			(xy 164.8968 -65.533013) (xy 164.812199 -65.528982) (xy 164.728364 -65.516929) (xy 164.646055 -65.496961)
			(xy 164.566016 -65.469259) (xy 164.488973 -65.434075) (xy 164.415623 -65.391726) (xy 164.346631 -65.342597)
			(xy 164.282621 -65.287132) (xy 164.224173 -65.225834) (xy 164.171817 -65.159258) (xy 164.126027 -65.088006)
			(xy 164.087216 -65.012725) (xy 164.055737 -64.934095) (xy 164.031876 -64.852828) (xy 164.015847 -64.769662)
			(xy 164.007796 -64.685348) (xy 164.007292 -64.643) (xy 164.007781 -64.600634) (xy 164.015839 -64.516286)
			(xy 164.031883 -64.433087) (xy 164.04336 -64.392302) (xy 164.046916 -64.380618) (xy 164.042598 -64.35725)
			(xy 163.986464 -64.28232) (xy 163.978863 -64.273211) (xy 163.957672 -64.262605) (xy 163.945824 -64.262)
			(xy 160.955482 -64.262) (xy 160.945413 -64.262427) (xy 160.926814 -64.270146) (xy 160.919414 -64.276986)
			(xy 159.679386 -65.517014) (xy 159.672532 -65.524409) (xy 159.66479 -65.543008) (xy 159.6644 -65.553082)
			(xy 159.6644 -68.326) (xy 161.844228 -68.326) (xy 161.844719 -68.284495) (xy 161.852455 -68.201845)
			(xy 161.86786 -68.120276) (xy 161.8908 -68.040498) (xy 161.921075 -67.963205) (xy 161.958422 -67.88907)
			(xy 162.002515 -67.818738) (xy 162.027362 -67.785488) (xy 162.033707 -67.77629) (xy 162.03854 -67.7545)
			(xy 162.033707 -67.73271) (xy 162.027362 -67.723512) (xy 162.00252 -67.690258) (xy 161.958422 -67.619928)
			(xy 161.921072 -67.545795) (xy 161.890794 -67.468502) (xy 161.867852 -67.388724) (xy 161.852445 -67.307155)
			(xy 161.844708 -67.224506) (xy 161.844228 -67.183) (xy 161.844649 -67.144107) (xy 161.851436 -67.066618)
			(xy 161.864967 -66.990018) (xy 161.885139 -66.914894) (xy 161.911796 -66.841819) (xy 161.944736 -66.771352)
			(xy 161.963862 -66.737484) (xy 161.968828 -66.727979) (xy 161.971057 -66.706668) (xy 161.96818 -66.696336)
			(xy 161.9543 -66.651776) (xy 161.934859 -66.560489) (xy 161.925085 -66.467667) (xy 161.924492 -66.421)
			(xy 161.924996 -66.378652) (xy 161.933047 -66.294338) (xy 161.949076 -66.211172) (xy 161.972937 -66.129905)
			(xy 162.004416 -66.051275) (xy 162.043227 -65.975994) (xy 162.089017 -65.904742) (xy 162.141373 -65.838166)
			(xy 162.199821 -65.776868) (xy 162.263831 -65.721403) (xy 162.332823 -65.672274) (xy 162.406173 -65.629925)
			(xy 162.483216 -65.594741) (xy 162.563255 -65.567039) (xy 162.645564 -65.547071) (xy 162.729399 -65.535018)
			(xy 162.814 -65.530988) (xy 162.898601 -65.535018) (xy 162.982436 -65.547071) (xy 163.064745 -65.567039)
			(xy 163.144784 -65.594741) (xy 163.221827 -65.629925) (xy 163.295177 -65.672274) (xy 163.364169 -65.721403)
			(xy 163.428179 -65.776868) (xy 163.486627 -65.838166) (xy 163.538983 -65.904742) (xy 163.584773 -65.975994)
			(xy 163.623584 -66.051275) (xy 163.655063 -66.129905) (xy 163.678924 -66.211172) (xy 163.694953 -66.294338)
			(xy 163.703004 -66.378652) (xy 163.703508 -66.421) (xy 163.703095 -66.459893) (xy 163.696308 -66.537383)
			(xy 163.682776 -66.613983) (xy 163.662603 -66.689107) (xy 163.635943 -66.762182) (xy 163.603001 -66.832649)
			(xy 163.583874 -66.866516) (xy 163.578907 -66.87602) (xy 163.576681 -66.897332) (xy 163.579556 -66.907664)
			(xy 163.593437 -66.952223) (xy 163.612877 -67.043511) (xy 163.622651 -67.136333) (xy 163.623244 -67.183)
			(xy 163.622739 -67.224505) (xy 163.615003 -67.307154) (xy 163.599599 -67.388722) (xy 163.576661 -67.4685)
			(xy 163.546389 -67.545793) (xy 163.509045 -67.619928) (xy 163.464956 -67.690262) (xy 163.44011 -67.723512)
			(xy 163.433768 -67.732711) (xy 163.428938 -67.7545) (xy 163.433768 -67.776289) (xy 163.44011 -67.785488)
			(xy 163.464948 -67.818745) (xy 163.509047 -67.889074) (xy 163.546398 -67.963207) (xy 163.576677 -68.040499)
			(xy 163.59962 -68.120276) (xy 163.615027 -68.201845) (xy 163.622764 -68.284494) (xy 163.623244 -68.326)
			(xy 163.62274 -68.368348) (xy 163.614689 -68.452662) (xy 163.59866 -68.535828) (xy 163.574799 -68.617095)
			(xy 163.54332 -68.695725) (xy 163.504509 -68.771006) (xy 163.458719 -68.842258) (xy 163.406363 -68.908834)
			(xy 163.347915 -68.970132) (xy 163.283905 -69.025597) (xy 163.214913 -69.074726) (xy 163.141563 -69.117075)
			(xy 163.06452 -69.152259) (xy 162.984481 -69.179961) (xy 162.902172 -69.199929) (xy 162.818337 -69.211982)
			(xy 162.733736 -69.216013) (xy 162.649135 -69.211982) (xy 162.5653 -69.199929) (xy 162.482991 -69.179961)
			(xy 162.402952 -69.152259) (xy 162.325909 -69.117075) (xy 162.252559 -69.074726) (xy 162.183567 -69.025597)
			(xy 162.119557 -68.970132) (xy 162.061109 -68.908834) (xy 162.008753 -68.842258) (xy 161.962963 -68.771006)
			(xy 161.924152 -68.695725) (xy 161.892673 -68.617095) (xy 161.868812 -68.535828) (xy 161.852783 -68.452662)
			(xy 161.844732 -68.368348) (xy 161.844228 -68.326) (xy 159.6644 -68.326) (xy 159.6644 -68.961) (xy 159.664633 -68.968269)
			(xy 159.668771 -68.982204) (xy 159.672528 -68.988432) (xy 159.694925 -69.024303) (xy 159.733601 -69.099514)
			(xy 159.764968 -69.178055) (xy 159.788743 -69.259217) (xy 159.804712 -69.342268) (xy 159.81273 -69.42646)
			(xy 159.813244 -69.468746) (xy 159.811466 -69.524626) (xy 159.81125 -69.534322) (xy 159.817245 -69.552749)
			(xy 159.82315 -69.56044) (xy 159.842708 -69.583808) (xy 159.849217 -69.590964) (xy 159.866191 -69.600213)
			(xy 159.875728 -69.601842) (xy 159.918432 -69.607439) (xy 160.002575 -69.625845) (xy 160.084544 -69.652298)
			(xy 160.163573 -69.68655) (xy 160.238922 -69.728279) (xy 160.309885 -69.777095) (xy 160.375798 -69.832541)
			(xy 160.436044 -69.894099) (xy 160.490057 -69.96119) (xy 160.537334 -70.033188) (xy 160.577431 -70.109418)
			(xy 160.609972 -70.189167) (xy 160.634654 -70.271687) (xy 160.651244 -70.356207) (xy 160.659588 -70.441934)
			(xy 160.66008 -70.485) (xy 160.659562 -70.527976) (xy 160.651272 -70.613527) (xy 160.634769 -70.697879)
			(xy 160.610207 -70.780247) (xy 160.577815 -70.859861) (xy 160.537895 -70.93598) (xy 160.49082 -71.007894)
			(xy 160.437027 -71.074932) (xy 160.37702 -71.136469) (xy 160.311357 -71.191931) (xy 160.276286 -71.216774)
			(xy 160.26384 -71.22541) (xy 160.25241 -71.252842) (xy 160.254852 -71.26605) (xy 161.589718 -71.26605)
			(xy 161.593789 -71.210428) (xy 161.605915 -71.155991) (xy 161.625838 -71.1039) (xy 161.653134 -71.055265)
			(xy 161.68722 -71.011122) (xy 161.727369 -70.972413) (xy 161.772727 -70.939962) (xy 161.822327 -70.914461)
			(xy 161.875111 -70.896454) (xy 161.929954 -70.886324) (xy 161.985688 -70.884287) (xy 162.041125 -70.890387)
			(xy 162.095082 -70.904493) (xy 162.146411 -70.926305) (xy 162.194017 -70.955359) (xy 162.236885 -70.991034)
			(xy 162.274102 -71.032571) (xy 162.304875 -71.079084) (xy 162.328547 -71.129581) (xy 162.344615 -71.182988)
			(xy 162.352735 -71.238164) (xy 162.353244 -71.26605) (xy 162.352735 -71.293936) (xy 162.344615 -71.349112)
			(xy 162.328547 -71.402519) (xy 162.304875 -71.453016) (xy 162.274102 -71.499529) (xy 162.236885 -71.541066)
			(xy 162.194017 -71.576741) (xy 162.146411 -71.605795) (xy 162.095082 -71.627607) (xy 162.041125 -71.641713)
			(xy 161.985688 -71.647813) (xy 161.929954 -71.645776) (xy 161.875111 -71.635646) (xy 161.822327 -71.617639)
			(xy 161.772727 -71.592138) (xy 161.727369 -71.559687) (xy 161.68722 -71.520978) (xy 161.653134 -71.476835)
			(xy 161.625838 -71.4282) (xy 161.605915 -71.376109) (xy 161.593789 -71.321672) (xy 161.589718 -71.26605)
			(xy 160.254852 -71.26605) (xy 160.274762 -71.373746) (xy 160.295082 -71.395336) (xy 160.309814 -71.399146)
			(xy 160.350762 -71.409676) (xy 160.430619 -71.43747) (xy 160.507477 -71.47272) (xy 160.58064 -71.515108)
			(xy 160.649449 -71.56425) (xy 160.713281 -71.619704) (xy 160.771561 -71.680967) (xy 160.82376 -71.747486)
			(xy 160.869409 -71.818661) (xy 160.908094 -71.893848) (xy 160.939466 -71.972368) (xy 160.963241 -72.053512)
			(xy 160.979206 -72.136547) (xy 160.987214 -72.220722) (xy 160.98774 -72.263) (xy 160.987265 -72.304103)
			(xy 160.979681 -72.385958) (xy 160.964576 -72.466765) (xy 160.942079 -72.545833) (xy 160.912384 -72.622488)
			(xy 160.875742 -72.696076) (xy 160.832467 -72.76597) (xy 160.782928 -72.831572) (xy 160.727547 -72.892324)
			(xy 160.666797 -72.947707) (xy 160.601196 -72.997249) (xy 160.531304 -73.040526) (xy 160.457717 -73.077171)
			(xy 160.381063 -73.106869) (xy 160.301996 -73.129368) (xy 160.22119 -73.144476) (xy 160.139335 -73.152064)
			(xy 160.098232 -73.152508) (xy 160.060214 -73.152096) (xy 159.984456 -73.145582) (xy 159.909532 -73.132626)
			(xy 159.835987 -73.11332) (xy 159.800036 -73.100946) (xy 159.788098 -73.096882) (xy 159.763968 -73.100184)
			(xy 159.68599 -73.155302) (xy 159.6764 -73.162874) (xy 159.665123 -73.184506) (xy 159.6644 -73.196704)
			(xy 159.6644 -81.052924) (xy 159.663972 -81.062992) (xy 159.656252 -81.08159) (xy 159.649414 -81.088992)
			(xy 158.923482 -81.814924) (xy 158.916086 -81.821776) (xy 158.897487 -81.829516) (xy 158.887414 -81.82991)
			(xy 135.767572 -81.82991) (xy 135.757504 -81.830339) (xy 135.738908 -81.838061) (xy 135.731504 -81.844896)
			(xy 133.161786 -84.414614) (xy 133.154391 -84.421468) (xy 133.135792 -84.42921) (xy 133.125718 -84.4296)
			(xy 131.635754 -84.4296) (xy 131.629912 -84.431124) (xy 131.578734 -84.442569) (xy 131.474577 -84.454791)
			(xy 131.42214 -84.455508) (xy 131.369702 -84.454808) (xy 131.265542 -84.442589) (xy 131.214368 -84.431124)
			(xy 131.208526 -84.4296) (xy 128.8161 -84.4296) (xy 128.810258 -84.431124) (xy 128.759081 -84.442571)
			(xy 128.654923 -84.454799) (xy 128.602486 -84.455508) (xy 128.550048 -84.454805) (xy 128.44589 -84.442579)
			(xy 128.394714 -84.431124) (xy 128.388872 -84.4296) (xy 127.766572 -84.4296) (xy 127.756504 -84.429172)
			(xy 127.737907 -84.42145) (xy 127.730504 -84.414614) (xy 125.160786 -81.844896) (xy 125.153386 -81.838052)
			(xy 125.134789 -81.830324) (xy 125.124718 -81.82991) (xy 123.454414 -81.82991) (xy 123.44435 -81.829472)
			(xy 123.425768 -81.821736) (xy 123.418346 -81.814924) (xy 122.376692 -80.77327) (xy 122.369851 -80.765869)
			(xy 122.362129 -80.747271) (xy 122.361706 -80.737202) (xy 122.361706 -43.471592) (xy 122.361282 -43.461522)
			(xy 122.353566 -43.442919) (xy 122.34672 -43.435524) (xy 121.483882 -42.572686) (xy 121.476487 -42.565833)
			(xy 121.457888 -42.558092) (xy 121.447814 -42.5577) (xy 109.500924 -42.5577) (xy 109.49086 -42.558137)
			(xy 109.472276 -42.565871) (xy 109.464856 -42.572686) (xy 109.408722 -42.62882) (xy 109.401876 -42.636219)
			(xy 109.394146 -42.654817) (xy 109.393736 -42.664888) (xy 109.393736 -44.075604) (xy 109.394161 -44.085673)
			(xy 109.40188 -44.104273) (xy 109.408722 -44.111672) (xy 109.993176 -44.696126) (xy 110.000575 -44.702968)
			(xy 110.019174 -44.710687) (xy 110.029244 -44.711112) (xy 111.736378 -44.711112) (xy 111.762794 -44.691808)
			(xy 111.768128 -44.675806) (xy 111.778365 -44.645418) (xy 111.805437 -44.587288) (xy 111.839606 -44.533025)
			(xy 111.880327 -44.48349) (xy 111.926955 -44.43947) (xy 111.97875 -44.401664) (xy 112.034888 -44.370672)
			(xy 112.094478 -44.346987) (xy 112.156574 -44.330985) (xy 112.22019 -44.32292) (xy 112.284314 -44.32292)
			(xy 112.34793 -44.330985) (xy 112.410026 -44.346987) (xy 112.469616 -44.370672) (xy 112.525754 -44.401664)
			(xy 112.577549 -44.43947) (xy 112.624177 -44.48349) (xy 112.664898 -44.533025) (xy 112.699067 -44.587288)
			(xy 112.726139 -44.645418) (xy 112.736376 -44.675806) (xy 112.74171 -44.691808) (xy 112.768126 -44.711112)
			(xy 118.36908 -44.711112) (xy 118.379143 -44.71155) (xy 118.397726 -44.719286) (xy 118.405148 -44.726098)
			(xy 119.919496 -46.240446) (xy 119.926336 -46.247847) (xy 119.934054 -46.266445) (xy 119.934482 -46.276514)
			(xy 119.934482 -52.41163) (xy 119.934053 -52.421697) (xy 119.926329 -52.440292) (xy 119.919496 -52.447698)
			(xy 119.303292 -53.063902) (xy 119.295893 -53.070747) (xy 119.277295 -53.078478) (xy 119.267224 -53.078888)
			(xy 110.941612 -53.078888) (xy 110.931541 -53.079308) (xy 110.912932 -53.087018) (xy 110.905544 -53.093874)
			(xy 110.415578 -53.58384) (xy 110.408729 -53.591237) (xy 110.400997 -53.609836) (xy 110.400592 -53.619908)
			(xy 110.400592 -55.200804) (xy 110.401015 -55.210874) (xy 110.40873 -55.229478) (xy 110.415578 -55.236872)
			(xy 110.984538 -55.805832) (xy 110.991935 -55.81268) (xy 111.010534 -55.820411) (xy 111.020606 -55.820818)
			(xy 111.80699 -55.820818) (xy 111.81881 -55.820266) (xy 111.839998 -55.809796) (xy 111.84763 -55.800752)
			(xy 111.866897 -55.776193) (xy 111.910474 -55.731501) (xy 111.959197 -55.692481) (xy 112.012332 -55.659723)
			(xy 112.069078 -55.633718) (xy 112.128582 -55.614858) (xy 112.189948 -55.603427) (xy 112.252252 -55.599598)
			(xy 112.314556 -55.603427) (xy 112.375922 -55.614858) (xy 112.435426 -55.633718) (xy 112.492172 -55.659723)
			(xy 112.545307 -55.692481) (xy 112.59403 -55.731501) (xy 112.637607 -55.776193) (xy 112.656874 -55.800752)
			(xy 112.664521 -55.809772) (xy 112.685703 -55.820218) (xy 112.697514 -55.820818) (xy 118.857776 -55.820818)
			(xy 118.86784 -55.821255) (xy 118.886422 -55.828991) (xy 118.893844 -55.835804) (xy 119.919496 -56.861456)
			(xy 119.926334 -56.868857) (xy 119.934049 -56.887456) (xy 119.934482 -56.897524) (xy 119.934482 -83.263232)
			(xy 119.93491 -83.2733) (xy 119.942631 -83.291898) (xy 119.949468 -83.2993) (xy 120.549924 -83.899756)
			(xy 120.557322 -83.906604) (xy 120.57592 -83.914336) (xy 120.585992 -83.914742) (xy 124.311918 -83.914742)
			(xy 124.321986 -83.91517) (xy 124.340581 -83.922893) (xy 124.347986 -83.929728) (xy 126.966472 -86.548214)
			(xy 126.97387 -86.555058) (xy 126.99247 -86.56278) (xy 127.00254 -86.5632)
		)
		(stroke
			(width 0)
			(type solid)
		)
		(fill yes)
		(layer "In7.Cu")
		(net "P52V_HS2_1272_GATE")
	)
	(gr_poly
		(pts
			(xy 341.050118 -98.4758) (xy 341.059995 -98.47534) (xy 341.078294 -98.467897) (xy 341.085678 -98.461322)
			(xy 341.085932 -98.461068) (xy 343.178384 -96.368616) (xy 343.178892 -96.368108) (xy 343.185464 -96.360723)
			(xy 343.192895 -96.342424) (xy 343.19337 -96.332548) (xy 343.19337 -83.840828) (xy 343.192933 -83.830764)
			(xy 343.185197 -83.812182) (xy 343.178384 -83.80476) (xy 341.969344 -82.59572) (xy 341.962232 -82.588354)
			(xy 341.943436 -82.580734) (xy 338.707984 -82.580734) (xy 338.697916 -82.581161) (xy 338.679319 -82.588883)
			(xy 338.671916 -82.59572) (xy 334.973422 -86.294214) (xy 334.966023 -86.301057) (xy 334.947424 -86.308777)
			(xy 334.937354 -86.3092) (xy 295.732962 -86.3092) (xy 295.721947 -86.309748) (xy 295.701944 -86.318977)
			(xy 295.694354 -86.32698) (xy 295.644062 -86.385908) (xy 295.637357 -86.394651) (xy 295.631435 -86.415849)
			(xy 295.632632 -86.426802) (xy 295.634882 -86.44175) (xy 295.6373 -86.471884) (xy 295.637458 -86.487)
			(xy 295.636972 -86.514251) (xy 295.629216 -86.568199) (xy 295.613861 -86.620494) (xy 295.591219 -86.670071)
			(xy 295.561753 -86.715921) (xy 295.526062 -86.757112) (xy 295.484871 -86.792803) (xy 295.439021 -86.822269)
			(xy 295.389444 -86.844911) (xy 295.337149 -86.860266) (xy 295.283201 -86.868022) (xy 295.228699 -86.868022)
			(xy 295.174751 -86.860266) (xy 295.122456 -86.844911) (xy 295.072879 -86.822269) (xy 295.027029 -86.792803)
			(xy 294.985838 -86.757112) (xy 294.950147 -86.715921) (xy 294.920681 -86.670071) (xy 294.898039 -86.620494)
			(xy 294.882684 -86.568199) (xy 294.874928 -86.514251) (xy 294.874442 -86.487) (xy 294.8746 -86.471884)
			(xy 294.877014 -86.441749) (xy 294.879268 -86.426802) (xy 294.880492 -86.415849) (xy 294.874554 -86.394649)
			(xy 294.867838 -86.385908) (xy 294.817546 -86.32698) (xy 294.809976 -86.318951) (xy 294.789959 -86.309717)
			(xy 294.778938 -86.3092) (xy 283.612082 -86.3092) (xy 283.602013 -86.309627) (xy 283.583414 -86.317346)
			(xy 283.576014 -86.324186) (xy 283.326586 -86.573614) (xy 283.31922 -86.580726) (xy 283.3116 -86.599522)
			(xy 283.3116 -86.872318) (xy 283.31206 -86.882195) (xy 283.319503 -86.900494) (xy 283.326078 -86.907878)
			(xy 283.326332 -86.908132) (xy 283.4132 -86.995) (xy 292.606982 -86.995) (xy 292.611053 -86.939378)
			(xy 292.623179 -86.884941) (xy 292.643102 -86.83285) (xy 292.670398 -86.784215) (xy 292.704484 -86.740072)
			(xy 292.744633 -86.701363) (xy 292.789991 -86.668912) (xy 292.839591 -86.643411) (xy 292.892375 -86.625404)
			(xy 292.947218 -86.615274) (xy 293.002952 -86.613237) (xy 293.058389 -86.619337) (xy 293.112346 -86.633443)
			(xy 293.163675 -86.655255) (xy 293.211281 -86.684309) (xy 293.254149 -86.719984) (xy 293.291366 -86.761521)
			(xy 293.322139 -86.808034) (xy 293.345811 -86.858531) (xy 293.361879 -86.911938) (xy 293.369999 -86.967114)
			(xy 293.370508 -86.995) (xy 293.369999 -87.022886) (xy 293.361879 -87.078062) (xy 293.345811 -87.131469)
			(xy 293.322139 -87.181966) (xy 293.291366 -87.228479) (xy 293.254149 -87.270016) (xy 293.211281 -87.305691)
			(xy 293.163675 -87.334745) (xy 293.112346 -87.356557) (xy 293.058389 -87.370663) (xy 293.002952 -87.376763)
			(xy 292.947218 -87.374726) (xy 292.892375 -87.364596) (xy 292.839591 -87.346589) (xy 292.789991 -87.321088)
			(xy 292.744633 -87.288637) (xy 292.704484 -87.249928) (xy 292.670398 -87.205785) (xy 292.643102 -87.15715)
			(xy 292.623179 -87.105059) (xy 292.611053 -87.050622) (xy 292.606982 -86.995) (xy 283.4132 -86.995)
			(xy 283.576014 -87.157814) (xy 283.582868 -87.165209) (xy 283.59061 -87.183808) (xy 283.591 -87.193882)
			(xy 283.591 -88.292251) (xy 288.797978 -88.292251) (xy 288.797978 -88.237749) (xy 288.805734 -88.183801)
			(xy 288.821089 -88.131506) (xy 288.843731 -88.081929) (xy 288.873197 -88.036079) (xy 288.908888 -87.994888)
			(xy 288.950079 -87.959197) (xy 288.995929 -87.929731) (xy 289.045506 -87.907089) (xy 289.097801 -87.891734)
			(xy 289.151749 -87.883978) (xy 289.179 -87.883492) (xy 289.207919 -87.883975) (xy 289.265093 -87.892707)
			(xy 289.320294 -87.909969) (xy 289.372256 -87.935367) (xy 289.419789 -87.968319) (xy 289.461803 -88.008068)
			(xy 289.47999 -88.030558) (xy 289.487551 -88.039321) (xy 289.508311 -88.049501) (xy 289.519868 -88.050116)
			(xy 289.600132 -88.050116) (xy 289.611694 -88.049501) (xy 289.632465 -88.039337) (xy 289.64001 -88.030558)
			(xy 289.658185 -88.008061) (xy 289.700209 -87.968329) (xy 289.747748 -87.935392) (xy 289.799712 -87.910007)
			(xy 289.854912 -87.892753) (xy 289.912083 -87.884026) (xy 289.941 -87.883492) (xy 289.968251 -87.883978)
			(xy 290.022199 -87.891734) (xy 290.074494 -87.907089) (xy 290.124071 -87.929731) (xy 290.169921 -87.959197)
			(xy 290.211112 -87.994888) (xy 290.246803 -88.036079) (xy 290.276269 -88.081929) (xy 290.298911 -88.131506)
			(xy 290.314266 -88.183801) (xy 290.322022 -88.237749) (xy 290.322022 -88.292251) (xy 290.314266 -88.346199)
			(xy 290.298911 -88.398494) (xy 290.276269 -88.448071) (xy 290.246803 -88.493921) (xy 290.211112 -88.535112)
			(xy 290.169921 -88.570803) (xy 290.124071 -88.600269) (xy 290.074494 -88.622911) (xy 290.022199 -88.638266)
			(xy 289.968251 -88.646022) (xy 289.941 -88.646508) (xy 289.912081 -88.646025) (xy 289.854907 -88.637293)
			(xy 289.799706 -88.620031) (xy 289.747744 -88.594633) (xy 289.700211 -88.561681) (xy 289.658197 -88.521932)
			(xy 289.64001 -88.499442) (xy 289.632449 -88.490679) (xy 289.611689 -88.480499) (xy 289.600132 -88.479884)
			(xy 289.519868 -88.479884) (xy 289.508306 -88.480499) (xy 289.487535 -88.490663) (xy 289.47999 -88.499442)
			(xy 289.461815 -88.521939) (xy 289.419791 -88.561671) (xy 289.372252 -88.594608) (xy 289.320288 -88.619993)
			(xy 289.265088 -88.637247) (xy 289.207917 -88.645974) (xy 289.179 -88.646508) (xy 289.151749 -88.646022)
			(xy 289.097801 -88.638266) (xy 289.045506 -88.622911) (xy 288.995929 -88.600269) (xy 288.950079 -88.570803)
			(xy 288.908888 -88.535112) (xy 288.873197 -88.493921) (xy 288.843731 -88.448071) (xy 288.821089 -88.398494)
			(xy 288.805734 -88.346199) (xy 288.797978 -88.292251) (xy 283.591 -88.292251) (xy 283.591 -88.447118)
			(xy 283.590573 -88.457187) (xy 283.582854 -88.475786) (xy 283.576014 -88.483186) (xy 283.453586 -88.605614)
			(xy 283.446191 -88.612468) (xy 283.427592 -88.62021) (xy 283.417518 -88.6206) (xy 278.862282 -88.6206)
			(xy 278.852213 -88.621027) (xy 278.833614 -88.628746) (xy 278.826214 -88.635586) (xy 278.678386 -88.783414)
			(xy 278.670991 -88.790268) (xy 278.652392 -88.79801) (xy 278.642318 -88.7984) (xy 263.444482 -88.7984)
			(xy 263.434413 -88.797973) (xy 263.415814 -88.790254) (xy 263.408414 -88.783414) (xy 260.060186 -85.435186)
			(xy 260.053332 -85.427791) (xy 260.04559 -85.409192) (xy 260.0452 -85.399118) (xy 260.0452 -55.306214)
			(xy 260.044761 -55.296151) (xy 260.037025 -55.277569) (xy 260.030214 -55.270146) (xy 258.605782 -53.845714)
			(xy 258.59867 -53.838348) (xy 258.579874 -53.830728) (xy 230.386382 -53.830728) (xy 230.376314 -53.831155)
			(xy 230.357717 -53.838877) (xy 230.350314 -53.845714) (xy 229.798118 -54.39791) (xy 229.790752 -54.405022)
			(xy 229.783132 -54.423818) (xy 229.783132 -71.113142) (xy 229.783597 -71.123017) (xy 229.79105 -71.141306)
			(xy 229.79761 -71.148702) (xy 229.797864 -71.148956) (xy 232.583482 -73.934574) (xy 232.58399 -73.935082)
			(xy 232.591374 -73.941656) (xy 232.609673 -73.949088) (xy 232.61955 -73.94956) (xy 256.34188 -73.94956)
			(xy 256.351942 -73.949999) (xy 256.37052 -73.957741) (xy 256.377948 -73.964546) (xy 257.455416 -75.042014)
			(xy 257.462269 -75.049409) (xy 257.470012 -75.068008) (xy 257.470402 -75.078082) (xy 257.470402 -81.915)
			(xy 258.012182 -81.915) (xy 258.016253 -81.859378) (xy 258.028379 -81.804941) (xy 258.048302 -81.75285)
			(xy 258.075598 -81.704215) (xy 258.109684 -81.660072) (xy 258.149833 -81.621363) (xy 258.195191 -81.588912)
			(xy 258.244791 -81.563411) (xy 258.297575 -81.545404) (xy 258.352418 -81.535274) (xy 258.408152 -81.533237)
			(xy 258.463589 -81.539337) (xy 258.517546 -81.553443) (xy 258.568875 -81.575255) (xy 258.616481 -81.604309)
			(xy 258.659349 -81.639984) (xy 258.696566 -81.681521) (xy 258.727339 -81.728034) (xy 258.751011 -81.778531)
			(xy 258.767079 -81.831938) (xy 258.775199 -81.887114) (xy 258.775708 -81.915) (xy 258.775199 -81.942886)
			(xy 258.767079 -81.998062) (xy 258.751011 -82.051469) (xy 258.727339 -82.101966) (xy 258.696566 -82.148479)
			(xy 258.659349 -82.190016) (xy 258.616481 -82.225691) (xy 258.568875 -82.254745) (xy 258.517546 -82.276557)
			(xy 258.463589 -82.290663) (xy 258.408152 -82.296763) (xy 258.352418 -82.294726) (xy 258.297575 -82.284596)
			(xy 258.244791 -82.266589) (xy 258.195191 -82.241088) (xy 258.149833 -82.208637) (xy 258.109684 -82.169928)
			(xy 258.075598 -82.125785) (xy 258.048302 -82.07715) (xy 258.028379 -82.025059) (xy 258.016253 -81.970622)
			(xy 258.012182 -81.915) (xy 257.470402 -81.915) (xy 257.470402 -88.034622) (xy 259.58495 -88.034622)
			(xy 259.589021 -87.979) (xy 259.601147 -87.924563) (xy 259.62107 -87.872472) (xy 259.648366 -87.823837)
			(xy 259.682452 -87.779694) (xy 259.722601 -87.740985) (xy 259.767959 -87.708534) (xy 259.817559 -87.683033)
			(xy 259.870343 -87.665026) (xy 259.925186 -87.654896) (xy 259.98092 -87.652859) (xy 260.036357 -87.658959)
			(xy 260.090314 -87.673065) (xy 260.141643 -87.694877) (xy 260.189249 -87.723931) (xy 260.232117 -87.759606)
			(xy 260.269334 -87.801143) (xy 260.300107 -87.847656) (xy 260.323779 -87.898153) (xy 260.339847 -87.95156)
			(xy 260.347967 -88.006736) (xy 260.348476 -88.034622) (xy 260.347967 -88.062508) (xy 260.339847 -88.117684)
			(xy 260.323779 -88.171091) (xy 260.300107 -88.221588) (xy 260.269334 -88.268101) (xy 260.232117 -88.309638)
			(xy 260.189249 -88.345313) (xy 260.141643 -88.374367) (xy 260.090314 -88.396179) (xy 260.036357 -88.410285)
			(xy 259.98092 -88.416385) (xy 259.925186 -88.414348) (xy 259.870343 -88.404218) (xy 259.817559 -88.386211)
			(xy 259.767959 -88.36071) (xy 259.722601 -88.328259) (xy 259.682452 -88.28955) (xy 259.648366 -88.245407)
			(xy 259.62107 -88.196772) (xy 259.601147 -88.144681) (xy 259.589021 -88.090244) (xy 259.58495 -88.034622)
			(xy 257.470402 -88.034622) (xy 257.470402 -88.8238) (xy 296.340782 -88.8238) (xy 296.344853 -88.768178)
			(xy 296.356979 -88.713741) (xy 296.376902 -88.66165) (xy 296.404198 -88.613015) (xy 296.438284 -88.568872)
			(xy 296.478433 -88.530163) (xy 296.523791 -88.497712) (xy 296.573391 -88.472211) (xy 296.626175 -88.454204)
			(xy 296.681018 -88.444074) (xy 296.736752 -88.442037) (xy 296.792189 -88.448137) (xy 296.846146 -88.462243)
			(xy 296.897475 -88.484055) (xy 296.945081 -88.513109) (xy 296.987949 -88.548784) (xy 297.025166 -88.590321)
			(xy 297.055939 -88.636834) (xy 297.079611 -88.687331) (xy 297.095679 -88.740738) (xy 297.103799 -88.795914)
			(xy 297.104308 -88.8238) (xy 297.103799 -88.851686) (xy 297.096689 -88.9) (xy 298.321982 -88.9) (xy 298.326053 -88.844378)
			(xy 298.338179 -88.789941) (xy 298.358102 -88.73785) (xy 298.385398 -88.689215) (xy 298.419484 -88.645072)
			(xy 298.459633 -88.606363) (xy 298.504991 -88.573912) (xy 298.554591 -88.548411) (xy 298.607375 -88.530404)
			(xy 298.662218 -88.520274) (xy 298.717952 -88.518237) (xy 298.773389 -88.524337) (xy 298.827346 -88.538443)
			(xy 298.878675 -88.560255) (xy 298.926281 -88.589309) (xy 298.969149 -88.624984) (xy 299.006366 -88.666521)
			(xy 299.037139 -88.713034) (xy 299.060811 -88.763531) (xy 299.076879 -88.816938) (xy 299.084999 -88.872114)
			(xy 299.085508 -88.9) (xy 299.210982 -88.9) (xy 299.215053 -88.844378) (xy 299.227179 -88.789941)
			(xy 299.247102 -88.73785) (xy 299.274398 -88.689215) (xy 299.308484 -88.645072) (xy 299.348633 -88.606363)
			(xy 299.393991 -88.573912) (xy 299.443591 -88.548411) (xy 299.496375 -88.530404) (xy 299.551218 -88.520274)
			(xy 299.606952 -88.518237) (xy 299.662389 -88.524337) (xy 299.716346 -88.538443) (xy 299.767675 -88.560255)
			(xy 299.815281 -88.589309) (xy 299.858149 -88.624984) (xy 299.895366 -88.666521) (xy 299.926139 -88.713034)
			(xy 299.949811 -88.763531) (xy 299.965879 -88.816938) (xy 299.973999 -88.872114) (xy 299.974508 -88.9)
			(xy 299.973999 -88.927886) (xy 299.965879 -88.983062) (xy 299.949811 -89.036469) (xy 299.926139 -89.086966)
			(xy 299.895366 -89.133479) (xy 299.858149 -89.175016) (xy 299.815281 -89.210691) (xy 299.767675 -89.239745)
			(xy 299.716346 -89.261557) (xy 299.662389 -89.275663) (xy 299.606952 -89.281763) (xy 299.551218 -89.279726)
			(xy 299.496375 -89.269596) (xy 299.443591 -89.251589) (xy 299.393991 -89.226088) (xy 299.348633 -89.193637)
			(xy 299.308484 -89.154928) (xy 299.274398 -89.110785) (xy 299.247102 -89.06215) (xy 299.227179 -89.010059)
			(xy 299.215053 -88.955622) (xy 299.210982 -88.9) (xy 299.085508 -88.9) (xy 299.084999 -88.927886)
			(xy 299.076879 -88.983062) (xy 299.060811 -89.036469) (xy 299.037139 -89.086966) (xy 299.006366 -89.133479)
			(xy 298.969149 -89.175016) (xy 298.926281 -89.210691) (xy 298.878675 -89.239745) (xy 298.827346 -89.261557)
			(xy 298.773389 -89.275663) (xy 298.717952 -89.281763) (xy 298.662218 -89.279726) (xy 298.607375 -89.269596)
			(xy 298.554591 -89.251589) (xy 298.504991 -89.226088) (xy 298.459633 -89.193637) (xy 298.419484 -89.154928)
			(xy 298.385398 -89.110785) (xy 298.358102 -89.06215) (xy 298.338179 -89.010059) (xy 298.326053 -88.955622)
			(xy 298.321982 -88.9) (xy 297.096689 -88.9) (xy 297.095679 -88.906862) (xy 297.079611 -88.960269)
			(xy 297.055939 -89.010766) (xy 297.025166 -89.057279) (xy 296.987949 -89.098816) (xy 296.945081 -89.134491)
			(xy 296.897475 -89.163545) (xy 296.846146 -89.185357) (xy 296.792189 -89.199463) (xy 296.736752 -89.205563)
			(xy 296.681018 -89.203526) (xy 296.626175 -89.193396) (xy 296.573391 -89.175389) (xy 296.523791 -89.149888)
			(xy 296.478433 -89.117437) (xy 296.438284 -89.078728) (xy 296.404198 -89.034585) (xy 296.376902 -88.98595)
			(xy 296.356979 -88.933859) (xy 296.344853 -88.879422) (xy 296.340782 -88.8238) (xy 257.470402 -88.8238)
			(xy 257.470402 -90.418666) (xy 259.057138 -90.418666) (xy 259.061209 -90.363044) (xy 259.073335 -90.308607)
			(xy 259.093258 -90.256516) (xy 259.120554 -90.207881) (xy 259.15464 -90.163738) (xy 259.194789 -90.125029)
			(xy 259.240147 -90.092578) (xy 259.289747 -90.067077) (xy 259.342531 -90.04907) (xy 259.397374 -90.03894)
			(xy 259.453108 -90.036903) (xy 259.508545 -90.043003) (xy 259.562502 -90.057109) (xy 259.613831 -90.078921)
			(xy 259.661437 -90.107975) (xy 259.704305 -90.14365) (xy 259.741522 -90.185187) (xy 259.772295 -90.2317)
			(xy 259.795967 -90.282197) (xy 259.808062 -90.3224) (xy 277.620982 -90.3224) (xy 277.625053 -90.266778)
			(xy 277.637179 -90.212341) (xy 277.657102 -90.16025) (xy 277.684398 -90.111615) (xy 277.718484 -90.067472)
			(xy 277.758633 -90.028763) (xy 277.803991 -89.996312) (xy 277.853591 -89.970811) (xy 277.906375 -89.952804)
			(xy 277.961218 -89.942674) (xy 278.016952 -89.940637) (xy 278.072389 -89.946737) (xy 278.126346 -89.960843)
			(xy 278.177675 -89.982655) (xy 278.225281 -90.011709) (xy 278.268149 -90.047384) (xy 278.305366 -90.088921)
			(xy 278.336139 -90.135434) (xy 278.359811 -90.185931) (xy 278.375879 -90.239338) (xy 278.383999 -90.294514)
			(xy 278.384508 -90.3224) (xy 278.383999 -90.350286) (xy 278.375879 -90.405462) (xy 278.359811 -90.458869)
			(xy 278.340436 -90.5002) (xy 284.961582 -90.5002) (xy 284.965653 -90.444578) (xy 284.977779 -90.390141)
			(xy 284.997702 -90.33805) (xy 285.024998 -90.289415) (xy 285.059084 -90.245272) (xy 285.099233 -90.206563)
			(xy 285.144591 -90.174112) (xy 285.194191 -90.148611) (xy 285.246975 -90.130604) (xy 285.301818 -90.120474)
			(xy 285.357552 -90.118437) (xy 285.412989 -90.124537) (xy 285.466946 -90.138643) (xy 285.518275 -90.160455)
			(xy 285.565881 -90.189509) (xy 285.608749 -90.225184) (xy 285.645966 -90.266721) (xy 285.676739 -90.313234)
			(xy 285.700411 -90.363731) (xy 285.716479 -90.417138) (xy 285.724599 -90.472314) (xy 285.725108 -90.5002)
			(xy 285.724599 -90.528086) (xy 285.716479 -90.583262) (xy 285.700411 -90.636669) (xy 285.676739 -90.687166)
			(xy 285.645966 -90.733679) (xy 285.608749 -90.775216) (xy 285.565881 -90.810891) (xy 285.518275 -90.839945)
			(xy 285.466946 -90.861757) (xy 285.412989 -90.875863) (xy 285.357552 -90.881963) (xy 285.301818 -90.879926)
			(xy 285.246975 -90.869796) (xy 285.194191 -90.851789) (xy 285.144591 -90.826288) (xy 285.099233 -90.793837)
			(xy 285.059084 -90.755128) (xy 285.024998 -90.710985) (xy 284.997702 -90.66235) (xy 284.977779 -90.610259)
			(xy 284.965653 -90.555822) (xy 284.961582 -90.5002) (xy 278.340436 -90.5002) (xy 278.336139 -90.509366)
			(xy 278.305366 -90.555879) (xy 278.268149 -90.597416) (xy 278.225281 -90.633091) (xy 278.177675 -90.662145)
			(xy 278.126346 -90.683957) (xy 278.072389 -90.698063) (xy 278.016952 -90.704163) (xy 277.961218 -90.702126)
			(xy 277.906375 -90.691996) (xy 277.853591 -90.673989) (xy 277.803991 -90.648488) (xy 277.758633 -90.616037)
			(xy 277.718484 -90.577328) (xy 277.684398 -90.533185) (xy 277.657102 -90.48455) (xy 277.637179 -90.432459)
			(xy 277.625053 -90.378022) (xy 277.620982 -90.3224) (xy 259.808062 -90.3224) (xy 259.812035 -90.335604)
			(xy 259.820155 -90.39078) (xy 259.820664 -90.418666) (xy 259.820155 -90.446552) (xy 259.812035 -90.501728)
			(xy 259.795967 -90.555135) (xy 259.772295 -90.605632) (xy 259.741522 -90.652145) (xy 259.704305 -90.693682)
			(xy 259.661437 -90.729357) (xy 259.613831 -90.758411) (xy 259.562502 -90.780223) (xy 259.508545 -90.794329)
			(xy 259.453108 -90.800429) (xy 259.397374 -90.798392) (xy 259.342531 -90.788262) (xy 259.289747 -90.770255)
			(xy 259.240147 -90.744754) (xy 259.194789 -90.712303) (xy 259.15464 -90.673594) (xy 259.120554 -90.629451)
			(xy 259.093258 -90.580816) (xy 259.073335 -90.528725) (xy 259.061209 -90.474288) (xy 259.057138 -90.418666)
			(xy 257.470402 -90.418666) (xy 257.470402 -94.498414) (xy 257.470861 -94.508291) (xy 257.478304 -94.526591)
			(xy 257.48488 -94.533974) (xy 257.485134 -94.534228) (xy 257.775202 -94.824296) (xy 257.77571 -94.824804)
			(xy 257.783087 -94.831398) (xy 257.801386 -94.838872) (xy 257.81127 -94.839282) (xy 266.302236 -94.839282)
			(xy 266.312111 -94.838818) (xy 266.330404 -94.831369) (xy 266.337796 -94.824804) (xy 266.33805 -94.82455)
			(xy 269.504414 -91.658186) (xy 269.511809 -91.651332) (xy 269.530408 -91.64359) (xy 269.540482 -91.6432)
			(xy 277.5204 -91.6432) (xy 277.530095 -91.642762) (xy 277.548103 -91.63557) (xy 277.555452 -91.62923)
			(xy 277.613364 -91.574112) (xy 277.621492 -91.556586) (xy 277.622 -91.54668) (xy 277.623955 -91.519161)
			(xy 277.634797 -91.465069) (xy 277.653316 -91.413102) (xy 277.679126 -91.364344) (xy 277.71169 -91.319812)
			(xy 277.750328 -91.280434) (xy 277.794234 -91.247031) (xy 277.842493 -91.2203) (xy 277.894099 -91.200798)
			(xy 277.947976 -91.188932) (xy 278.003 -91.184949) (xy 278.058024 -91.188932) (xy 278.111901 -91.200798)
			(xy 278.163507 -91.2203) (xy 278.211766 -91.247031) (xy 278.255672 -91.280434) (xy 278.29431 -91.319812)
			(xy 278.326874 -91.364344) (xy 278.352684 -91.413102) (xy 278.371203 -91.465069) (xy 278.382045 -91.519161)
			(xy 278.384 -91.54668) (xy 278.384508 -91.556586) (xy 278.392636 -91.574112) (xy 278.450548 -91.62923)
			(xy 278.457869 -91.635611) (xy 278.475896 -91.64279) (xy 278.4856 -91.6432) (xy 296.087292 -91.6432)
			(xy 296.097314 -91.642782) (xy 296.115834 -91.635113) (xy 296.130009 -91.620941) (xy 296.13768 -91.602422)
			(xy 296.138092 -91.5924) (xy 296.138092 -90.17) (xy 296.138703 -90.135809) (xy 296.148394 -90.068116)
			(xy 296.157396 -90.035126) (xy 296.160444 -90.024966) (xy 296.15765 -90.004138) (xy 296.109136 -89.922096)
			(xy 296.092118 -89.909904) (xy 296.081704 -89.907618) (xy 296.056014 -89.901495) (xy 296.006505 -89.883112)
			(xy 295.960009 -89.858068) (xy 295.917419 -89.82684) (xy 295.879551 -89.79003) (xy 295.86301 -89.769442)
			(xy 295.855415 -89.760622) (xy 295.834506 -89.750456) (xy 295.822878 -89.749884) (xy 295.743122 -89.749884)
			(xy 295.731499 -89.750456) (xy 295.710601 -89.76064) (xy 295.70299 -89.769442) (xy 295.684803 -89.791932)
			(xy 295.642789 -89.831681) (xy 295.595256 -89.864633) (xy 295.543294 -89.890031) (xy 295.488093 -89.907293)
			(xy 295.430919 -89.916025) (xy 295.402 -89.916508) (xy 295.374749 -89.916022) (xy 295.320801 -89.908266)
			(xy 295.268506 -89.892911) (xy 295.218929 -89.870269) (xy 295.173079 -89.840803) (xy 295.131888 -89.805112)
			(xy 295.096197 -89.763921) (xy 295.066731 -89.718071) (xy 295.044089 -89.668494) (xy 295.028734 -89.616199)
			(xy 295.020978 -89.562251) (xy 295.020978 -89.507749) (xy 295.028734 -89.453801) (xy 295.044089 -89.401506)
			(xy 295.066731 -89.351929) (xy 295.096197 -89.306079) (xy 295.131888 -89.264888) (xy 295.173079 -89.229197)
			(xy 295.218929 -89.199731) (xy 295.268506 -89.177089) (xy 295.320801 -89.161734) (xy 295.374749 -89.153978)
			(xy 295.402 -89.153492) (xy 295.430917 -89.154026) (xy 295.488088 -89.162753) (xy 295.543288 -89.180007)
			(xy 295.595252 -89.205392) (xy 295.642791 -89.238329) (xy 295.684815 -89.278061) (xy 295.70299 -89.300558)
			(xy 295.710585 -89.309378) (xy 295.731494 -89.319544) (xy 295.743122 -89.320116) (xy 295.822878 -89.320116)
			(xy 295.834501 -89.319544) (xy 295.855399 -89.30936) (xy 295.86301 -89.300558) (xy 295.881197 -89.278068)
			(xy 295.923211 -89.238319) (xy 295.970744 -89.205367) (xy 296.022706 -89.179969) (xy 296.077907 -89.162707)
			(xy 296.135081 -89.153975) (xy 296.164 -89.153492) (xy 296.191251 -89.153978) (xy 296.245199 -89.161734)
			(xy 296.297494 -89.177089) (xy 296.347071 -89.199731) (xy 296.392921 -89.229197) (xy 296.434112 -89.264888)
			(xy 296.469803 -89.306079) (xy 296.499269 -89.351929) (xy 296.521911 -89.401506) (xy 296.537266 -89.453801)
			(xy 296.545022 -89.507749) (xy 296.545508 -89.535) (xy 296.545508 -89.535254) (xy 296.545455 -89.545242)
			(xy 296.544437 -89.565191) (xy 296.543476 -89.575132) (xy 296.542206 -89.5858) (xy 296.548556 -89.605866)
			(xy 296.610786 -89.678002) (xy 296.629836 -89.686892) (xy 296.640504 -89.6874) (xy 296.67129 -89.689094)
			(xy 296.732091 -89.699333) (xy 296.791093 -89.71723) (xy 296.847336 -89.742494) (xy 296.899905 -89.774713)
			(xy 296.947944 -89.813364) (xy 296.990671 -89.857816) (xy 297.02739 -89.907347) (xy 297.057504 -89.96115)
			(xy 297.080522 -90.018349) (xy 297.096071 -90.078013) (xy 297.103896 -90.139171) (xy 297.104308 -90.17)
			(xy 299.210982 -90.17) (xy 299.215053 -90.114378) (xy 299.227179 -90.059941) (xy 299.247102 -90.00785)
			(xy 299.274398 -89.959215) (xy 299.308484 -89.915072) (xy 299.348633 -89.876363) (xy 299.393991 -89.843912)
			(xy 299.443591 -89.818411) (xy 299.496375 -89.800404) (xy 299.551218 -89.790274) (xy 299.606952 -89.788237)
			(xy 299.662389 -89.794337) (xy 299.716346 -89.808443) (xy 299.767675 -89.830255) (xy 299.815281 -89.859309)
			(xy 299.858149 -89.894984) (xy 299.895366 -89.936521) (xy 299.926139 -89.983034) (xy 299.949811 -90.033531)
			(xy 299.965879 -90.086938) (xy 299.973999 -90.142114) (xy 299.974508 -90.17) (xy 299.973999 -90.197886)
			(xy 299.965879 -90.253062) (xy 299.949811 -90.306469) (xy 299.926139 -90.356966) (xy 299.895366 -90.403479)
			(xy 299.858149 -90.445016) (xy 299.815281 -90.480691) (xy 299.767675 -90.509745) (xy 299.716346 -90.531557)
			(xy 299.662389 -90.545663) (xy 299.606952 -90.551763) (xy 299.551218 -90.549726) (xy 299.496375 -90.539596)
			(xy 299.443591 -90.521589) (xy 299.393991 -90.496088) (xy 299.348633 -90.463637) (xy 299.308484 -90.424928)
			(xy 299.274398 -90.380785) (xy 299.247102 -90.33215) (xy 299.227179 -90.280059) (xy 299.215053 -90.225622)
			(xy 299.210982 -90.17) (xy 297.104308 -90.17) (xy 297.104308 -91.34348) (xy 299.058582 -91.34348)
			(xy 299.062653 -91.287858) (xy 299.074779 -91.233421) (xy 299.094702 -91.18133) (xy 299.121998 -91.132695)
			(xy 299.156084 -91.088552) (xy 299.196233 -91.049843) (xy 299.241591 -91.017392) (xy 299.291191 -90.991891)
			(xy 299.343975 -90.973884) (xy 299.398818 -90.963754) (xy 299.454552 -90.961717) (xy 299.509989 -90.967817)
			(xy 299.563946 -90.981923) (xy 299.615275 -91.003735) (xy 299.662881 -91.032789) (xy 299.705749 -91.068464)
			(xy 299.742966 -91.110001) (xy 299.773739 -91.156514) (xy 299.797411 -91.207011) (xy 299.813479 -91.260418)
			(xy 299.821599 -91.315594) (xy 299.822108 -91.34348) (xy 299.821599 -91.371366) (xy 299.813479 -91.426542)
			(xy 299.797411 -91.479949) (xy 299.773739 -91.530446) (xy 299.742966 -91.576959) (xy 299.705749 -91.618496)
			(xy 299.662881 -91.654171) (xy 299.615275 -91.683225) (xy 299.563946 -91.705037) (xy 299.509989 -91.719143)
			(xy 299.454552 -91.725243) (xy 299.398818 -91.723206) (xy 299.343975 -91.713076) (xy 299.291191 -91.695069)
			(xy 299.241591 -91.669568) (xy 299.196233 -91.637117) (xy 299.156084 -91.598408) (xy 299.121998 -91.554265)
			(xy 299.094702 -91.50563) (xy 299.074779 -91.453539) (xy 299.062653 -91.399102) (xy 299.058582 -91.34348)
			(xy 297.104308 -91.34348) (xy 297.104308 -91.5924) (xy 297.104728 -91.602421) (xy 297.112398 -91.620936)
			(xy 297.12657 -91.635107) (xy 297.145087 -91.642774) (xy 297.155108 -91.6432) (xy 297.463718 -91.6432)
			(xy 297.473787 -91.643627) (xy 297.492386 -91.651346) (xy 297.499786 -91.658186) (xy 298.917614 -93.076014)
			(xy 298.924468 -93.083409) (xy 298.93221 -93.102008) (xy 298.9326 -93.112082) (xy 298.9326 -95.965518)
			(xy 298.93306 -95.975395) (xy 298.940503 -95.993694) (xy 298.947078 -96.001078) (xy 298.947332 -96.001332)
			(xy 301.406814 -98.460814) (xy 301.407322 -98.461322) (xy 301.4147 -98.467912) (xy 301.432999 -98.475379)
			(xy 301.442882 -98.4758)
		)
		(stroke
			(width 0)
			(type solid)
		)
		(fill yes)
		(layer "In7.Cu")
		(net "GND")
	)
	(gr_poly
		(pts
			(xy 405.96185 -169.546524) (xy 405.971917 -169.546092) (xy 405.99051 -169.538368) (xy 405.997918 -169.531538)
			(xy 406.351994 -169.177462) (xy 406.358835 -169.170062) (xy 406.366557 -169.151464) (xy 406.36698 -169.141394)
			(xy 406.36698 -157.907482) (xy 406.367406 -157.897413) (xy 406.375123 -157.878811) (xy 406.381966 -157.871414)
			(xy 407.52014 -156.73324) (xy 407.527539 -156.726396) (xy 407.546137 -156.71867) (xy 407.556208 -156.718254)
			(xy 435.712362 -156.718254) (xy 435.722426 -156.717818) (xy 435.74101 -156.710083) (xy 435.74843 -156.703268)
			(xy 438.277762 -154.173936) (xy 438.284602 -154.166536) (xy 438.29232 -154.147937) (xy 438.292748 -154.137868)
			(xy 438.292748 -133.674612) (xy 438.29317 -133.664542) (xy 438.300887 -133.645939) (xy 438.307734 -133.638544)
			(xy 442.564774 -129.381504) (xy 442.572176 -129.374669) (xy 442.590775 -129.366961) (xy 442.600842 -129.366518)
			(xy 472.244928 -129.366518) (xy 472.254996 -129.36609) (xy 472.273595 -129.358371) (xy 472.280996 -129.351532)
			(xy 473.978478 -127.65405) (xy 473.985319 -127.64665) (xy 473.993039 -127.628051) (xy 473.993464 -127.617982)
			(xy 473.993464 -20.480274) (xy 473.993035 -20.470207) (xy 473.98531 -20.451612) (xy 473.978478 -20.444206)
			(xy 471.769694 -18.235422) (xy 471.762296 -18.228574) (xy 471.743698 -18.220839) (xy 471.733626 -18.220436)
			(xy 463.650584 -18.220436) (xy 463.640516 -18.220863) (xy 463.621919 -18.228585) (xy 463.614516 -18.235422)
			(xy 463.100674 -18.749264) (xy 463.09383 -18.756663) (xy 463.086107 -18.775262) (xy 463.085688 -18.785332)
			(xy 463.085688 -19.35099) (xy 463.086109 -19.361061) (xy 463.093819 -19.37967) (xy 463.100674 -19.387058)
			(xy 463.10169 -19.388074) (xy 463.10169 -55.989982) (xy 468.668617 -55.989982) (xy 468.672606 -55.877017)
			(xy 468.684554 -55.764614) (xy 468.704401 -55.653334) (xy 468.732047 -55.543732) (xy 468.767357 -55.436352)
			(xy 468.810152 -55.331731) (xy 468.860221 -55.230389) (xy 468.917314 -55.132831) (xy 468.981147 -55.039544)
			(xy 469.0514 -54.950991) (xy 469.127725 -54.867615) (xy 469.209741 -54.789831) (xy 469.29704 -54.718025)
			(xy 469.389186 -54.652556) (xy 469.485721 -54.593751) (xy 469.586164 -54.541901) (xy 469.690014 -54.497266)
			(xy 469.796753 -54.460067) (xy 469.905851 -54.43049) (xy 470.016763 -54.408682) (xy 470.128937 -54.394753)
			(xy 470.241815 -54.38877) (xy 470.354833 -54.390765) (xy 470.467429 -54.400727) (xy 470.579042 -54.418607)
			(xy 470.689115 -54.444315) (xy 470.797101 -54.477724) (xy 470.902461 -54.518667) (xy 471.004671 -54.566939)
			(xy 471.103221 -54.622302) (xy 471.197621 -54.684477) (xy 471.287399 -54.753157) (xy 471.372109 -54.827999)
			(xy 471.451329 -54.90863) (xy 471.524664 -54.994647) (xy 471.591749 -55.085624) (xy 471.652249 -55.181106)
			(xy 471.705863 -55.280618) (xy 471.752325 -55.383664) (xy 471.791402 -55.48973) (xy 471.822899 -55.598289)
			(xy 471.846661 -55.708799) (xy 471.862568 -55.82071) (xy 471.870541 -55.933464) (xy 471.87104 -55.989982)
			(xy 471.870541 -56.0465) (xy 471.862568 -56.159254) (xy 471.846661 -56.271165) (xy 471.822899 -56.381675)
			(xy 471.791402 -56.490234) (xy 471.752325 -56.5963) (xy 471.705863 -56.699346) (xy 471.652249 -56.798858)
			(xy 471.591749 -56.89434) (xy 471.524664 -56.985317) (xy 471.451329 -57.071334) (xy 471.372109 -57.151965)
			(xy 471.287399 -57.226807) (xy 471.197621 -57.295487) (xy 471.103221 -57.357662) (xy 471.004671 -57.413025)
			(xy 470.902461 -57.461297) (xy 470.797101 -57.50224) (xy 470.689115 -57.535649) (xy 470.579042 -57.561357)
			(xy 470.467429 -57.579237) (xy 470.354833 -57.589199) (xy 470.241815 -57.591194) (xy 470.128937 -57.585211)
			(xy 470.016763 -57.571282) (xy 469.905851 -57.549474) (xy 469.796753 -57.519897) (xy 469.690014 -57.482698)
			(xy 469.586164 -57.438063) (xy 469.485721 -57.386213) (xy 469.389186 -57.327408) (xy 469.29704 -57.261939)
			(xy 469.209741 -57.190133) (xy 469.127725 -57.112349) (xy 469.0514 -57.028973) (xy 468.981147 -56.94042)
			(xy 468.917314 -56.847133) (xy 468.860221 -56.749575) (xy 468.810152 -56.648233) (xy 468.767357 -56.543612)
			(xy 468.732047 -56.436232) (xy 468.704401 -56.32663) (xy 468.684554 -56.21535) (xy 468.672606 -56.102947)
			(xy 468.668617 -55.989982) (xy 463.10169 -55.989982) (xy 463.10169 -66.434208) (xy 463.102114 -66.444278)
			(xy 463.109829 -66.462881) (xy 463.116676 -66.470276) (xy 463.789014 -67.142614) (xy 463.796409 -67.149468)
			(xy 463.815008 -67.15721) (xy 463.825082 -67.1576) (xy 472.393518 -67.1576) (xy 472.403587 -67.158027)
			(xy 472.422186 -67.165746) (xy 472.429586 -67.172586) (xy 473.136214 -67.879214) (xy 473.143068 -67.886609)
			(xy 473.15081 -67.905208) (xy 473.1512 -67.915282) (xy 473.1512 -76.864718) (xy 473.150773 -76.874787)
			(xy 473.143054 -76.893386) (xy 473.136214 -76.900786) (xy 471.210386 -78.826614) (xy 471.203532 -78.834009)
			(xy 471.19579 -78.852608) (xy 471.1954 -78.862682) (xy 471.1954 -80.19034) (xy 471.195913 -80.200533)
			(xy 471.203927 -80.219284) (xy 471.218571 -80.233474) (xy 471.227912 -80.237584) (xy 471.266794 -80.252988)
			(xy 471.341793 -80.290014) (xy 471.413042 -80.333822) (xy 471.479932 -80.384036) (xy 471.541886 -80.440225)
			(xy 471.598375 -80.501907) (xy 471.648912 -80.568553) (xy 471.693064 -80.63959) (xy 471.730452 -80.714408)
			(xy 471.760755 -80.792365) (xy 471.783713 -80.872793) (xy 471.799128 -80.955) (xy 471.806869 -81.038281)
			(xy 471.806869 -81.121921) (xy 471.799128 -81.205202) (xy 471.783713 -81.287409) (xy 471.760755 -81.367836)
			(xy 471.730452 -81.445793) (xy 471.693063 -81.520612) (xy 471.648911 -81.591648) (xy 471.598374 -81.658294)
			(xy 471.541885 -81.719976) (xy 471.479931 -81.776165) (xy 471.413041 -81.826379) (xy 471.341792 -81.870187)
			(xy 471.266793 -81.907212) (xy 471.227912 -81.92262) (xy 471.218543 -81.9267) (xy 471.203842 -81.940868)
			(xy 471.195848 -81.959656) (xy 471.1954 -81.969864) (xy 471.1954 -82.73034) (xy 471.195913 -82.740533)
			(xy 471.203927 -82.759284) (xy 471.218571 -82.773474) (xy 471.227912 -82.777584) (xy 471.266796 -82.792986)
			(xy 471.341796 -82.830008) (xy 471.413047 -82.873813) (xy 471.479938 -82.924026) (xy 471.541893 -82.980215)
			(xy 471.598382 -83.041897) (xy 471.648918 -83.108544) (xy 471.693068 -83.179582) (xy 471.730453 -83.254403)
			(xy 471.760751 -83.332362) (xy 471.783703 -83.412791) (xy 471.799112 -83.495) (xy 471.806845 -83.578282)
			(xy 471.807286 -83.620102) (xy 471.806649 -83.668575) (xy 471.796249 -83.764962) (xy 471.77556 -83.859675)
			(xy 471.760804 -83.905852) (xy 471.756232 -83.919568) (xy 471.762836 -83.947508) (xy 471.847672 -84.032344)
			(xy 471.875612 -84.038948) (xy 471.889328 -84.034376) (xy 471.935508 -84.019633) (xy 472.030223 -83.998959)
			(xy 472.126606 -83.988546) (xy 472.175078 -83.987894) (xy 472.218032 -83.988388) (xy 472.303553 -83.996552)
			(xy 472.387909 -84.012809) (xy 472.470339 -84.03701) (xy 472.550094 -84.068938) (xy 472.626454 -84.108303)
			(xy 472.698726 -84.154747) (xy 472.766256 -84.207852) (xy 472.828432 -84.267135) (xy 472.884691 -84.33206)
			(xy 472.934523 -84.402039) (xy 472.977478 -84.476438) (xy 473.013167 -84.554583) (xy 473.041265 -84.635767)
			(xy 473.061519 -84.719254) (xy 473.073746 -84.804288) (xy 473.077834 -84.8901) (xy 473.073746 -84.975912)
			(xy 473.061519 -85.060946) (xy 473.041265 -85.144433) (xy 473.013167 -85.225617) (xy 472.977478 -85.303762)
			(xy 472.934523 -85.378161) (xy 472.884691 -85.44814) (xy 472.828432 -85.513065) (xy 472.766256 -85.572348)
			(xy 472.698726 -85.625453) (xy 472.626454 -85.671897) (xy 472.550094 -85.711262) (xy 472.470339 -85.74319)
			(xy 472.387909 -85.767391) (xy 472.303553 -85.783648) (xy 472.218032 -85.791812) (xy 472.175078 -85.79231)
			(xy 472.126605 -85.791672) (xy 472.030219 -85.781271) (xy 471.935506 -85.76058) (xy 471.889328 -85.745828)
			(xy 471.875612 -85.741256) (xy 471.847672 -85.74786) (xy 471.762836 -85.832696) (xy 471.756232 -85.860636)
			(xy 471.760804 -85.874352) (xy 471.775547 -85.920532) (xy 471.796218 -86.015247) (xy 471.806629 -86.11163)
			(xy 471.807286 -86.160102) (xy 471.806649 -86.208575) (xy 471.796249 -86.304962) (xy 471.77556 -86.399675)
			(xy 471.760804 -86.445852) (xy 471.756232 -86.459568) (xy 471.762836 -86.487508) (xy 471.847672 -86.572344)
			(xy 471.875612 -86.578948) (xy 471.889328 -86.574376) (xy 471.935508 -86.559633) (xy 472.030223 -86.538959)
			(xy 472.126606 -86.528546) (xy 472.175078 -86.527894) (xy 472.218032 -86.528388) (xy 472.303553 -86.536552)
			(xy 472.387909 -86.552809) (xy 472.470339 -86.57701) (xy 472.550094 -86.608938) (xy 472.626454 -86.648303)
			(xy 472.698726 -86.694747) (xy 472.766256 -86.747852) (xy 472.828432 -86.807135) (xy 472.884691 -86.87206)
			(xy 472.934523 -86.942039) (xy 472.977478 -87.016438) (xy 473.013167 -87.094583) (xy 473.041265 -87.175767)
			(xy 473.061519 -87.259254) (xy 473.073746 -87.344288) (xy 473.077834 -87.4301) (xy 473.073746 -87.515912)
			(xy 473.061519 -87.600946) (xy 473.041265 -87.684433) (xy 473.013167 -87.765617) (xy 472.977478 -87.843762)
			(xy 472.934523 -87.918161) (xy 472.884691 -87.98814) (xy 472.828432 -88.053065) (xy 472.766256 -88.112348)
			(xy 472.698726 -88.165453) (xy 472.626454 -88.211897) (xy 472.550094 -88.251262) (xy 472.470339 -88.28319)
			(xy 472.387909 -88.307391) (xy 472.303553 -88.323648) (xy 472.218032 -88.331812) (xy 472.175078 -88.33231)
			(xy 472.126605 -88.331672) (xy 472.030219 -88.321271) (xy 471.935506 -88.30058) (xy 471.889328 -88.285828)
			(xy 471.875612 -88.281256) (xy 471.847672 -88.28786) (xy 471.762836 -88.372696) (xy 471.756232 -88.400636)
			(xy 471.760804 -88.414352) (xy 471.775547 -88.460532) (xy 471.796218 -88.555247) (xy 471.806629 -88.65163)
			(xy 471.807286 -88.700102) (xy 471.806813 -88.74192) (xy 471.799073 -88.825198) (xy 471.783659 -88.907402)
			(xy 471.760704 -88.987827) (xy 471.730405 -89.065782) (xy 471.693021 -89.140599) (xy 471.648874 -89.211635)
			(xy 471.598342 -89.278281) (xy 471.541859 -89.339964) (xy 471.479911 -89.396156) (xy 471.413028 -89.446373)
			(xy 471.341785 -89.490186) (xy 471.266793 -89.527217) (xy 471.227912 -89.54262) (xy 471.218543 -89.5467)
			(xy 471.203842 -89.560868) (xy 471.195848 -89.579656) (xy 471.1954 -89.589864) (xy 471.1954 -89.878662)
			(xy 471.195978 -89.889904) (xy 471.205598 -89.910223) (xy 471.213942 -89.917778) (xy 471.283284 -89.974928)
			(xy 471.304874 -89.980516) (xy 471.316304 -89.97823) (xy 471.371784 -89.968011) (xy 471.48379 -89.954453)
			(xy 471.596472 -89.948815) (xy 471.709271 -89.951126) (xy 471.821628 -89.961372) (xy 471.932984 -89.979505)
			(xy 472.042787 -90.005433) (xy 472.150492 -90.039028) (xy 472.255564 -90.080124) (xy 472.357482 -90.128516)
			(xy 472.45574 -90.183963) (xy 472.54985 -90.246192) (xy 472.639344 -90.314892) (xy 472.72378 -90.389723)
			(xy 472.802736 -90.470314) (xy 472.875823 -90.556264) (xy 472.942676 -90.647147) (xy 473.002964 -90.742511)
			(xy 473.056388 -90.841884) (xy 473.102682 -90.944771) (xy 473.141617 -91.050663) (xy 473.172999 -91.159034)
			(xy 473.196673 -91.269345) (xy 473.212522 -91.381049) (xy 473.220465 -91.493592) (xy 473.220465 -91.606415)
			(xy 473.212521 -91.718958) (xy 473.196672 -91.830662) (xy 473.172998 -91.940973) (xy 473.141615 -92.049343)
			(xy 473.102679 -92.155235) (xy 473.056385 -92.258123) (xy 473.00296 -92.357495) (xy 472.942672 -92.452859)
			(xy 472.875818 -92.543742) (xy 472.802732 -92.629691) (xy 472.723775 -92.710282) (xy 472.639339 -92.785112)
			(xy 472.549844 -92.853812) (xy 472.455734 -92.91604) (xy 472.357476 -92.971488) (xy 472.255558 -93.019879)
			(xy 472.150486 -93.060974) (xy 472.042781 -93.094569) (xy 471.932977 -93.120496) (xy 471.821621 -93.138628)
			(xy 471.709264 -93.148875) (xy 471.596465 -93.151185) (xy 471.483783 -93.145546) (xy 471.371778 -93.131988)
			(xy 471.316304 -93.121734) (xy 471.304874 -93.119702) (xy 471.283284 -93.12529) (xy 471.213942 -93.18244)
			(xy 471.205655 -93.19004) (xy 471.196027 -93.21033) (xy 471.1954 -93.221556) (xy 471.1954 -100.054918)
			(xy 471.194973 -100.064987) (xy 471.187254 -100.083586) (xy 471.180414 -100.090986) (xy 464.784948 -106.486452)
			(xy 466.257638 -106.486452) (xy 466.261709 -106.43083) (xy 466.273835 -106.376393) (xy 466.293758 -106.324302)
			(xy 466.321054 -106.275667) (xy 466.35514 -106.231524) (xy 466.395289 -106.192815) (xy 466.440647 -106.160364)
			(xy 466.490247 -106.134863) (xy 466.543031 -106.116856) (xy 466.597874 -106.106726) (xy 466.653608 -106.104689)
			(xy 466.709045 -106.110789) (xy 466.763002 -106.124895) (xy 466.814331 -106.146707) (xy 466.861937 -106.175761)
			(xy 466.904805 -106.211436) (xy 466.942022 -106.252973) (xy 466.972795 -106.299486) (xy 466.996467 -106.349983)
			(xy 467.012535 -106.40339) (xy 467.020655 -106.458566) (xy 467.021164 -106.486452) (xy 467.527638 -106.486452)
			(xy 467.531709 -106.43083) (xy 467.543835 -106.376393) (xy 467.563758 -106.324302) (xy 467.591054 -106.275667)
			(xy 467.62514 -106.231524) (xy 467.665289 -106.192815) (xy 467.710647 -106.160364) (xy 467.760247 -106.134863)
			(xy 467.813031 -106.116856) (xy 467.867874 -106.106726) (xy 467.923608 -106.104689) (xy 467.979045 -106.110789)
			(xy 468.033002 -106.124895) (xy 468.084331 -106.146707) (xy 468.131937 -106.175761) (xy 468.174805 -106.211436)
			(xy 468.212022 -106.252973) (xy 468.242795 -106.299486) (xy 468.266467 -106.349983) (xy 468.282535 -106.40339)
			(xy 468.290655 -106.458566) (xy 468.291164 -106.486452) (xy 468.797638 -106.486452) (xy 468.801709 -106.43083)
			(xy 468.813835 -106.376393) (xy 468.833758 -106.324302) (xy 468.861054 -106.275667) (xy 468.89514 -106.231524)
			(xy 468.935289 -106.192815) (xy 468.980647 -106.160364) (xy 469.030247 -106.134863) (xy 469.083031 -106.116856)
			(xy 469.137874 -106.106726) (xy 469.193608 -106.104689) (xy 469.249045 -106.110789) (xy 469.303002 -106.124895)
			(xy 469.354331 -106.146707) (xy 469.401937 -106.175761) (xy 469.444805 -106.211436) (xy 469.482022 -106.252973)
			(xy 469.512795 -106.299486) (xy 469.536467 -106.349983) (xy 469.552535 -106.40339) (xy 469.560655 -106.458566)
			(xy 469.561164 -106.486452) (xy 470.067638 -106.486452) (xy 470.071709 -106.43083) (xy 470.083835 -106.376393)
			(xy 470.103758 -106.324302) (xy 470.131054 -106.275667) (xy 470.16514 -106.231524) (xy 470.205289 -106.192815)
			(xy 470.250647 -106.160364) (xy 470.300247 -106.134863) (xy 470.353031 -106.116856) (xy 470.407874 -106.106726)
			(xy 470.463608 -106.104689) (xy 470.519045 -106.110789) (xy 470.573002 -106.124895) (xy 470.624331 -106.146707)
			(xy 470.671937 -106.175761) (xy 470.714805 -106.211436) (xy 470.752022 -106.252973) (xy 470.782795 -106.299486)
			(xy 470.806467 -106.349983) (xy 470.822535 -106.40339) (xy 470.830655 -106.458566) (xy 470.831164 -106.486452)
			(xy 470.830655 -106.514338) (xy 470.822535 -106.569514) (xy 470.806467 -106.622921) (xy 470.782795 -106.673418)
			(xy 470.752022 -106.719931) (xy 470.714805 -106.761468) (xy 470.671937 -106.797143) (xy 470.624331 -106.826197)
			(xy 470.573002 -106.848009) (xy 470.519045 -106.862115) (xy 470.463608 -106.868215) (xy 470.407874 -106.866178)
			(xy 470.353031 -106.856048) (xy 470.300247 -106.838041) (xy 470.250647 -106.81254) (xy 470.205289 -106.780089)
			(xy 470.16514 -106.74138) (xy 470.131054 -106.697237) (xy 470.103758 -106.648602) (xy 470.083835 -106.596511)
			(xy 470.071709 -106.542074) (xy 470.067638 -106.486452) (xy 469.561164 -106.486452) (xy 469.560655 -106.514338)
			(xy 469.552535 -106.569514) (xy 469.536467 -106.622921) (xy 469.512795 -106.673418) (xy 469.482022 -106.719931)
			(xy 469.444805 -106.761468) (xy 469.401937 -106.797143) (xy 469.354331 -106.826197) (xy 469.303002 -106.848009)
			(xy 469.249045 -106.862115) (xy 469.193608 -106.868215) (xy 469.137874 -106.866178) (xy 469.083031 -106.856048)
			(xy 469.030247 -106.838041) (xy 468.980647 -106.81254) (xy 468.935289 -106.780089) (xy 468.89514 -106.74138)
			(xy 468.861054 -106.697237) (xy 468.833758 -106.648602) (xy 468.813835 -106.596511) (xy 468.801709 -106.542074)
			(xy 468.797638 -106.486452) (xy 468.291164 -106.486452) (xy 468.290655 -106.514338) (xy 468.282535 -106.569514)
			(xy 468.266467 -106.622921) (xy 468.242795 -106.673418) (xy 468.212022 -106.719931) (xy 468.174805 -106.761468)
			(xy 468.131937 -106.797143) (xy 468.084331 -106.826197) (xy 468.033002 -106.848009) (xy 467.979045 -106.862115)
			(xy 467.923608 -106.868215) (xy 467.867874 -106.866178) (xy 467.813031 -106.856048) (xy 467.760247 -106.838041)
			(xy 467.710647 -106.81254) (xy 467.665289 -106.780089) (xy 467.62514 -106.74138) (xy 467.591054 -106.697237)
			(xy 467.563758 -106.648602) (xy 467.543835 -106.596511) (xy 467.531709 -106.542074) (xy 467.527638 -106.486452)
			(xy 467.021164 -106.486452) (xy 467.020655 -106.514338) (xy 467.012535 -106.569514) (xy 466.996467 -106.622921)
			(xy 466.972795 -106.673418) (xy 466.942022 -106.719931) (xy 466.904805 -106.761468) (xy 466.861937 -106.797143)
			(xy 466.814331 -106.826197) (xy 466.763002 -106.848009) (xy 466.709045 -106.862115) (xy 466.653608 -106.868215)
			(xy 466.597874 -106.866178) (xy 466.543031 -106.856048) (xy 466.490247 -106.838041) (xy 466.440647 -106.81254)
			(xy 466.395289 -106.780089) (xy 466.35514 -106.74138) (xy 466.321054 -106.697237) (xy 466.293758 -106.648602)
			(xy 466.273835 -106.596511) (xy 466.261709 -106.542074) (xy 466.257638 -106.486452) (xy 464.784948 -106.486452)
			(xy 462.498948 -108.772452) (xy 466.257638 -108.772452) (xy 466.261709 -108.71683) (xy 466.273835 -108.662393)
			(xy 466.293758 -108.610302) (xy 466.321054 -108.561667) (xy 466.35514 -108.517524) (xy 466.395289 -108.478815)
			(xy 466.440647 -108.446364) (xy 466.490247 -108.420863) (xy 466.543031 -108.402856) (xy 466.597874 -108.392726)
			(xy 466.653608 -108.390689) (xy 466.709045 -108.396789) (xy 466.763002 -108.410895) (xy 466.814331 -108.432707)
			(xy 466.861937 -108.461761) (xy 466.904805 -108.497436) (xy 466.942022 -108.538973) (xy 466.972795 -108.585486)
			(xy 466.996467 -108.635983) (xy 467.012535 -108.68939) (xy 467.020655 -108.744566) (xy 467.021164 -108.772452)
			(xy 467.020655 -108.800338) (xy 467.012535 -108.855514) (xy 466.996467 -108.908921) (xy 466.972795 -108.959418)
			(xy 466.942022 -109.005931) (xy 466.904805 -109.047468) (xy 466.861937 -109.083143) (xy 466.814331 -109.112197)
			(xy 466.763002 -109.134009) (xy 466.709045 -109.148115) (xy 466.653608 -109.154215) (xy 466.597874 -109.152178)
			(xy 466.543031 -109.142048) (xy 466.490247 -109.124041) (xy 466.440647 -109.09854) (xy 466.395289 -109.066089)
			(xy 466.35514 -109.02738) (xy 466.321054 -108.983237) (xy 466.293758 -108.934602) (xy 466.273835 -108.882511)
			(xy 466.261709 -108.828074) (xy 466.257638 -108.772452) (xy 462.498948 -108.772452) (xy 461.907128 -109.364272)
			(xy 468.797638 -109.364272) (xy 468.801709 -109.30865) (xy 468.813835 -109.254213) (xy 468.833758 -109.202122)
			(xy 468.861054 -109.153487) (xy 468.89514 -109.109344) (xy 468.935289 -109.070635) (xy 468.980647 -109.038184)
			(xy 469.030247 -109.012683) (xy 469.083031 -108.994676) (xy 469.137874 -108.984546) (xy 469.193608 -108.982509)
			(xy 469.249045 -108.988609) (xy 469.303002 -109.002715) (xy 469.354331 -109.024527) (xy 469.401937 -109.053581)
			(xy 469.444805 -109.089256) (xy 469.482022 -109.130793) (xy 469.512795 -109.177306) (xy 469.536467 -109.227803)
			(xy 469.552535 -109.28121) (xy 469.560655 -109.336386) (xy 469.561164 -109.364272) (xy 469.560655 -109.392158)
			(xy 469.552535 -109.447334) (xy 469.536467 -109.500741) (xy 469.512795 -109.551238) (xy 469.482022 -109.597751)
			(xy 469.444805 -109.639288) (xy 469.401937 -109.674963) (xy 469.354331 -109.704017) (xy 469.303002 -109.725829)
			(xy 469.249045 -109.739935) (xy 469.193608 -109.746035) (xy 469.137874 -109.743998) (xy 469.083031 -109.733868)
			(xy 469.030247 -109.715861) (xy 468.980647 -109.69036) (xy 468.935289 -109.657909) (xy 468.89514 -109.6192)
			(xy 468.861054 -109.575057) (xy 468.833758 -109.526422) (xy 468.813835 -109.474331) (xy 468.801709 -109.419894)
			(xy 468.797638 -109.364272) (xy 461.907128 -109.364272) (xy 461.457548 -109.813852) (xy 467.527638 -109.813852)
			(xy 467.531709 -109.75823) (xy 467.543835 -109.703793) (xy 467.563758 -109.651702) (xy 467.591054 -109.603067)
			(xy 467.62514 -109.558924) (xy 467.665289 -109.520215) (xy 467.710647 -109.487764) (xy 467.760247 -109.462263)
			(xy 467.813031 -109.444256) (xy 467.867874 -109.434126) (xy 467.923608 -109.432089) (xy 467.979045 -109.438189)
			(xy 468.033002 -109.452295) (xy 468.084331 -109.474107) (xy 468.131937 -109.503161) (xy 468.174805 -109.538836)
			(xy 468.212022 -109.580373) (xy 468.242795 -109.626886) (xy 468.266467 -109.677383) (xy 468.282535 -109.73079)
			(xy 468.290655 -109.785966) (xy 468.291164 -109.813852) (xy 468.290655 -109.841738) (xy 468.282535 -109.896914)
			(xy 468.266467 -109.950321) (xy 468.242795 -110.000818) (xy 468.212022 -110.047331) (xy 468.174805 -110.088868)
			(xy 468.131937 -110.124543) (xy 468.084331 -110.153597) (xy 468.033002 -110.175409) (xy 467.979045 -110.189515)
			(xy 467.923608 -110.195615) (xy 467.867874 -110.193578) (xy 467.813031 -110.183448) (xy 467.760247 -110.165441)
			(xy 467.710647 -110.13994) (xy 467.665289 -110.107489) (xy 467.62514 -110.06878) (xy 467.591054 -110.024637)
			(xy 467.563758 -109.976002) (xy 467.543835 -109.923911) (xy 467.531709 -109.869474) (xy 467.527638 -109.813852)
			(xy 461.457548 -109.813852) (xy 461.304386 -109.967014) (xy 461.296991 -109.973868) (xy 461.278392 -109.98161)
			(xy 461.268318 -109.982) (xy 441.752482 -109.982) (xy 441.742413 -109.981573) (xy 441.723814 -109.973854)
			(xy 441.716414 -109.967014) (xy 431.459386 -99.709986) (xy 431.451991 -99.703132) (xy 431.433392 -99.69539)
			(xy 431.423318 -99.695) (xy 418.130482 -99.695) (xy 418.120413 -99.695427) (xy 418.101814 -99.703146)
			(xy 418.094414 -99.709986) (xy 416.697668 -101.106732) (xy 416.690819 -101.114129) (xy 416.683086 -101.132728)
			(xy 416.682682 -101.1428) (xy 416.682682 -104.549956) (xy 422.484046 -104.549956) (xy 422.488076 -104.407621)
			(xy 422.500151 -104.265741) (xy 422.520234 -104.124773) (xy 422.548261 -103.985166) (xy 422.584141 -103.847368)
			(xy 422.627759 -103.711821) (xy 422.678976 -103.578959) (xy 422.737627 -103.449207) (xy 422.803525 -103.322981)
			(xy 422.876459 -103.200685) (xy 422.956196 -103.082712) (xy 423.042478 -102.969439) (xy 423.135031 -102.861228)
			(xy 423.233558 -102.758427) (xy 423.337743 -102.661365) (xy 423.447252 -102.570353) (xy 423.561735 -102.485681)
			(xy 423.680825 -102.407623) (xy 423.80414 -102.336427) (xy 423.931286 -102.272321) (xy 424.061855 -102.215512)
			(xy 424.195429 -102.16618) (xy 424.33158 -102.124484) (xy 424.469871 -102.090558) (xy 424.609861 -102.06451)
			(xy 424.7511 -102.046424) (xy 424.893136 -102.036357) (xy 425.035514 -102.034342) (xy 425.177778 -102.040385)
			(xy 425.319472 -102.054467) (xy 425.460142 -102.076543) (xy 425.599339 -102.106543) (xy 425.736615 -102.144369)
			(xy 425.871531 -102.189901) (xy 426.003655 -102.242992) (xy 426.132564 -102.303474) (xy 426.257845 -102.371152)
			(xy 426.379096 -102.445809) (xy 426.495929 -102.527207) (xy 426.60797 -102.615084) (xy 426.71486 -102.709159)
			(xy 426.816257 -102.809131) (xy 426.911835 -102.914679) (xy 427.001289 -103.025465) (xy 427.084331 -103.141134)
			(xy 427.160697 -103.261317) (xy 427.230141 -103.385627) (xy 427.292441 -103.513668) (xy 427.347397 -103.645027)
			(xy 427.394834 -103.779286) (xy 427.434598 -103.916013) (xy 427.466564 -104.054771) (xy 427.490629 -104.195115)
			(xy 427.506715 -104.336596) (xy 427.51477 -104.47876) (xy 427.515274 -104.549956) (xy 427.51477 -104.621152)
			(xy 427.506715 -104.763316) (xy 427.490629 -104.904797) (xy 427.466564 -105.045141) (xy 427.434598 -105.183899)
			(xy 427.394834 -105.320626) (xy 427.347397 -105.454885) (xy 427.292441 -105.586244) (xy 427.230141 -105.714285)
			(xy 427.160697 -105.838595) (xy 427.084331 -105.958778) (xy 427.001289 -106.074447) (xy 426.911835 -106.185233)
			(xy 426.816257 -106.290781) (xy 426.71486 -106.390753) (xy 426.60797 -106.484828) (xy 426.495929 -106.572705)
			(xy 426.379096 -106.654103) (xy 426.257845 -106.72876) (xy 426.132564 -106.796438) (xy 426.003655 -106.85692)
			(xy 425.871531 -106.910011) (xy 425.736615 -106.955543) (xy 425.599339 -106.993369) (xy 425.460142 -107.023369)
			(xy 425.319472 -107.045445) (xy 425.177778 -107.059527) (xy 425.035514 -107.06557) (xy 424.893136 -107.063555)
			(xy 424.7511 -107.053488) (xy 424.609861 -107.035402) (xy 424.469871 -107.009354) (xy 424.33158 -106.975428)
			(xy 424.195429 -106.933732) (xy 424.061855 -106.8844) (xy 423.931286 -106.827591) (xy 423.80414 -106.763485)
			(xy 423.680825 -106.692289) (xy 423.561735 -106.614231) (xy 423.447252 -106.529559) (xy 423.337743 -106.438547)
			(xy 423.233558 -106.341485) (xy 423.135031 -106.238684) (xy 423.042478 -106.130473) (xy 422.956196 -106.0172)
			(xy 422.876459 -105.899227) (xy 422.803525 -105.776931) (xy 422.737627 -105.650705) (xy 422.678976 -105.520953)
			(xy 422.627759 -105.388091) (xy 422.584141 -105.252544) (xy 422.548261 -105.114746) (xy 422.520234 -104.975139)
			(xy 422.500151 -104.834171) (xy 422.488076 -104.692291) (xy 422.484046 -104.549956) (xy 416.682682 -104.549956)
			(xy 416.682682 -110.626652) (xy 470.067638 -110.626652) (xy 470.071709 -110.57103) (xy 470.083835 -110.516593)
			(xy 470.103758 -110.464502) (xy 470.131054 -110.415867) (xy 470.16514 -110.371724) (xy 470.205289 -110.333015)
			(xy 470.250647 -110.300564) (xy 470.300247 -110.275063) (xy 470.353031 -110.257056) (xy 470.407874 -110.246926)
			(xy 470.463608 -110.244889) (xy 470.519045 -110.250989) (xy 470.573002 -110.265095) (xy 470.624331 -110.286907)
			(xy 470.671937 -110.315961) (xy 470.714805 -110.351636) (xy 470.752022 -110.393173) (xy 470.782795 -110.439686)
			(xy 470.806467 -110.490183) (xy 470.822535 -110.54359) (xy 470.830655 -110.598766) (xy 470.831164 -110.626652)
			(xy 470.830655 -110.654538) (xy 470.822535 -110.709714) (xy 470.806467 -110.763121) (xy 470.782795 -110.813618)
			(xy 470.752022 -110.860131) (xy 470.714805 -110.901668) (xy 470.671937 -110.937343) (xy 470.624331 -110.966397)
			(xy 470.573002 -110.988209) (xy 470.519045 -111.002315) (xy 470.463608 -111.008415) (xy 470.407874 -111.006378)
			(xy 470.353031 -110.996248) (xy 470.300247 -110.978241) (xy 470.250647 -110.95274) (xy 470.205289 -110.920289)
			(xy 470.16514 -110.88158) (xy 470.131054 -110.837437) (xy 470.103758 -110.788802) (xy 470.083835 -110.736711)
			(xy 470.071709 -110.682274) (xy 470.067638 -110.626652) (xy 416.682682 -110.626652) (xy 416.682682 -111.469932)
			(xy 416.682253 -111.479999) (xy 416.674528 -111.498594) (xy 416.667696 -111.506) (xy 416.667696 -147.867624)
			(xy 416.667268 -147.877692) (xy 416.659547 -147.89629) (xy 416.65271 -147.903692) (xy 414.731454 -149.824948)
			(xy 414.724055 -149.831793) (xy 414.705457 -149.839519) (xy 414.695386 -149.839934) (xy 403.189186 -149.839934)
			(xy 403.179118 -149.84036) (xy 403.16052 -149.848082) (xy 403.153118 -149.85492) (xy 402.543264 -150.464774)
			(xy 402.536422 -150.472174) (xy 402.528705 -150.490772) (xy 402.528278 -150.500842) (xy 402.528278 -169.1259)
			(xy 402.5287 -169.135971) (xy 402.536412 -169.154577) (xy 402.543264 -169.161968) (xy 402.912834 -169.531538)
			(xy 402.920231 -169.538386) (xy 402.93883 -169.546118) (xy 402.948902 -169.546524)
		)
		(stroke
			(width 0)
			(type solid)
		)
		(fill yes)
		(layer "In7.Cu")
		(net "GND")
	)
	(gr_poly
		(pts
			(xy 29.601414 -155.435808) (xy 29.611483 -155.435383) (xy 29.630085 -155.427666) (xy 29.637482 -155.420822)
			(xy 31.015178 -154.043126) (xy 31.022015 -154.035724) (xy 31.029726 -154.017126) (xy 31.030164 -154.007058)
			(xy 31.030164 -39.205408) (xy 31.030587 -39.195339) (xy 31.038307 -39.176738) (xy 31.04515 -39.16934)
			(xy 41.12387 -29.09062) (xy 41.131271 -29.083783) (xy 41.14987 -29.07607) (xy 41.159938 -29.075634)
			(xy 53.297074 -29.075634) (xy 53.305992 -29.075235) (xy 53.322747 -29.069118) (xy 53.32984 -29.063696)
			(xy 53.350544 -29.046942) (xy 53.39572 -29.018734) (xy 53.44438 -28.997083) (xy 53.495579 -28.982411)
			(xy 53.54832 -28.975003) (xy 53.60158 -28.975003) (xy 53.654321 -28.982411) (xy 53.70552 -28.997083)
			(xy 53.75418 -29.018734) (xy 53.799356 -29.046942) (xy 53.82006 -29.063696) (xy 53.827107 -29.069197)
			(xy 53.843892 -29.075319) (xy 53.852826 -29.075634) (xy 54.996334 -29.075634) (xy 55.0064 -29.075203)
			(xy 55.024989 -29.067472) (xy 55.032402 -29.060648) (xy 58.678064 -25.414986) (xy 58.685462 -25.40814)
			(xy 58.704061 -25.400416) (xy 58.714132 -25.4) (xy 74.300334 -25.4) (xy 74.310401 -25.399571) (xy 74.328997 -25.391847)
			(xy 74.336402 -25.385014) (xy 78.228444 -21.492972) (xy 78.235841 -21.486125) (xy 78.25444 -21.478395)
			(xy 78.264512 -21.477986) (xy 88.896444 -21.477986) (xy 88.90651 -21.477554) (xy 88.925102 -21.469827)
			(xy 88.932512 -21.463) (xy 98.696526 -11.698986) (xy 98.703922 -11.692134) (xy 98.722521 -11.684396)
			(xy 98.732594 -11.684) (xy 100.303584 -11.684) (xy 100.315002 -11.68354) (xy 100.335629 -11.673756)
			(xy 100.343208 -11.665204) (xy 100.361423 -11.643665) (xy 100.403117 -11.605671) (xy 100.449951 -11.574232)
			(xy 100.500905 -11.550032) (xy 100.554867 -11.533599) (xy 100.61066 -11.525292) (xy 100.667068 -11.525292)
			(xy 100.722861 -11.533599) (xy 100.776823 -11.550032) (xy 100.827777 -11.574232) (xy 100.874611 -11.605671)
			(xy 100.916305 -11.643665) (xy 100.93452 -11.665204) (xy 100.94219 -11.673636) (xy 100.962761 -11.683389)
			(xy 100.974144 -11.684) (xy 160.101534 -11.684) (xy 160.111601 -11.684429) (xy 160.130197 -11.692153)
			(xy 160.137602 -11.698986) (xy 162.960304 -14.521688) (xy 162.967152 -14.529086) (xy 162.97489 -14.547684)
			(xy 162.97529 -14.557756) (xy 162.97529 -25.354026) (xy 162.975717 -25.364094) (xy 162.983437 -25.382693)
			(xy 162.990276 -25.390094) (xy 163.433506 -25.833324) (xy 163.440901 -25.840178) (xy 163.4595 -25.847922)
			(xy 163.469574 -25.84831) (xy 207.009746 -25.84831) (xy 207.020969 -25.847722) (xy 207.041289 -25.838184)
			(xy 207.055647 -25.820928) (xy 207.059022 -25.81021) (xy 207.087724 -25.697942) (xy 207.074008 -25.666192)
			(xy 207.058768 -25.65781) (xy 206.985113 -25.616734) (xy 206.841265 -25.528663) (xy 206.70166 -25.43401)
			(xy 206.566599 -25.33298) (xy 206.436372 -25.22579) (xy 206.311261 -25.112672) (xy 206.191535 -24.993868)
			(xy 206.077452 -24.869636) (xy 205.969258 -24.740242) (xy 205.867186 -24.605967) (xy 205.771456 -24.467098)
			(xy 205.682275 -24.323936) (xy 205.599835 -24.176789) (xy 205.524313 -24.025975) (xy 205.455872 -23.871817)
			(xy 205.39466 -23.71465) (xy 205.340809 -23.55481) (xy 205.294434 -23.392644) (xy 205.255636 -23.228499)
			(xy 205.224498 -23.062731) (xy 205.201088 -22.895697) (xy 205.185456 -22.727755) (xy 205.177635 -22.55927)
			(xy 205.177136 -22.474936) (xy 205.177642 -22.388469) (xy 205.185869 -22.215732) (xy 205.202307 -22.043582)
			(xy 205.226917 -21.872409) (xy 205.259645 -21.702601) (xy 205.300416 -21.534543) (xy 205.349138 -21.368615)
			(xy 205.405701 -21.205194) (xy 205.469976 -21.044649) (xy 205.541817 -20.887345) (xy 205.621062 -20.733637)
			(xy 205.707532 -20.583875) (xy 205.80103 -20.438396) (xy 205.901345 -20.297532) (xy 206.008249 -20.1616)
			(xy 206.1215 -20.03091) (xy 206.240842 -19.905757) (xy 206.366004 -19.786424) (xy 206.496702 -19.673182)
			(xy 206.632642 -19.566288) (xy 206.773513 -19.465983) (xy 206.918998 -19.372495) (xy 207.068767 -19.286037)
			(xy 207.222481 -19.206802) (xy 207.37979 -19.134972) (xy 207.54034 -19.070709) (xy 207.703765 -19.014159)
			(xy 207.869696 -18.965449) (xy 208.037757 -18.92469) (xy 208.207568 -18.891974) (xy 208.378742 -18.867375)
			(xy 208.550894 -18.85095) (xy 208.723631 -18.842735) (xy 208.810098 -18.842228) (xy 208.899889 -18.842768)
			(xy 209.079252 -18.851615) (xy 209.257958 -18.869318) (xy 209.435571 -18.895834) (xy 209.611656 -18.931097)
			(xy 209.785783 -18.975021) (xy 209.871818 -19.000724) (xy 209.883502 -19.00428) (xy 209.907124 -19.000216)
			(xy 209.982562 -18.944336) (xy 209.991785 -18.936723) (xy 210.002515 -18.915386) (xy 210.003136 -18.903442)
			(xy 210.003136 -8.567928) (xy 210.002698 -8.557865) (xy 209.994958 -8.539286) (xy 209.98815 -8.53186)
			(xy 208.752694 -7.296404) (xy 208.745295 -7.289558) (xy 208.726697 -7.281825) (xy 208.716626 -7.281418)
			(xy 87.427816 -7.281418) (xy 87.417753 -7.281857) (xy 87.399172 -7.289595) (xy 87.391748 -7.296404)
			(xy 84.90204 -9.786112) (xy 84.894642 -9.792958) (xy 84.876043 -9.800685) (xy 84.865972 -9.801098)
			(xy 59.622182 -9.801098) (xy 59.612113 -9.800671) (xy 59.593514 -9.792952) (xy 59.586114 -9.786112)
			(xy 57.533032 -7.73303) (xy 57.526193 -7.725629) (xy 57.518479 -7.707031) (xy 57.518046 -7.696962)
			(xy 57.518046 -1.874266) (xy 57.517615 -1.8642) (xy 57.509886 -1.845609) (xy 57.50306 -1.838198)
			(xy 57.117234 -1.452372) (xy 57.109835 -1.445528) (xy 57.091236 -1.437807) (xy 57.081166 -1.437386)
			(xy 4.084574 -1.437386) (xy 4.074506 -1.437813) (xy 4.055907 -1.445533) (xy 4.048506 -1.452372) (xy 1.710944 -3.789934)
			(xy 1.704098 -3.797332) (xy 1.696369 -3.815931) (xy 1.695958 -3.826002) (xy 1.695958 -14.732) (xy 80.135982 -14.732)
			(xy 80.140053 -14.676378) (xy 80.152179 -14.621941) (xy 80.172102 -14.56985) (xy 80.199398 -14.521215)
			(xy 80.233484 -14.477072) (xy 80.273633 -14.438363) (xy 80.318991 -14.405912) (xy 80.368591 -14.380411)
			(xy 80.421375 -14.362404) (xy 80.476218 -14.352274) (xy 80.531952 -14.350237) (xy 80.587389 -14.356337)
			(xy 80.641346 -14.370443) (xy 80.692675 -14.392255) (xy 80.740281 -14.421309) (xy 80.783149 -14.456984)
			(xy 80.820366 -14.498521) (xy 80.851139 -14.545034) (xy 80.874811 -14.595531) (xy 80.890879 -14.648938)
			(xy 80.898999 -14.704114) (xy 80.899508 -14.732) (xy 80.898999 -14.759886) (xy 80.890879 -14.815062)
			(xy 80.874811 -14.868469) (xy 80.851139 -14.918966) (xy 80.820366 -14.965479) (xy 80.783149 -15.007016)
			(xy 80.740281 -15.042691) (xy 80.692675 -15.071745) (xy 80.641346 -15.093557) (xy 80.587389 -15.107663)
			(xy 80.531952 -15.113763) (xy 80.476218 -15.111726) (xy 80.421375 -15.101596) (xy 80.368591 -15.083589)
			(xy 80.318991 -15.058088) (xy 80.273633 -15.025637) (xy 80.233484 -14.986928) (xy 80.199398 -14.942785)
			(xy 80.172102 -14.89415) (xy 80.152179 -14.842059) (xy 80.140053 -14.787622) (xy 80.135982 -14.732)
			(xy 1.695958 -14.732) (xy 1.695958 -16.383) (xy 80.135982 -16.383) (xy 80.140053 -16.327378) (xy 80.152179 -16.272941)
			(xy 80.172102 -16.22085) (xy 80.199398 -16.172215) (xy 80.233484 -16.128072) (xy 80.273633 -16.089363)
			(xy 80.318991 -16.056912) (xy 80.368591 -16.031411) (xy 80.421375 -16.013404) (xy 80.476218 -16.003274)
			(xy 80.531952 -16.001237) (xy 80.587389 -16.007337) (xy 80.641346 -16.021443) (xy 80.692675 -16.043255)
			(xy 80.740281 -16.072309) (xy 80.783149 -16.107984) (xy 80.820366 -16.149521) (xy 80.851139 -16.196034)
			(xy 80.874811 -16.246531) (xy 80.87766 -16.256) (xy 82.193382 -16.256) (xy 82.197453 -16.200378)
			(xy 82.209579 -16.145941) (xy 82.229502 -16.09385) (xy 82.256798 -16.045215) (xy 82.290884 -16.001072)
			(xy 82.331033 -15.962363) (xy 82.376391 -15.929912) (xy 82.425991 -15.904411) (xy 82.478775 -15.886404)
			(xy 82.533618 -15.876274) (xy 82.589352 -15.874237) (xy 82.644789 -15.880337) (xy 82.698746 -15.894443)
			(xy 82.750075 -15.916255) (xy 82.797681 -15.945309) (xy 82.840549 -15.980984) (xy 82.877766 -16.022521)
			(xy 82.908539 -16.069034) (xy 82.912836 -16.0782) (xy 84.072982 -16.0782) (xy 84.077053 -16.022578)
			(xy 84.089179 -15.968141) (xy 84.109102 -15.91605) (xy 84.136398 -15.867415) (xy 84.170484 -15.823272)
			(xy 84.210633 -15.784563) (xy 84.255991 -15.752112) (xy 84.305591 -15.726611) (xy 84.358375 -15.708604)
			(xy 84.413218 -15.698474) (xy 84.468952 -15.696437) (xy 84.524389 -15.702537) (xy 84.578346 -15.716643)
			(xy 84.629675 -15.738455) (xy 84.677281 -15.767509) (xy 84.720149 -15.803184) (xy 84.757366 -15.844721)
			(xy 84.788139 -15.891234) (xy 84.811811 -15.941731) (xy 84.827879 -15.995138) (xy 84.835999 -16.050314)
			(xy 84.836508 -16.0782) (xy 84.835999 -16.106086) (xy 84.827879 -16.161262) (xy 84.811811 -16.214669)
			(xy 84.788139 -16.265166) (xy 84.757366 -16.311679) (xy 84.720149 -16.353216) (xy 84.677281 -16.388891)
			(xy 84.629675 -16.417945) (xy 84.578346 -16.439757) (xy 84.524389 -16.453863) (xy 84.468952 -16.459963)
			(xy 84.413218 -16.457926) (xy 84.358375 -16.447796) (xy 84.305591 -16.429789) (xy 84.255991 -16.404288)
			(xy 84.210633 -16.371837) (xy 84.170484 -16.333128) (xy 84.136398 -16.288985) (xy 84.109102 -16.24035)
			(xy 84.089179 -16.188259) (xy 84.077053 -16.133822) (xy 84.072982 -16.0782) (xy 82.912836 -16.0782)
			(xy 82.932211 -16.119531) (xy 82.948279 -16.172938) (xy 82.956399 -16.228114) (xy 82.956908 -16.256)
			(xy 82.956399 -16.283886) (xy 82.948279 -16.339062) (xy 82.932211 -16.392469) (xy 82.908539 -16.442966)
			(xy 82.877766 -16.489479) (xy 82.840549 -16.531016) (xy 82.797681 -16.566691) (xy 82.750075 -16.595745)
			(xy 82.698746 -16.617557) (xy 82.644789 -16.631663) (xy 82.589352 -16.637763) (xy 82.533618 -16.635726)
			(xy 82.478775 -16.625596) (xy 82.425991 -16.607589) (xy 82.376391 -16.582088) (xy 82.331033 -16.549637)
			(xy 82.290884 -16.510928) (xy 82.256798 -16.466785) (xy 82.229502 -16.41815) (xy 82.209579 -16.366059)
			(xy 82.197453 -16.311622) (xy 82.193382 -16.256) (xy 80.87766 -16.256) (xy 80.890879 -16.299938)
			(xy 80.898999 -16.355114) (xy 80.899508 -16.383) (xy 80.898999 -16.410886) (xy 80.890879 -16.466062)
			(xy 80.874811 -16.519469) (xy 80.851139 -16.569966) (xy 80.820366 -16.616479) (xy 80.783149 -16.658016)
			(xy 80.740281 -16.693691) (xy 80.692675 -16.722745) (xy 80.641346 -16.744557) (xy 80.587389 -16.758663)
			(xy 80.531952 -16.764763) (xy 80.476218 -16.762726) (xy 80.421375 -16.752596) (xy 80.368591 -16.734589)
			(xy 80.318991 -16.709088) (xy 80.273633 -16.676637) (xy 80.233484 -16.637928) (xy 80.199398 -16.593785)
			(xy 80.172102 -16.54515) (xy 80.152179 -16.493059) (xy 80.140053 -16.438622) (xy 80.135982 -16.383)
			(xy 1.695958 -16.383) (xy 1.695958 -16.891) (xy 81.278982 -16.891) (xy 81.283053 -16.835378) (xy 81.295179 -16.780941)
			(xy 81.315102 -16.72885) (xy 81.342398 -16.680215) (xy 81.376484 -16.636072) (xy 81.416633 -16.597363)
			(xy 81.461991 -16.564912) (xy 81.511591 -16.539411) (xy 81.564375 -16.521404) (xy 81.619218 -16.511274)
			(xy 81.674952 -16.509237) (xy 81.730389 -16.515337) (xy 81.784346 -16.529443) (xy 81.835675 -16.551255)
			(xy 81.883281 -16.580309) (xy 81.926149 -16.615984) (xy 81.963366 -16.657521) (xy 81.994139 -16.704034)
			(xy 82.017811 -16.754531) (xy 82.033879 -16.807938) (xy 82.041999 -16.863114) (xy 82.042508 -16.891)
			(xy 82.041999 -16.918886) (xy 82.033879 -16.974062) (xy 82.017811 -17.027469) (xy 81.994139 -17.077966)
			(xy 81.963366 -17.124479) (xy 81.926149 -17.166016) (xy 81.883281 -17.201691) (xy 81.835675 -17.230745)
			(xy 81.784346 -17.252557) (xy 81.730389 -17.266663) (xy 81.674952 -17.272763) (xy 81.619218 -17.270726)
			(xy 81.564375 -17.260596) (xy 81.511591 -17.242589) (xy 81.461991 -17.217088) (xy 81.416633 -17.184637)
			(xy 81.376484 -17.145928) (xy 81.342398 -17.101785) (xy 81.315102 -17.05315) (xy 81.295179 -17.001059)
			(xy 81.283053 -16.946622) (xy 81.278982 -16.891) (xy 1.695958 -16.891) (xy 1.695958 -20.63857) (xy 56.730635 -20.63857)
			(xy 56.730635 -20.50943) (xy 56.738585 -20.380535) (xy 56.754455 -20.252375) (xy 56.778184 -20.125434)
			(xy 56.809683 -20.000195) (xy 56.848832 -19.877132) (xy 56.895483 -19.756713) (xy 56.949458 -19.639394)
			(xy 57.010553 -19.52562) (xy 57.078536 -19.415823) (xy 57.15315 -19.31042) (xy 57.234111 -19.20981)
			(xy 57.321111 -19.114375) (xy 57.413822 -19.024476) (xy 57.511892 -18.940455) (xy 57.614947 -18.862631)
			(xy 57.722598 -18.791299) (xy 57.834437 -18.726729) (xy 57.950038 -18.669167) (xy 58.068963 -18.61883)
			(xy 58.190762 -18.57591) (xy 58.314972 -18.540569) (xy 58.441121 -18.512942) (xy 58.568733 -18.493133)
			(xy 58.697322 -18.481217) (xy 58.8264 -18.477241) (xy 58.955478 -18.481217) (xy 59.084067 -18.493133)
			(xy 59.211679 -18.512942) (xy 59.337828 -18.540569) (xy 59.462038 -18.57591) (xy 59.583837 -18.61883)
			(xy 59.702762 -18.669167) (xy 59.818363 -18.726729) (xy 59.930202 -18.791299) (xy 60.037853 -18.862631)
			(xy 60.109385 -18.91665) (xy 80.135982 -18.91665) (xy 80.140053 -18.861028) (xy 80.152179 -18.806591)
			(xy 80.172102 -18.7545) (xy 80.199398 -18.705865) (xy 80.233484 -18.661722) (xy 80.273633 -18.623013)
			(xy 80.318991 -18.590562) (xy 80.368591 -18.565061) (xy 80.421375 -18.547054) (xy 80.476218 -18.536924)
			(xy 80.531952 -18.534887) (xy 80.587389 -18.540987) (xy 80.641346 -18.555093) (xy 80.692675 -18.576905)
			(xy 80.740281 -18.605959) (xy 80.783149 -18.641634) (xy 80.820366 -18.683171) (xy 80.851139 -18.729684)
			(xy 80.874811 -18.780181) (xy 80.890879 -18.833588) (xy 80.898999 -18.888764) (xy 80.899508 -18.91665)
			(xy 81.278982 -18.91665) (xy 81.283053 -18.861028) (xy 81.295179 -18.806591) (xy 81.315102 -18.7545)
			(xy 81.342398 -18.705865) (xy 81.376484 -18.661722) (xy 81.416633 -18.623013) (xy 81.461991 -18.590562)
			(xy 81.511591 -18.565061) (xy 81.564375 -18.547054) (xy 81.619218 -18.536924) (xy 81.674952 -18.534887)
			(xy 81.730389 -18.540987) (xy 81.784346 -18.555093) (xy 81.835675 -18.576905) (xy 81.883281 -18.605959)
			(xy 81.926149 -18.641634) (xy 81.963366 -18.683171) (xy 81.994139 -18.729684) (xy 82.017811 -18.780181)
			(xy 82.033879 -18.833588) (xy 82.041999 -18.888764) (xy 82.042508 -18.91665) (xy 82.042503 -18.916904)
			(xy 82.421982 -18.916904) (xy 82.426053 -18.861282) (xy 82.438179 -18.806845) (xy 82.458102 -18.754754)
			(xy 82.485398 -18.706119) (xy 82.519484 -18.661976) (xy 82.559633 -18.623267) (xy 82.604991 -18.590816)
			(xy 82.654591 -18.565315) (xy 82.707375 -18.547308) (xy 82.762218 -18.537178) (xy 82.817952 -18.535141)
			(xy 82.873389 -18.541241) (xy 82.927346 -18.555347) (xy 82.978675 -18.577159) (xy 83.026281 -18.606213)
			(xy 83.069149 -18.641888) (xy 83.106366 -18.683425) (xy 83.137139 -18.729938) (xy 83.160811 -18.780435)
			(xy 83.176879 -18.833842) (xy 83.184999 -18.889018) (xy 83.185508 -18.916904) (xy 83.564982 -18.916904)
			(xy 83.569053 -18.861282) (xy 83.581179 -18.806845) (xy 83.601102 -18.754754) (xy 83.628398 -18.706119)
			(xy 83.662484 -18.661976) (xy 83.702633 -18.623267) (xy 83.747991 -18.590816) (xy 83.797591 -18.565315)
			(xy 83.850375 -18.547308) (xy 83.905218 -18.537178) (xy 83.960952 -18.535141) (xy 84.016389 -18.541241)
			(xy 84.070346 -18.555347) (xy 84.121675 -18.577159) (xy 84.169281 -18.606213) (xy 84.212149 -18.641888)
			(xy 84.249366 -18.683425) (xy 84.280139 -18.729938) (xy 84.303811 -18.780435) (xy 84.319879 -18.833842)
			(xy 84.327999 -18.889018) (xy 84.328508 -18.916904) (xy 84.327999 -18.94479) (xy 84.319879 -18.999966)
			(xy 84.303811 -19.053373) (xy 84.280139 -19.10387) (xy 84.249366 -19.150383) (xy 84.212149 -19.19192)
			(xy 84.169281 -19.227595) (xy 84.121675 -19.256649) (xy 84.070346 -19.278461) (xy 84.016389 -19.292567)
			(xy 83.960952 -19.298667) (xy 83.905218 -19.29663) (xy 83.850375 -19.2865) (xy 83.797591 -19.268493)
			(xy 83.747991 -19.242992) (xy 83.702633 -19.210541) (xy 83.662484 -19.171832) (xy 83.628398 -19.127689)
			(xy 83.601102 -19.079054) (xy 83.581179 -19.026963) (xy 83.569053 -18.972526) (xy 83.564982 -18.916904)
			(xy 83.185508 -18.916904) (xy 83.184999 -18.94479) (xy 83.176879 -18.999966) (xy 83.160811 -19.053373)
			(xy 83.137139 -19.10387) (xy 83.106366 -19.150383) (xy 83.069149 -19.19192) (xy 83.026281 -19.227595)
			(xy 82.978675 -19.256649) (xy 82.927346 -19.278461) (xy 82.873389 -19.292567) (xy 82.817952 -19.298667)
			(xy 82.762218 -19.29663) (xy 82.707375 -19.2865) (xy 82.654591 -19.268493) (xy 82.604991 -19.242992)
			(xy 82.559633 -19.210541) (xy 82.519484 -19.171832) (xy 82.485398 -19.127689) (xy 82.458102 -19.079054)
			(xy 82.438179 -19.026963) (xy 82.426053 -18.972526) (xy 82.421982 -18.916904) (xy 82.042503 -18.916904)
			(xy 82.041999 -18.944536) (xy 82.033879 -18.999712) (xy 82.017811 -19.053119) (xy 81.994139 -19.103616)
			(xy 81.963366 -19.150129) (xy 81.926149 -19.191666) (xy 81.883281 -19.227341) (xy 81.835675 -19.256395)
			(xy 81.784346 -19.278207) (xy 81.730389 -19.292313) (xy 81.674952 -19.298413) (xy 81.619218 -19.296376)
			(xy 81.564375 -19.286246) (xy 81.511591 -19.268239) (xy 81.461991 -19.242738) (xy 81.416633 -19.210287)
			(xy 81.376484 -19.171578) (xy 81.342398 -19.127435) (xy 81.315102 -19.0788) (xy 81.295179 -19.026709)
			(xy 81.283053 -18.972272) (xy 81.278982 -18.91665) (xy 80.899508 -18.91665) (xy 80.898999 -18.944536)
			(xy 80.890879 -18.999712) (xy 80.874811 -19.053119) (xy 80.851139 -19.103616) (xy 80.820366 -19.150129)
			(xy 80.783149 -19.191666) (xy 80.740281 -19.227341) (xy 80.692675 -19.256395) (xy 80.641346 -19.278207)
			(xy 80.587389 -19.292313) (xy 80.531952 -19.298413) (xy 80.476218 -19.296376) (xy 80.421375 -19.286246)
			(xy 80.368591 -19.268239) (xy 80.318991 -19.242738) (xy 80.273633 -19.210287) (xy 80.233484 -19.171578)
			(xy 80.199398 -19.127435) (xy 80.172102 -19.0788) (xy 80.152179 -19.026709) (xy 80.140053 -18.972272)
			(xy 80.135982 -18.91665) (xy 60.109385 -18.91665) (xy 60.140908 -18.940455) (xy 60.238978 -19.024476)
			(xy 60.331689 -19.114375) (xy 60.418689 -19.20981) (xy 60.49965 -19.31042) (xy 60.574264 -19.415823)
			(xy 60.642247 -19.52562) (xy 60.703342 -19.639394) (xy 60.757317 -19.756713) (xy 60.803968 -19.877132)
			(xy 60.843117 -20.000195) (xy 60.874616 -20.125434) (xy 60.898345 -20.252375) (xy 60.914215 -20.380535)
			(xy 60.922165 -20.50943) (xy 60.922662 -20.574) (xy 60.922165 -20.63857) (xy 60.914215 -20.767465)
			(xy 60.898345 -20.895625) (xy 60.874616 -21.022566) (xy 60.843117 -21.147805) (xy 60.803968 -21.270868)
			(xy 60.757317 -21.391287) (xy 60.703342 -21.508606) (xy 60.642247 -21.62238) (xy 60.574264 -21.732177)
			(xy 60.49965 -21.83758) (xy 60.418689 -21.93819) (xy 60.331689 -22.033625) (xy 60.238978 -22.123524)
			(xy 60.140908 -22.207545) (xy 60.037853 -22.285369) (xy 59.930202 -22.356701) (xy 59.818363 -22.421271)
			(xy 59.702762 -22.478833) (xy 59.583837 -22.52917) (xy 59.462038 -22.57209) (xy 59.337828 -22.607431)
			(xy 59.211679 -22.635058) (xy 59.084067 -22.654867) (xy 58.955478 -22.666783) (xy 58.8264 -22.67076)
			(xy 58.697322 -22.666783) (xy 58.568733 -22.654867) (xy 58.441121 -22.635058) (xy 58.314972 -22.607431)
			(xy 58.190762 -22.57209) (xy 58.068963 -22.52917) (xy 57.950038 -22.478833) (xy 57.834437 -22.421271)
			(xy 57.722598 -22.356701) (xy 57.614947 -22.285369) (xy 57.511892 -22.207545) (xy 57.413822 -22.123524)
			(xy 57.321111 -22.033625) (xy 57.234111 -21.93819) (xy 57.15315 -21.83758) (xy 57.078536 -21.732177)
			(xy 57.010553 -21.62238) (xy 56.949458 -21.508606) (xy 56.895483 -21.391287) (xy 56.848832 -21.270868)
			(xy 56.809683 -21.147805) (xy 56.778184 -21.022566) (xy 56.754455 -20.895625) (xy 56.738585 -20.767465)
			(xy 56.730635 -20.63857) (xy 1.695958 -20.63857) (xy 1.695958 -25.72639) (xy 39.441372 -25.72639)
			(xy 39.445443 -25.670768) (xy 39.457569 -25.616331) (xy 39.477492 -25.56424) (xy 39.504788 -25.515605)
			(xy 39.538874 -25.471462) (xy 39.579023 -25.432753) (xy 39.624381 -25.400302) (xy 39.673981 -25.374801)
			(xy 39.726765 -25.356794) (xy 39.781608 -25.346664) (xy 39.837342 -25.344627) (xy 39.892779 -25.350727)
			(xy 39.946736 -25.364833) (xy 39.998065 -25.386645) (xy 40.045671 -25.415699) (xy 40.088539 -25.451374)
			(xy 40.125756 -25.492911) (xy 40.156529 -25.539424) (xy 40.180201 -25.589921) (xy 40.196269 -25.643328)
			(xy 40.204389 -25.698504) (xy 40.204898 -25.72639) (xy 40.204389 -25.754276) (xy 40.196269 -25.809452)
			(xy 40.180201 -25.862859) (xy 40.15904 -25.908) (xy 44.521372 -25.908) (xy 44.525443 -25.852378)
			(xy 44.537569 -25.797941) (xy 44.557492 -25.74585) (xy 44.584788 -25.697215) (xy 44.618874 -25.653072)
			(xy 44.659023 -25.614363) (xy 44.704381 -25.581912) (xy 44.753981 -25.556411) (xy 44.806765 -25.538404)
			(xy 44.861608 -25.528274) (xy 44.917342 -25.526237) (xy 44.972779 -25.532337) (xy 45.026736 -25.546443)
			(xy 45.078065 -25.568255) (xy 45.125671 -25.597309) (xy 45.168539 -25.632984) (xy 45.205756 -25.674521)
			(xy 45.236529 -25.721034) (xy 45.260201 -25.771531) (xy 45.276269 -25.824938) (xy 45.284389 -25.880114)
			(xy 45.284898 -25.908) (xy 45.284389 -25.935886) (xy 45.276269 -25.991062) (xy 45.260201 -26.044469)
			(xy 45.236529 -26.094966) (xy 45.205756 -26.141479) (xy 45.168539 -26.183016) (xy 45.125671 -26.218691)
			(xy 45.078065 -26.247745) (xy 45.026736 -26.269557) (xy 44.972779 -26.283663) (xy 44.917342 -26.289763)
			(xy 44.861608 -26.287726) (xy 44.806765 -26.277596) (xy 44.753981 -26.259589) (xy 44.704381 -26.234088)
			(xy 44.659023 -26.201637) (xy 44.618874 -26.162928) (xy 44.584788 -26.118785) (xy 44.557492 -26.07015)
			(xy 44.537569 -26.018059) (xy 44.525443 -25.963622) (xy 44.521372 -25.908) (xy 40.15904 -25.908)
			(xy 40.156529 -25.913356) (xy 40.125756 -25.959869) (xy 40.088539 -26.001406) (xy 40.045671 -26.037081)
			(xy 39.998065 -26.066135) (xy 39.946736 -26.087947) (xy 39.892779 -26.102053) (xy 39.837342 -26.108153)
			(xy 39.781608 -26.106116) (xy 39.726765 -26.095986) (xy 39.673981 -26.077979) (xy 39.624381 -26.052478)
			(xy 39.579023 -26.020027) (xy 39.538874 -25.981318) (xy 39.504788 -25.937175) (xy 39.477492 -25.88854)
			(xy 39.457569 -25.836449) (xy 39.445443 -25.782012) (xy 39.441372 -25.72639) (xy 1.695958 -25.72639)
			(xy 1.695958 -27.051) (xy 47.268382 -27.051) (xy 47.272453 -26.995378) (xy 47.284579 -26.940941)
			(xy 47.304502 -26.88885) (xy 47.331798 -26.840215) (xy 47.365884 -26.796072) (xy 47.406033 -26.757363)
			(xy 47.451391 -26.724912) (xy 47.500991 -26.699411) (xy 47.553775 -26.681404) (xy 47.608618 -26.671274)
			(xy 47.664352 -26.669237) (xy 47.719789 -26.675337) (xy 47.773746 -26.689443) (xy 47.825075 -26.711255)
			(xy 47.872681 -26.740309) (xy 47.915549 -26.775984) (xy 47.952766 -26.817521) (xy 47.983539 -26.864034)
			(xy 48.007211 -26.914531) (xy 48.015791 -26.94305) (xy 53.319932 -26.94305) (xy 53.324003 -26.887428)
			(xy 53.336129 -26.832991) (xy 53.356052 -26.7809) (xy 53.383348 -26.732265) (xy 53.417434 -26.688122)
			(xy 53.457583 -26.649413) (xy 53.502941 -26.616962) (xy 53.552541 -26.591461) (xy 53.605325 -26.573454)
			(xy 53.660168 -26.563324) (xy 53.715902 -26.561287) (xy 53.771339 -26.567387) (xy 53.825296 -26.581493)
			(xy 53.876625 -26.603305) (xy 53.924231 -26.632359) (xy 53.967099 -26.668034) (xy 54.004316 -26.709571)
			(xy 54.035089 -26.756084) (xy 54.058761 -26.806581) (xy 54.074829 -26.859988) (xy 54.082949 -26.915164)
			(xy 54.083458 -26.94305) (xy 54.082949 -26.970936) (xy 54.074829 -27.026112) (xy 54.058761 -27.079519)
			(xy 54.035089 -27.130016) (xy 54.004316 -27.176529) (xy 53.967099 -27.218066) (xy 53.924231 -27.253741)
			(xy 53.876625 -27.282795) (xy 53.825296 -27.304607) (xy 53.771339 -27.318713) (xy 53.715902 -27.324813)
			(xy 53.660168 -27.322776) (xy 53.605325 -27.312646) (xy 53.552541 -27.294639) (xy 53.502941 -27.269138)
			(xy 53.457583 -27.236687) (xy 53.417434 -27.197978) (xy 53.383348 -27.153835) (xy 53.356052 -27.1052)
			(xy 53.336129 -27.053109) (xy 53.324003 -26.998672) (xy 53.319932 -26.94305) (xy 48.015791 -26.94305)
			(xy 48.023279 -26.967938) (xy 48.031399 -27.023114) (xy 48.031908 -27.051) (xy 48.031399 -27.078886)
			(xy 48.023279 -27.134062) (xy 48.007211 -27.187469) (xy 47.983539 -27.237966) (xy 47.952766 -27.284479)
			(xy 47.915549 -27.326016) (xy 47.872681 -27.361691) (xy 47.825075 -27.390745) (xy 47.773746 -27.412557)
			(xy 47.719789 -27.426663) (xy 47.664352 -27.432763) (xy 47.608618 -27.430726) (xy 47.553775 -27.420596)
			(xy 47.500991 -27.402589) (xy 47.451391 -27.377088) (xy 47.406033 -27.344637) (xy 47.365884 -27.305928)
			(xy 47.331798 -27.261785) (xy 47.304502 -27.21315) (xy 47.284579 -27.161059) (xy 47.272453 -27.106622)
			(xy 47.268382 -27.051) (xy 1.695958 -27.051) (xy 1.695958 -34.036) (xy 33.806382 -34.036) (xy 33.810453 -33.980378)
			(xy 33.822579 -33.925941) (xy 33.842502 -33.87385) (xy 33.869798 -33.825215) (xy 33.903884 -33.781072)
			(xy 33.944033 -33.742363) (xy 33.989391 -33.709912) (xy 34.038991 -33.684411) (xy 34.091775 -33.666404)
			(xy 34.146618 -33.656274) (xy 34.202352 -33.654237) (xy 34.257789 -33.660337) (xy 34.311746 -33.674443)
			(xy 34.363075 -33.696255) (xy 34.410681 -33.725309) (xy 34.453549 -33.760984) (xy 34.490766 -33.802521)
			(xy 34.521539 -33.849034) (xy 34.545211 -33.899531) (xy 34.561279 -33.952938) (xy 34.569399 -34.008114)
			(xy 34.569908 -34.036) (xy 34.569399 -34.063886) (xy 34.561279 -34.119062) (xy 34.545211 -34.172469)
			(xy 34.521539 -34.222966) (xy 34.490766 -34.269479) (xy 34.453549 -34.311016) (xy 34.410681 -34.346691)
			(xy 34.363075 -34.375745) (xy 34.311746 -34.397557) (xy 34.257789 -34.411663) (xy 34.202352 -34.417763)
			(xy 34.146618 -34.415726) (xy 34.091775 -34.405596) (xy 34.038991 -34.387589) (xy 33.989391 -34.362088)
			(xy 33.944033 -34.329637) (xy 33.903884 -34.290928) (xy 33.869798 -34.246785) (xy 33.842502 -34.19815)
			(xy 33.822579 -34.146059) (xy 33.810453 -34.091622) (xy 33.806382 -34.036) (xy 1.695958 -34.036)
			(xy 1.695958 -60.099956) (xy 12.484104 -60.099956) (xy 12.488134 -59.957621) (xy 12.500209 -59.815741)
			(xy 12.520292 -59.674773) (xy 12.548319 -59.535166) (xy 12.584199 -59.397368) (xy 12.627817 -59.261821)
			(xy 12.679034 -59.128959) (xy 12.737685 -58.999207) (xy 12.803583 -58.872981) (xy 12.876517 -58.750685)
			(xy 12.956254 -58.632712) (xy 13.042536 -58.519439) (xy 13.135089 -58.411228) (xy 13.233616 -58.308427)
			(xy 13.337801 -58.211365) (xy 13.44731 -58.120353) (xy 13.561793 -58.035681) (xy 13.680883 -57.957623)
			(xy 13.804198 -57.886427) (xy 13.931344 -57.822321) (xy 14.061913 -57.765512) (xy 14.195487 -57.71618)
			(xy 14.331638 -57.674484) (xy 14.469929 -57.640558) (xy 14.609919 -57.61451) (xy 14.751158 -57.596424)
			(xy 14.893194 -57.586357) (xy 15.035572 -57.584342) (xy 15.177836 -57.590385) (xy 15.31953 -57.604467)
			(xy 15.4602 -57.626543) (xy 15.599397 -57.656543) (xy 15.736673 -57.694369) (xy 15.871589 -57.739901)
			(xy 16.003713 -57.792992) (xy 16.132622 -57.853474) (xy 16.257903 -57.921152) (xy 16.379154 -57.995809)
			(xy 16.495987 -58.077207) (xy 16.608028 -58.165084) (xy 16.714918 -58.259159) (xy 16.816315 -58.359131)
			(xy 16.911893 -58.464679) (xy 17.001347 -58.575465) (xy 17.084389 -58.691134) (xy 17.160755 -58.811317)
			(xy 17.230199 -58.935627) (xy 17.292499 -59.063668) (xy 17.347455 -59.195027) (xy 17.394892 -59.329286)
			(xy 17.434656 -59.466013) (xy 17.466622 -59.604771) (xy 17.490687 -59.745115) (xy 17.506773 -59.886596)
			(xy 17.514828 -60.02876) (xy 17.515332 -60.099956) (xy 17.514828 -60.171152) (xy 17.506773 -60.313316)
			(xy 17.490687 -60.454797) (xy 17.466622 -60.595141) (xy 17.434656 -60.733899) (xy 17.394892 -60.870626)
			(xy 17.347455 -61.004885) (xy 17.292499 -61.136244) (xy 17.230199 -61.264285) (xy 17.160755 -61.388595)
			(xy 17.084389 -61.508778) (xy 17.001347 -61.624447) (xy 16.911893 -61.735233) (xy 16.816315 -61.840781)
			(xy 16.714918 -61.940753) (xy 16.608028 -62.034828) (xy 16.495987 -62.122705) (xy 16.379154 -62.204103)
			(xy 16.257903 -62.27876) (xy 16.132622 -62.346438) (xy 16.003713 -62.40692) (xy 15.871589 -62.460011)
			(xy 15.736673 -62.505543) (xy 15.599397 -62.543369) (xy 15.4602 -62.573369) (xy 15.31953 -62.595445)
			(xy 15.177836 -62.609527) (xy 15.035572 -62.61557) (xy 14.893194 -62.613555) (xy 14.751158 -62.603488)
			(xy 14.609919 -62.585402) (xy 14.469929 -62.559354) (xy 14.331638 -62.525428) (xy 14.195487 -62.483732)
			(xy 14.061913 -62.4344) (xy 13.931344 -62.377591) (xy 13.804198 -62.313485) (xy 13.680883 -62.242289)
			(xy 13.561793 -62.164231) (xy 13.44731 -62.079559) (xy 13.337801 -61.988547) (xy 13.233616 -61.891485)
			(xy 13.135089 -61.788684) (xy 13.042536 -61.680473) (xy 12.956254 -61.5672) (xy 12.876517 -61.449227)
			(xy 12.803583 -61.326931) (xy 12.737685 -61.200705) (xy 12.679034 -61.070953) (xy 12.627817 -60.938091)
			(xy 12.584199 -60.802544) (xy 12.548319 -60.664746) (xy 12.520292 -60.525139) (xy 12.500209 -60.384171)
			(xy 12.488134 -60.242291) (xy 12.484104 -60.099956) (xy 1.695958 -60.099956) (xy 1.695958 -104.544876)
			(xy 12.484104 -104.544876) (xy 12.488134 -104.402541) (xy 12.500209 -104.260661) (xy 12.520292 -104.119693)
			(xy 12.548319 -103.980086) (xy 12.584199 -103.842288) (xy 12.627817 -103.706741) (xy 12.679034 -103.573879)
			(xy 12.737685 -103.444127) (xy 12.803583 -103.317901) (xy 12.876517 -103.195605) (xy 12.956254 -103.077632)
			(xy 13.042536 -102.964359) (xy 13.135089 -102.856148) (xy 13.233616 -102.753347) (xy 13.337801 -102.656285)
			(xy 13.44731 -102.565273) (xy 13.561793 -102.480601) (xy 13.680883 -102.402543) (xy 13.804198 -102.331347)
			(xy 13.931344 -102.267241) (xy 14.061913 -102.210432) (xy 14.195487 -102.1611) (xy 14.331638 -102.119404)
			(xy 14.469929 -102.085478) (xy 14.609919 -102.05943) (xy 14.751158 -102.041344) (xy 14.893194 -102.031277)
			(xy 15.035572 -102.029262) (xy 15.177836 -102.035305) (xy 15.31953 -102.049387) (xy 15.4602 -102.071463)
			(xy 15.599397 -102.101463) (xy 15.736673 -102.139289) (xy 15.871589 -102.184821) (xy 16.003713 -102.237912)
			(xy 16.132622 -102.298394) (xy 16.257903 -102.366072) (xy 16.379154 -102.440729) (xy 16.495987 -102.522127)
			(xy 16.608028 -102.610004) (xy 16.714918 -102.704079) (xy 16.816315 -102.804051) (xy 16.911893 -102.909599)
			(xy 17.001347 -103.020385) (xy 17.084389 -103.136054) (xy 17.160755 -103.256237) (xy 17.230199 -103.380547)
			(xy 17.292499 -103.508588) (xy 17.347455 -103.639947) (xy 17.394892 -103.774206) (xy 17.434656 -103.910933)
			(xy 17.466622 -104.049691) (xy 17.490687 -104.190035) (xy 17.506773 -104.331516) (xy 17.514828 -104.47368)
			(xy 17.515332 -104.544876) (xy 17.514828 -104.616072) (xy 17.506773 -104.758236) (xy 17.490687 -104.899717)
			(xy 17.466622 -105.040061) (xy 17.434656 -105.178819) (xy 17.394892 -105.315546) (xy 17.347455 -105.449805)
			(xy 17.292499 -105.581164) (xy 17.230199 -105.709205) (xy 17.160755 -105.833515) (xy 17.084389 -105.953698)
			(xy 17.001347 -106.069367) (xy 16.911893 -106.180153) (xy 16.816315 -106.285701) (xy 16.714918 -106.385673)
			(xy 16.608028 -106.479748) (xy 16.495987 -106.567625) (xy 16.379154 -106.649023) (xy 16.257903 -106.72368)
			(xy 16.132622 -106.791358) (xy 16.003713 -106.85184) (xy 15.871589 -106.904931) (xy 15.736673 -106.950463)
			(xy 15.599397 -106.988289) (xy 15.4602 -107.018289) (xy 15.31953 -107.040365) (xy 15.177836 -107.054447)
			(xy 15.035572 -107.06049) (xy 14.893194 -107.058475) (xy 14.751158 -107.048408) (xy 14.609919 -107.030322)
			(xy 14.469929 -107.004274) (xy 14.331638 -106.970348) (xy 14.195487 -106.928652) (xy 14.061913 -106.87932)
			(xy 13.931344 -106.822511) (xy 13.804198 -106.758405) (xy 13.680883 -106.687209) (xy 13.561793 -106.609151)
			(xy 13.44731 -106.524479) (xy 13.337801 -106.433467) (xy 13.233616 -106.336405) (xy 13.135089 -106.233604)
			(xy 13.042536 -106.125393) (xy 12.956254 -106.01212) (xy 12.876517 -105.894147) (xy 12.803583 -105.771851)
			(xy 12.737685 -105.645625) (xy 12.679034 -105.515873) (xy 12.627817 -105.383011) (xy 12.584199 -105.247464)
			(xy 12.548319 -105.109666) (xy 12.520292 -104.970059) (xy 12.500209 -104.829091) (xy 12.488134 -104.687211)
			(xy 12.484104 -104.544876) (xy 1.695958 -104.544876) (xy 1.695958 -154.473148) (xy 1.696391 -154.483213)
			(xy 1.704125 -154.501799) (xy 1.710944 -154.509216) (xy 2.62255 -155.420822) (xy 2.629947 -155.427669)
			(xy 2.648547 -155.435398) (xy 2.658618 -155.435808)
		)
		(stroke
			(width 0)
			(type solid)
		)
		(fill yes)
		(layer "In7.Cu")
		(net "GND")
	)
	(gr_poly
		(pts
			(xy 75.000104 -171.141898) (xy 75.095459 -171.141392) (xy 75.285997 -171.133298) (xy 75.47602 -171.117124)
			(xy 75.665185 -171.092901) (xy 75.853152 -171.06067) (xy 76.039581 -171.020492) (xy 76.224138 -170.972437)
			(xy 76.406488 -170.916593) (xy 76.586304 -170.853059) (xy 76.763262 -170.781952) (xy 76.937042 -170.703398)
			(xy 77.107332 -170.61754) (xy 77.273824 -170.524532) (xy 77.436219 -170.424541) (xy 77.594224 -170.317748)
			(xy 77.747555 -170.204346) (xy 77.895934 -170.084538) (xy 78.039094 -169.958541) (xy 78.176779 -169.826581)
			(xy 78.308738 -169.688897) (xy 78.434736 -169.545737) (xy 78.554543 -169.397358) (xy 78.667946 -169.244028)
			(xy 78.774739 -169.086023) (xy 78.87473 -168.923628) (xy 78.967738 -168.757135) (xy 79.053597 -168.586846)
			(xy 79.13215 -168.413065) (xy 79.203258 -168.236108) (xy 79.266791 -168.056292) (xy 79.322636 -167.873941)
			(xy 79.370691 -167.689385) (xy 79.41087 -167.502956) (xy 79.4431 -167.314989) (xy 79.467324 -167.125824)
			(xy 79.483497 -166.935801) (xy 79.491592 -166.745263) (xy 79.492094 -166.649908) (xy 79.492094 -161.299906)
			(xy 79.49259 -161.216412) (xy 79.500536 -161.049613) (xy 79.516409 -160.88338) (xy 79.540173 -160.718091)
			(xy 79.571776 -160.554121) (xy 79.611145 -160.391839) (xy 79.65819 -160.231615) (xy 79.712807 -160.073811)
			(xy 79.774869 -159.918784) (xy 79.844239 -159.766886) (xy 79.920757 -159.61846) (xy 80.004251 -159.473844)
			(xy 80.094531 -159.333364) (xy 80.191394 -159.197339) (xy 80.294619 -159.066077) (xy 80.403972 -158.939876)
			(xy 80.519207 -158.81902) (xy 80.640062 -158.703785) (xy 80.766263 -158.59443) (xy 80.897525 -158.491204)
			(xy 81.033549 -158.394341) (xy 81.174029 -158.30406) (xy 81.318645 -158.220565) (xy 81.46707 -158.144047)
			(xy 81.618967 -158.074677) (xy 81.773994 -158.012613) (xy 81.931798 -157.957996) (xy 82.092022 -157.910949)
			(xy 82.254303 -157.87158) (xy 82.418274 -157.839976) (xy 82.583562 -157.816211) (xy 82.749795 -157.800337)
			(xy 82.916594 -157.792391) (xy 83.000088 -157.791912) (xy 83.49996 -157.791912) (xy 83.595316 -157.791414)
			(xy 83.785856 -157.783321) (xy 83.97588 -157.76715) (xy 84.165048 -157.742927) (xy 84.353016 -157.710699)
			(xy 84.539448 -157.670521) (xy 84.724006 -157.622468) (xy 84.906359 -157.566624) (xy 85.086177 -157.503092)
			(xy 85.263137 -157.431985) (xy 85.436919 -157.353432) (xy 85.607211 -157.267575) (xy 85.773706 -157.174567)
			(xy 85.936103 -157.074577) (xy 86.09411 -156.967784) (xy 86.247443 -156.854382) (xy 86.395824 -156.734574)
			(xy 86.538987 -156.608577) (xy 86.676673 -156.476617) (xy 86.808635 -156.338932) (xy 86.934634 -156.195771)
			(xy 87.054444 -156.047392) (xy 87.167848 -155.894061) (xy 87.274643 -155.736055) (xy 87.374636 -155.573659)
			(xy 87.467646 -155.407166) (xy 87.553506 -155.236875) (xy 87.632061 -155.063094) (xy 87.70317 -154.886135)
			(xy 87.766705 -154.706317) (xy 87.822551 -154.523966) (xy 87.870607 -154.339408) (xy 87.910787 -154.152977)
			(xy 87.943018 -153.965009) (xy 87.967243 -153.775842) (xy 87.983417 -153.585818) (xy 87.991512 -153.395278)
			(xy 87.99195 -153.299922) (xy 87.99195 -110.499906) (xy 87.992448 -110.374117) (xy 88.000358 -110.122665)
			(xy 88.016162 -109.871584) (xy 88.039844 -109.621124) (xy 88.071382 -109.371531) (xy 88.110744 -109.123053)
			(xy 88.15789 -108.875933) (xy 88.212776 -108.630415) (xy 88.275346 -108.386743) (xy 88.345539 -108.145157)
			(xy 88.423285 -107.905894) (xy 88.508508 -107.669191) (xy 88.601123 -107.435282) (xy 88.70104 -107.204397)
			(xy 88.80816 -106.976765) (xy 88.922376 -106.75261) (xy 89.043577 -106.532152) (xy 89.171643 -106.31561)
			(xy 89.306446 -106.103198) (xy 89.447855 -105.895124) (xy 89.59573 -105.691595) (xy 89.749925 -105.492811)
			(xy 89.910287 -105.298968) (xy 90.076658 -105.110257) (xy 90.248875 -104.926866) (xy 90.426767 -104.748974)
			(xy 90.610159 -104.576757) (xy 90.798869 -104.410386) (xy 90.992712 -104.250023) (xy 91.191497 -104.095829)
			(xy 91.395026 -103.947954) (xy 91.6031 -103.806545) (xy 91.815512 -103.671742) (xy 92.032054 -103.543676)
			(xy 92.252511 -103.422476) (xy 92.476667 -103.308259) (xy 92.704299 -103.20114) (xy 92.935184 -103.101223)
			(xy 93.169093 -103.008607) (xy 93.405796 -102.923384) (xy 93.645058 -102.845638) (xy 93.886645 -102.775445)
			(xy 94.130317 -102.712875) (xy 94.375834 -102.65799) (xy 94.622954 -102.610843) (xy 94.871433 -102.571482)
			(xy 95.121026 -102.539944) (xy 95.371486 -102.516262) (xy 95.622567 -102.500458) (xy 95.874019 -102.492548)
			(xy 95.999808 -102.492048) (xy 344.000074 -102.492048) (xy 344.125864 -102.492537) (xy 344.37732 -102.500438)
			(xy 344.628404 -102.516234) (xy 344.878867 -102.539909) (xy 345.128464 -102.57144) (xy 345.376946 -102.610795)
			(xy 345.62407 -102.657936) (xy 345.869592 -102.712815) (xy 346.113268 -102.77538) (xy 346.354859 -102.845568)
			(xy 346.594126 -102.92331) (xy 346.830833 -103.008529) (xy 347.064747 -103.101142) (xy 347.295636 -103.201056)
			(xy 347.523272 -103.308173) (xy 347.747432 -103.422387) (xy 347.967894 -103.543586) (xy 348.184439 -103.671651)
			(xy 348.396856 -103.806454) (xy 348.604933 -103.947862) (xy 348.808466 -104.095737) (xy 349.007253 -104.249932)
			(xy 349.201099 -104.410295) (xy 349.389812 -104.576667) (xy 349.573207 -104.748885) (xy 349.751101 -104.926779)
			(xy 349.923319 -105.110173) (xy 350.089692 -105.298886) (xy 350.250056 -105.492731) (xy 350.404251 -105.691518)
			(xy 350.552126 -105.895051) (xy 350.693536 -106.103128) (xy 350.828339 -106.315544) (xy 350.956404 -106.532089)
			(xy 351.077604 -106.75255) (xy 351.191819 -106.97671) (xy 351.298936 -107.204346) (xy 351.398851 -107.435235)
			(xy 351.491464 -107.669148) (xy 351.576683 -107.905855) (xy 351.654426 -108.145122) (xy 351.724615 -108.386713)
			(xy 351.78718 -108.630389) (xy 351.84206 -108.87591) (xy 351.889202 -109.123034) (xy 351.928557 -109.371517)
			(xy 351.960089 -109.621113) (xy 351.983764 -109.871576) (xy 351.999561 -110.12266) (xy 352.007463 -110.374116)
			(xy 352.007932 -110.499906) (xy 352.007932 -153.299922) (xy 352.008439 -153.395276) (xy 352.016533 -153.585814)
			(xy 352.032708 -153.775835) (xy 352.056932 -153.965) (xy 352.089163 -154.152965) (xy 352.129342 -154.339394)
			(xy 352.177398 -154.523949) (xy 352.233242 -154.706298) (xy 352.296776 -154.886113) (xy 352.367884 -155.063069)
			(xy 352.446438 -155.236848) (xy 352.532297 -155.407137) (xy 352.625305 -155.573628) (xy 352.725296 -155.736022)
			(xy 352.832089 -155.894025) (xy 352.945492 -156.047354) (xy 353.0653 -156.195732) (xy 353.191297 -156.338892)
			(xy 353.323257 -156.476574) (xy 353.460941 -156.608533) (xy 353.604101 -156.734529) (xy 353.75248 -156.854335)
			(xy 353.90581 -156.967736) (xy 354.063815 -157.074528) (xy 354.22621 -157.174517) (xy 354.392702 -157.267524)
			(xy 354.562991 -157.353381) (xy 354.736771 -157.431933) (xy 354.913728 -157.50304) (xy 355.093544 -157.566571)
			(xy 355.275894 -157.622414) (xy 355.460449 -157.670468) (xy 355.646878 -157.710646) (xy 355.834844 -157.742875)
			(xy 356.024008 -157.767097) (xy 356.21403 -157.783269) (xy 356.404568 -157.791362) (xy 356.499922 -157.791912)
			(xy 357.000048 -157.791912) (xy 357.083541 -157.79241) (xy 357.250338 -157.800358) (xy 357.416569 -157.816233)
			(xy 357.581855 -157.839999) (xy 357.745823 -157.871604) (xy 357.908102 -157.910974) (xy 358.068324 -157.958022)
			(xy 358.226126 -158.012639) (xy 358.38115 -158.074704) (xy 358.533046 -158.144074) (xy 358.681468 -158.220593)
			(xy 358.826082 -158.304088) (xy 358.966559 -158.394369) (xy 359.102581 -158.491232) (xy 359.233841 -158.594457)
			(xy 359.36004 -158.703811) (xy 359.480893 -158.819046) (xy 359.596126 -158.9399) (xy 359.705478 -159.066101)
			(xy 359.808701 -159.197362) (xy 359.905562 -159.333386) (xy 359.99584 -159.473864) (xy 360.079333 -159.618479)
			(xy 360.15585 -159.766903) (xy 360.225218 -159.9188) (xy 360.287279 -160.073825) (xy 360.341895 -160.231627)
			(xy 360.38894 -160.39185) (xy 360.428308 -160.554129) (xy 360.459909 -160.718098) (xy 360.483674 -160.883385)
			(xy 360.499546 -161.049615) (xy 360.507492 -161.216413) (xy 360.508042 -161.299906) (xy 360.508042 -166.649908)
			(xy 360.508541 -166.745263) (xy 360.516636 -166.9358) (xy 360.532809 -167.125823) (xy 360.557033 -167.314988)
			(xy 360.589264 -167.502954) (xy 360.629443 -167.689383) (xy 360.677498 -167.873938) (xy 360.733342 -168.056288)
			(xy 360.796876 -168.236104) (xy 360.867984 -168.413061) (xy 360.946538 -168.586841) (xy 361.032396 -168.75713)
			(xy 361.125405 -168.923621) (xy 361.225396 -169.086016) (xy 361.332189 -169.24402) (xy 361.445592 -169.397349)
			(xy 361.5654 -169.545728) (xy 361.691398 -169.688888) (xy 361.823357 -169.826571) (xy 361.961042 -169.95853)
			(xy 362.104203 -170.084526) (xy 362.252582 -170.204333) (xy 362.405913 -170.317734) (xy 362.563918 -170.424526)
			(xy 362.726313 -170.524515) (xy 362.892806 -170.617522) (xy 363.063096 -170.70338) (xy 363.236876 -170.781932)
			(xy 363.413834 -170.853038) (xy 363.59365 -170.91657) (xy 363.776 -170.972413) (xy 363.960556 -171.020467)
			(xy 364.146985 -171.060644) (xy 364.334952 -171.092873) (xy 364.524117 -171.117095) (xy 364.71414 -171.133267)
			(xy 364.904677 -171.14136) (xy 365.000032 -171.141898) (xy 403.999954 -171.141898) (xy 404.09531 -171.1414)
			(xy 404.28585 -171.133308) (xy 404.475874 -171.117136) (xy 404.665041 -171.092914) (xy 404.85301 -171.060686)
			(xy 405.039441 -171.020508) (xy 405.224 -170.972455) (xy 405.406352 -170.916612) (xy 405.58617 -170.85308)
			(xy 405.76313 -170.781973) (xy 405.936913 -170.70342) (xy 406.107205 -170.617562) (xy 406.273699 -170.524554)
			(xy 406.436096 -170.424564) (xy 406.594104 -170.317772) (xy 406.747436 -170.204369) (xy 406.895817 -170.084561)
			(xy 407.03898 -169.958564) (xy 407.176666 -169.826604) (xy 407.308627 -169.688919) (xy 407.434627 -169.545758)
			(xy 407.554436 -169.397379) (xy 407.66784 -169.244048) (xy 407.774635 -169.086042) (xy 407.874627 -168.923646)
			(xy 407.967637 -168.757152) (xy 408.053497 -168.586861) (xy 408.132052 -168.41308) (xy 408.20316 -168.236121)
			(xy 408.266695 -168.056304) (xy 408.32254 -167.873952) (xy 408.370596 -167.689394) (xy 408.410775 -167.502963)
			(xy 408.443006 -167.314995) (xy 408.46723 -167.125828) (xy 408.483404 -166.935803) (xy 408.491499 -166.745264)
			(xy 408.491944 -166.649908) (xy 408.491944 -163.299902) (xy 408.492443 -163.194388) (xy 408.500526 -162.983513)
			(xy 408.51668 -162.773104) (xy 408.540882 -162.563467) (xy 408.573095 -162.354911) (xy 408.613273 -162.147742)
			(xy 408.661357 -161.942264) (xy 408.717276 -161.738779) (xy 408.780948 -161.537585) (xy 408.85228 -161.338977)
			(xy 408.931166 -161.143247) (xy 409.017492 -160.950683) (xy 409.11113 -160.761566) (xy 409.211943 -160.576175)
			(xy 409.319783 -160.394781) (xy 409.434492 -160.217651) (xy 409.555901 -160.045044) (xy 409.683832 -159.877215)
			(xy 409.818098 -159.714408) (xy 409.958502 -159.556864) (xy 410.104837 -159.404814) (xy 410.256888 -159.25848)
			(xy 410.414433 -159.118078) (xy 410.57724 -158.983813) (xy 410.74507 -158.855882) (xy 410.917677 -158.734474)
			(xy 411.094808 -158.619766) (xy 411.276203 -158.511927) (xy 411.461595 -158.411115) (xy 411.650712 -158.317478)
			(xy 411.843277 -158.231154) (xy 412.039007 -158.152268) (xy 412.237615 -158.080938) (xy 412.43881 -158.017267)
			(xy 412.642296 -157.961349) (xy 412.847774 -157.913267) (xy 413.054943 -157.87309) (xy 413.263499 -157.840877)
			(xy 413.473136 -157.816677) (xy 413.683545 -157.800524) (xy 413.89442 -157.792443) (xy 413.999934 -157.791912)
			(xy 434.999892 -157.791912) (xy 435.095247 -157.791406) (xy 435.285786 -157.783312) (xy 435.475809 -157.767139)
			(xy 435.664975 -157.742916) (xy 435.852942 -157.710686) (xy 436.039373 -157.670508) (xy 436.223929 -157.622454)
			(xy 436.406281 -157.56661) (xy 436.586097 -157.503077) (xy 436.763056 -157.43197) (xy 436.936837 -157.353416)
			(xy 437.107127 -157.267558) (xy 437.27362 -157.17455) (xy 437.436016 -157.07456) (xy 437.594022 -156.967767)
			(xy 437.747353 -156.854365) (xy 437.895733 -156.734557) (xy 438.038894 -156.60856) (xy 438.176579 -156.476601)
			(xy 438.30854 -156.338916) (xy 438.434538 -156.195756) (xy 438.554346 -156.047377) (xy 438.66775 -155.894046)
			(xy 438.774543 -155.736041) (xy 438.874535 -155.573646) (xy 438.967544 -155.407154) (xy 439.053403 -155.236864)
			(xy 439.131958 -155.063083) (xy 439.203066 -154.886125) (xy 439.2666 -154.706309) (xy 439.322445 -154.523958)
			(xy 439.370501 -154.339402) (xy 439.410681 -154.152972) (xy 439.442912 -153.965005) (xy 439.467136 -153.775839)
			(xy 439.483311 -153.585816) (xy 439.491405 -153.395277) (xy 439.491882 -153.299922) (xy 439.491882 -136.77011)
			(xy 439.492393 -136.664597) (xy 439.500486 -136.453727) (xy 439.51665 -136.243322) (xy 439.540861 -136.03369)
			(xy 439.573083 -135.82514) (xy 439.613269 -135.617976) (xy 439.661359 -135.412504) (xy 439.717285 -135.209024)
			(xy 439.780962 -135.007835) (xy 439.852299 -134.809233) (xy 439.931189 -134.613509) (xy 440.017518 -134.42095)
			(xy 440.111159 -134.231839) (xy 440.211974 -134.046453) (xy 440.319816 -133.865064) (xy 440.434526 -133.687939)
			(xy 440.555935 -133.515337) (xy 440.683866 -133.347512) (xy 440.818131 -133.18471) (xy 440.958533 -133.02717)
			(xy 441.104866 -132.875122) (xy 441.256915 -132.728791) (xy 441.414457 -132.588391) (xy 441.577261 -132.454128)
			(xy 441.745087 -132.326199) (xy 441.91769 -132.204791) (xy 442.094817 -132.090083) (xy 442.276207 -131.982244)
			(xy 442.461594 -131.881431) (xy 442.650706 -131.787792) (xy 442.843266 -131.701465) (xy 443.038991 -131.622577)
			(xy 443.237594 -131.551242) (xy 443.438783 -131.487567) (xy 443.642264 -131.431644) (xy 443.847737 -131.383556)
			(xy 444.054901 -131.343372) (xy 444.263452 -131.311152) (xy 444.473084 -131.286944) (xy 444.683489 -131.270783)
			(xy 444.894359 -131.262691) (xy 444.999872 -131.26212) (xy 471.000074 -131.26212) (xy 471.09543 -131.261614)
			(xy 471.285969 -131.253522) (xy 471.475993 -131.237349) (xy 471.665159 -131.213127) (xy 471.853128 -131.180897)
			(xy 472.039558 -131.14072) (xy 472.224116 -131.092666) (xy 472.406468 -131.036822) (xy 472.586285 -130.97329)
			(xy 472.763245 -130.902183) (xy 472.937026 -130.82363) (xy 473.107318 -130.737772) (xy 473.273812 -130.644764)
			(xy 473.436208 -130.544774) (xy 473.594215 -130.437982) (xy 473.747547 -130.32458) (xy 473.895928 -130.204772)
			(xy 474.03909 -130.078775) (xy 474.176776 -129.946815) (xy 474.308737 -129.809131) (xy 474.434736 -129.66597)
			(xy 474.554545 -129.517591) (xy 474.667949 -129.364261) (xy 474.774744 -129.206255) (xy 474.874736 -129.04386)
			(xy 474.967746 -128.877367) (xy 475.053606 -128.707077) (xy 475.132161 -128.533296) (xy 475.20327 -128.356338)
			(xy 475.266805 -128.176521) (xy 475.32265 -127.99417) (xy 475.370707 -127.809613) (xy 475.410887 -127.623182)
			(xy 475.443118 -127.435215) (xy 475.467343 -127.246049) (xy 475.483518 -127.056025) (xy 475.491613 -126.865486)
			(xy 475.492064 -126.77013) (xy 475.492064 -21.770086) (xy 475.491565 -21.674731) (xy 475.48347 -21.484194)
			(xy 475.467296 -21.294171) (xy 475.443072 -21.105007) (xy 475.410841 -20.917041) (xy 475.370662 -20.730612)
			(xy 475.322607 -20.546056) (xy 475.266762 -20.363706) (xy 475.203229 -20.183891) (xy 475.132121 -20.006934)
			(xy 475.053567 -19.833155) (xy 474.967708 -19.662865) (xy 474.874699 -19.496374) (xy 474.774708 -19.33398)
			(xy 474.667915 -19.175975) (xy 474.554512 -19.022646) (xy 474.434704 -18.874268) (xy 474.308707 -18.731108)
			(xy 474.176747 -18.593425) (xy 474.039062 -18.461466) (xy 473.895902 -18.33547) (xy 473.747522 -18.215663)
			(xy 473.594192 -18.102262) (xy 473.436187 -17.99547) (xy 473.273792 -17.895481) (xy 473.107299 -17.802473)
			(xy 472.937009 -17.716616) (xy 472.763229 -17.638064) (xy 472.586272 -17.566957) (xy 472.406456 -17.503425)
			(xy 472.224105 -17.447582) (xy 472.039549 -17.399529) (xy 471.85312 -17.359351) (xy 471.665154 -17.327122)
			(xy 471.475989 -17.3029) (xy 471.285966 -17.286727) (xy 471.095429 -17.278635) (xy 471.000074 -17.278096)
			(xy 444.999872 -17.278096) (xy 444.894359 -17.277587) (xy 444.683488 -17.269495) (xy 444.473081 -17.253334)
			(xy 444.263448 -17.229125) (xy 444.054895 -17.196905) (xy 443.84773 -17.156721) (xy 443.642256 -17.108631)
			(xy 443.438775 -17.052708) (xy 443.237584 -16.989031) (xy 443.038981 -16.917696) (xy 442.843255 -16.838806)
			(xy 442.650694 -16.752478) (xy 442.461581 -16.658838) (xy 442.276194 -16.558023) (xy 442.094803 -16.450182)
			(xy 441.917676 -16.335473) (xy 441.745073 -16.214064) (xy 441.577246 -16.086133) (xy 441.414443 -15.951868)
			(xy 441.256901 -15.811465) (xy 441.104852 -15.665132) (xy 440.95852 -15.513083) (xy 440.818118 -15.355541)
			(xy 440.683854 -15.192737) (xy 440.555923 -15.024909) (xy 440.434515 -14.852305) (xy 440.319806 -14.675178)
			(xy 440.211966 -14.493787) (xy 440.111152 -14.308399) (xy 440.017512 -14.119286) (xy 439.931185 -13.926725)
			(xy 439.852296 -13.730999) (xy 439.780962 -13.532395) (xy 439.717286 -13.331204) (xy 439.661363 -13.127723)
			(xy 439.613275 -12.922248) (xy 439.573091 -12.715083) (xy 439.540872 -12.506531) (xy 439.516664 -12.296897)
			(xy 439.500503 -12.086491) (xy 439.492413 -11.875619) (xy 439.491882 -11.770106) (xy 439.491882 -4.99999)
			(xy 439.491376 -4.904635) (xy 439.483281 -4.714098) (xy 439.467108 -4.524075) (xy 439.442884 -4.33491)
			(xy 439.410653 -4.146944) (xy 439.370474 -3.960515) (xy 439.322419 -3.775959) (xy 439.266575 -3.593609)
			(xy 439.203041 -3.413794) (xy 439.131934 -3.236837) (xy 439.05338 -3.063057) (xy 438.967522 -2.892768)
			(xy 438.874513 -2.726276) (xy 438.774522 -2.563881) (xy 438.66773 -2.405877) (xy 438.554327 -2.252547)
			(xy 438.434519 -2.104169) (xy 438.308522 -1.961009) (xy 438.176562 -1.823325) (xy 438.038878 -1.691366)
			(xy 437.895718 -1.565369) (xy 437.747339 -1.445562) (xy 437.594008 -1.33216) (xy 437.436004 -1.225368)
			(xy 437.273609 -1.125378) (xy 437.107116 -1.03237) (xy 436.936827 -0.946512) (xy 436.763047 -0.867959)
			(xy 436.586089 -0.796852) (xy 436.406274 -0.73332) (xy 436.223923 -0.677476) (xy 436.039367 -0.629422)
			(xy 435.852938 -0.589243) (xy 435.664972 -0.557014) (xy 435.475807 -0.53279) (xy 435.285784 -0.516618)
			(xy 435.095247 -0.508524) (xy 434.999892 -0.508) (xy 4.99999 -0.508) (xy 4.904635 -0.508506) (xy 4.714097 -0.5166)
			(xy 4.524074 -0.532773) (xy 4.334909 -0.556997) (xy 4.146942 -0.589227) (xy 3.960513 -0.629406) (xy 3.775956 -0.67746)
			(xy 3.593606 -0.733305) (xy 3.41379 -0.796838) (xy 3.236832 -0.867945) (xy 3.063052 -0.946499) (xy 2.892762 -1.032357)
			(xy 2.72627 -1.125365) (xy 2.563875 -1.225356) (xy 2.40587 -1.332149) (xy 2.25254 -1.445551) (xy 2.10416 -1.565359)
			(xy 1.961 -1.691356) (xy 1.823316 -1.823316) (xy 1.691356 -1.961) (xy 1.565359 -2.10416) (xy 1.445551 -2.25254)
			(xy 1.332149 -2.40587) (xy 1.225356 -2.563875) (xy 1.125365 -2.72627) (xy 1.032357 -2.892762) (xy 0.946499 -3.063052)
			(xy 0.867945 -3.236832) (xy 0.796838 -3.41379) (xy 0.733305 -3.593606) (xy 0.67746 -3.775956) (xy 0.629406 -3.960513)
			(xy 0.589227 -4.146942) (xy 0.556997 -4.334909) (xy 0.532773 -4.524074) (xy 0.5166 -4.714097) (xy 0.508506 -4.904635)
			(xy 0.508 -4.99999) (xy 0.508 -153.299922) (xy 1.015746 -153.299922) (xy 1.015746 -4.99999) (xy 1.016248 -4.91058)
			(xy 1.02427 -4.73194) (xy 1.0403 -4.55384) (xy 1.064303 -4.376638) (xy 1.096233 -4.200692) (xy 1.136024 -4.026356)
			(xy 1.183597 -3.85398) (xy 1.238855 -3.683912) (xy 1.301688 -3.516495) (xy 1.371969 -3.352065) (xy 1.449556 -3.190953)
			(xy 1.534293 -3.033485) (xy 1.62601 -2.879978) (xy 1.724521 -2.730739) (xy 1.829629 -2.586071) (xy 1.941121 -2.446264)
			(xy 2.058774 -2.3116) (xy 2.182349 -2.182349) (xy 2.3116 -2.058774) (xy 2.446264 -1.941121) (xy 2.586071 -1.829629)
			(xy 2.730739 -1.724521) (xy 2.879978 -1.62601) (xy 3.033485 -1.534293) (xy 3.190953 -1.449556) (xy 3.352065 -1.371969)
			(xy 3.516495 -1.301688) (xy 3.683912 -1.238855) (xy 3.85398 -1.183597) (xy 4.026356 -1.136024) (xy 4.200692 -1.096233)
			(xy 4.376638 -1.064303) (xy 4.55384 -1.0403) (xy 4.73194 -1.02427) (xy 4.91058 -1.016248) (xy 4.99999 -1.015746)
			(xy 434.999892 -1.015746) (xy 435.089302 -1.016266) (xy 435.267941 -1.024288) (xy 435.446041 -1.040317)
			(xy 435.623242 -1.06432) (xy 435.799188 -1.096249) (xy 435.973524 -1.13604) (xy 436.1459 -1.183612)
			(xy 436.315967 -1.23887) (xy 436.483385 -1.301702) (xy 436.647814 -1.371982) (xy 436.808925 -1.449569)
			(xy 436.966393 -1.534306) (xy 437.119901 -1.626022) (xy 437.269139 -1.724533) (xy 437.413807 -1.82964)
			(xy 437.553614 -1.941132) (xy 437.688278 -2.058784) (xy 437.817529 -2.182359) (xy 437.941104 -2.311608)
			(xy 438.058757 -2.446272) (xy 438.170249 -2.586078) (xy 438.275357 -2.730746) (xy 438.373869 -2.879984)
			(xy 438.465585 -3.033491) (xy 438.550323 -3.190959) (xy 438.62791 -3.352069) (xy 438.698191 -3.516499)
			(xy 438.761024 -3.683916) (xy 438.816283 -3.853983) (xy 438.863856 -4.026358) (xy 438.903647 -4.200694)
			(xy 438.935577 -4.37664) (xy 438.959581 -4.553841) (xy 438.975611 -4.731941) (xy 438.983634 -4.91058)
			(xy 438.984136 -4.99999) (xy 438.984136 -11.770106) (xy 438.984663 -11.879986) (xy 438.992696 -12.099598)
			(xy 439.008745 -12.318771) (xy 439.032786 -12.537211) (xy 439.06479 -12.754627) (xy 439.104711 -12.97073)
			(xy 439.152499 -13.185231) (xy 439.208088 -13.397843) (xy 439.271405 -13.608283) (xy 439.342365 -13.816271)
			(xy 439.420873 -14.021528) (xy 439.506825 -14.223781) (xy 439.600107 -14.422761) (xy 439.700592 -14.6182)
			(xy 439.808148 -14.80984) (xy 439.922632 -14.997424) (xy 440.043889 -15.180702) (xy 440.171759 -15.359429)
			(xy 440.306071 -15.533367) (xy 440.446645 -15.702284) (xy 440.593295 -15.865955) (xy 440.745824 -16.024161)
			(xy 440.904029 -16.17669) (xy 441.067699 -16.32334) (xy 441.236615 -16.463916) (xy 441.410553 -16.598228)
			(xy 441.58928 -16.726099) (xy 441.772557 -16.847357) (xy 441.960141 -16.961841) (xy 442.15178 -17.069397)
			(xy 442.34722 -17.169884) (xy 442.546199 -17.263166) (xy 442.748452 -17.349118) (xy 442.953709 -17.427628)
			(xy 443.161696 -17.498588) (xy 443.372136 -17.561906) (xy 443.584748 -17.617496) (xy 443.799248 -17.665284)
			(xy 444.015351 -17.705207) (xy 444.232767 -17.737211) (xy 444.451208 -17.761253) (xy 444.67038 -17.777302)
			(xy 444.889992 -17.785336) (xy 444.999872 -17.785842) (xy 471.000074 -17.785842) (xy 471.089484 -17.786376)
			(xy 471.268123 -17.794397) (xy 471.446223 -17.810425) (xy 471.623424 -17.834428) (xy 471.79937 -17.866356)
			(xy 471.973706 -17.906146) (xy 472.146082 -17.953718) (xy 472.31615 -18.008975) (xy 472.483567 -18.071807)
			(xy 472.647997 -18.142086) (xy 472.809108 -18.219672) (xy 472.966576 -18.304408) (xy 473.120084 -18.396124)
			(xy 473.269323 -18.494634) (xy 473.413991 -18.599741) (xy 473.553798 -18.711232) (xy 473.688463 -18.828884)
			(xy 473.817713 -18.952458) (xy 473.941289 -19.081708) (xy 474.058942 -19.216371) (xy 474.170435 -19.356177)
			(xy 474.275543 -19.500844) (xy 474.374055 -19.650082) (xy 474.465772 -19.803589) (xy 474.55051 -19.961056)
			(xy 474.628097 -20.122167) (xy 474.698379 -20.286596) (xy 474.761212 -20.454012) (xy 474.816471 -20.62408)
			(xy 474.864044 -20.796455) (xy 474.903836 -20.970791) (xy 474.935766 -21.146736) (xy 474.95977 -21.323937)
			(xy 474.9758 -21.502037) (xy 474.983823 -21.680676) (xy 474.984318 -21.770086) (xy 474.984318 -126.77013)
			(xy 474.983872 -126.859541) (xy 474.975847 -127.038182) (xy 474.959817 -127.216283) (xy 474.935812 -127.393485)
			(xy 474.903881 -127.569433) (xy 474.864088 -127.74377) (xy 474.816514 -127.916147) (xy 474.761254 -128.086215)
			(xy 474.698419 -128.253634) (xy 474.628137 -128.418064) (xy 474.550548 -128.579176) (xy 474.465809 -128.736644)
			(xy 474.374091 -128.890153) (xy 474.275578 -129.039391) (xy 474.170468 -129.18406) (xy 474.058974 -129.323867)
			(xy 473.94132 -129.458531) (xy 473.817742 -129.587782) (xy 473.68849 -129.711357) (xy 473.553824 -129.82901)
			(xy 473.414015 -129.940502) (xy 473.269345 -130.045609) (xy 473.120105 -130.14412) (xy 472.966596 -130.235837)
			(xy 472.809126 -130.320573) (xy 472.648013 -130.39816) (xy 472.483582 -130.46844) (xy 472.316163 -130.531272)
			(xy 472.146093 -130.58653) (xy 471.973716 -130.634102) (xy 471.799378 -130.673892) (xy 471.62343 -130.70582)
			(xy 471.446227 -130.729823) (xy 471.268126 -130.745851) (xy 471.089485 -130.753873) (xy 471.000074 -130.754374)
			(xy 444.999872 -130.754374) (xy 444.889993 -130.754942) (xy 444.670382 -130.762976) (xy 444.45121 -130.779024)
			(xy 444.232771 -130.803066) (xy 444.015356 -130.83507) (xy 443.799255 -130.874992) (xy 443.584755 -130.92278)
			(xy 443.372144 -130.978369) (xy 443.161705 -131.041686) (xy 442.953719 -131.112645) (xy 442.748462 -131.191154)
			(xy 442.54621 -131.277105) (xy 442.347232 -131.370386) (xy 442.151793 -131.470871) (xy 441.960154 -131.578426)
			(xy 441.772571 -131.692909) (xy 441.589294 -131.814165) (xy 441.410567 -131.942034) (xy 441.23663 -132.076345)
			(xy 441.067713 -132.216918) (xy 440.904043 -132.363566) (xy 440.745838 -132.516094) (xy 440.593309 -132.674298)
			(xy 440.446659 -132.837966) (xy 440.306083 -133.006881) (xy 440.171771 -133.180818) (xy 440.0439 -133.359543)
			(xy 439.922642 -133.542819) (xy 439.808158 -133.730401) (xy 439.7006 -133.922038) (xy 439.600113 -134.117476)
			(xy 439.50683 -134.316454) (xy 439.420877 -134.518705) (xy 439.342367 -134.72396) (xy 439.271405 -134.931946)
			(xy 439.208086 -135.142384) (xy 439.152494 -135.354995) (xy 439.104705 -135.569494) (xy 439.06478 -135.785595)
			(xy 439.032774 -136.00301) (xy 439.00873 -136.221449) (xy 438.992679 -136.44062) (xy 438.984643 -136.660231)
			(xy 438.984136 -136.77011) (xy 438.984136 -153.299922) (xy 438.983664 -153.389332) (xy 438.97564 -153.567973)
			(xy 438.95961 -153.746073) (xy 438.935605 -153.923275) (xy 438.903675 -154.099222) (xy 438.863882 -154.273559)
			(xy 438.816309 -154.445935) (xy 438.761049 -154.616003) (xy 438.698216 -154.783421) (xy 438.627934 -154.947851)
			(xy 438.550346 -155.108962) (xy 438.465608 -155.266431) (xy 438.37389 -155.419939) (xy 438.275378 -155.569177)
			(xy 438.170269 -155.713845) (xy 438.058776 -155.853652) (xy 437.941122 -155.988317) (xy 437.817546 -156.117567)
			(xy 437.688294 -156.241142) (xy 437.553629 -156.358795) (xy 437.413821 -156.470287) (xy 437.269152 -156.575395)
			(xy 437.119913 -156.673906) (xy 436.966405 -156.765622) (xy 436.808936 -156.850359) (xy 436.647824 -156.927946)
			(xy 436.483393 -156.998227) (xy 436.315975 -157.061059) (xy 436.145906 -157.116317) (xy 435.97353 -157.16389)
			(xy 435.799193 -157.203681) (xy 435.623246 -157.23561) (xy 435.446043 -157.259613) (xy 435.267943 -157.275642)
			(xy 435.089302 -157.283664) (xy 434.999892 -157.284166) (xy 413.999934 -157.284166) (xy 413.890053 -157.284693)
			(xy 413.670438 -157.292718) (xy 413.451263 -157.308759) (xy 413.232819 -157.332793) (xy 413.015399 -157.36479)
			(xy 412.799293 -157.404705) (xy 412.584789 -157.452487) (xy 412.372173 -157.508071) (xy 412.161729 -157.571383)
			(xy 411.953737 -157.642339) (xy 411.748476 -157.720844) (xy 411.546219 -157.806793) (xy 411.347236 -157.900071)
			(xy 411.151792 -158.000555) (xy 410.960149 -158.10811) (xy 410.772561 -158.222592) (xy 410.58928 -158.343848)
			(xy 410.41055 -158.471718) (xy 410.236609 -158.60603) (xy 410.067689 -158.746605) (xy 409.904016 -158.893256)
			(xy 409.745809 -159.045786) (xy 409.593277 -159.203993) (xy 409.446626 -159.367665) (xy 409.30605 -159.536584)
			(xy 409.171737 -159.710524) (xy 409.043866 -159.889254) (xy 408.922609 -160.072534) (xy 408.808126 -160.260121)
			(xy 408.70057 -160.451764) (xy 408.600086 -160.647207) (xy 408.506806 -160.84619) (xy 408.420856 -161.048446)
			(xy 408.34235 -161.253707) (xy 408.271393 -161.461698) (xy 408.20808 -161.672142) (xy 408.152495 -161.884758)
			(xy 408.104712 -162.099262) (xy 408.064795 -162.315368) (xy 408.032797 -162.532788) (xy 408.008762 -162.751231)
			(xy 407.99272 -162.970406) (xy 407.984694 -163.190021) (xy 407.984198 -163.299902) (xy 407.984198 -166.649908)
			(xy 407.983758 -166.739319) (xy 407.975734 -166.917961) (xy 407.959704 -167.096062) (xy 407.9357 -167.273266)
			(xy 407.90377 -167.449214) (xy 407.863978 -167.623552) (xy 407.816404 -167.795929) (xy 407.761144 -167.965998)
			(xy 407.69831 -168.133417) (xy 407.628028 -168.297848) (xy 407.550439 -168.458961) (xy 407.4657 -168.61643)
			(xy 407.373982 -168.769939) (xy 407.275469 -168.919178) (xy 407.170359 -169.063847) (xy 407.058865 -169.203655)
			(xy 406.94121 -169.33832) (xy 406.817632 -169.467571) (xy 406.68838 -169.591147) (xy 406.553714 -169.7088)
			(xy 406.413904 -169.820292) (xy 406.269234 -169.9254) (xy 406.119993 -170.023911) (xy 405.966483 -170.115627)
			(xy 405.809013 -170.200364) (xy 405.647899 -170.27795) (xy 405.483467 -170.34823) (xy 405.316047 -170.411062)
			(xy 405.145977 -170.466319) (xy 404.973599 -170.513891) (xy 404.799261 -170.553681) (xy 404.623312 -170.585609)
			(xy 404.446109 -170.609611) (xy 404.268007 -170.625638) (xy 404.089365 -170.633659) (xy 403.999954 -170.634152)
			(xy 365.000032 -170.634152) (xy 364.910622 -170.633618) (xy 364.731983 -170.625597) (xy 364.553883 -170.609569)
			(xy 364.376682 -170.585567) (xy 364.200735 -170.553639) (xy 364.026399 -170.513849) (xy 363.854023 -170.466278)
			(xy 363.683955 -170.411021) (xy 363.516538 -170.348189) (xy 363.352108 -170.27791) (xy 363.190997 -170.200324)
			(xy 363.033528 -170.115588) (xy 362.88002 -170.023872) (xy 362.730782 -169.925362) (xy 362.586113 -169.820255)
			(xy 362.446306 -169.708764) (xy 362.311641 -169.591112) (xy 362.182391 -169.467537) (xy 362.058815 -169.338288)
			(xy 361.941162 -169.203625) (xy 361.829669 -169.063819) (xy 361.724561 -168.919151) (xy 361.626049 -168.769913)
			(xy 361.534332 -168.616406) (xy 361.449594 -168.458939) (xy 361.372007 -168.297828) (xy 361.301726 -168.133399)
			(xy 361.238893 -167.965982) (xy 361.183634 -167.795915) (xy 361.136061 -167.62354) (xy 361.096269 -167.449204)
			(xy 361.064339 -167.273258) (xy 361.040335 -167.096057) (xy 361.024305 -166.917957) (xy 361.016282 -166.739318)
			(xy 361.015788 -166.649908) (xy 361.015788 -161.299906) (xy 361.015228 -161.20979) (xy 361.007143 -161.029739)
			(xy 360.990987 -160.850233) (xy 360.966795 -160.671632) (xy 360.934613 -160.494296) (xy 360.894508 -160.318583)
			(xy 360.846561 -160.144845) (xy 360.790866 -159.973434) (xy 360.727538 -159.804695) (xy 360.656703 -159.638966)
			(xy 360.578504 -159.476582) (xy 360.493098 -159.31787) (xy 360.400658 -159.16315) (xy 360.30137 -159.012732)
			(xy 360.195433 -158.866921) (xy 360.083061 -158.726009) (xy 359.96448 -158.590281) (xy 359.839929 -158.460009)
			(xy 359.709659 -158.335456) (xy 359.573933 -158.216874) (xy 359.433022 -158.1045) (xy 359.287212 -157.998561)
			(xy 359.136796 -157.89927) (xy 358.982077 -157.806828) (xy 358.823366 -157.72142) (xy 358.660983 -157.643219)
			(xy 358.495256 -157.572382) (xy 358.326517 -157.509051) (xy 358.155106 -157.453355) (xy 357.98137 -157.405405)
			(xy 357.805657 -157.365298) (xy 357.628322 -157.333114) (xy 357.449721 -157.308919) (xy 357.270215 -157.292761)
			(xy 357.090164 -157.284673) (xy 357.000048 -157.284166) (xy 356.499922 -157.284166) (xy 356.410513 -157.283621)
			(xy 356.231874 -157.275599) (xy 356.053774 -157.259571) (xy 355.876574 -157.235568) (xy 355.700628 -157.20364)
			(xy 355.526292 -157.16385) (xy 355.353917 -157.116279) (xy 355.18385 -157.061021) (xy 355.016433 -156.99819)
			(xy 354.852004 -156.92791) (xy 354.690893 -156.850325) (xy 354.533425 -156.765589) (xy 354.379918 -156.673874)
			(xy 354.23068 -156.575364) (xy 354.086012 -156.470257) (xy 353.946205 -156.358766) (xy 353.811541 -156.241115)
			(xy 353.682291 -156.117541) (xy 353.558715 -155.988292) (xy 353.441062 -155.853629) (xy 353.329569 -155.713823)
			(xy 353.224462 -155.569156) (xy 353.12595 -155.419919) (xy 353.034233 -155.266413) (xy 352.949495 -155.108946)
			(xy 352.871908 -154.947836) (xy 352.801627 -154.783408) (xy 352.738793 -154.615992) (xy 352.683534 -154.445925)
			(xy 352.635961 -154.27355) (xy 352.596169 -154.099215) (xy 352.564239 -153.92327) (xy 352.540234 -153.746069)
			(xy 352.524204 -153.56797) (xy 352.51618 -153.389331) (xy 352.515678 -153.299922) (xy 352.515678 -110.499906)
			(xy 352.515198 -110.368763) (xy 352.507121 -110.106602) (xy 352.490975 -109.844813) (xy 352.466774 -109.583647)
			(xy 352.434543 -109.323349) (xy 352.39431 -109.064167) (xy 352.346115 -108.806347) (xy 352.290004 -108.550134)
			(xy 352.226029 -108.29577) (xy 352.154251 -108.043497) (xy 352.074738 -107.793553) (xy 351.987566 -107.546177)
			(xy 351.892818 -107.301603) (xy 351.790582 -107.060063) (xy 351.680957 -106.821785) (xy 351.564046 -106.586997)
			(xy 351.439961 -106.35592) (xy 351.308818 -106.128774) (xy 351.170742 -105.905774) (xy 351.025864 -105.687132)
			(xy 350.874322 -105.473055) (xy 350.716259 -105.263747) (xy 350.551826 -105.059405) (xy 350.381178 -104.860224)
			(xy 350.204477 -104.666393) (xy 350.021891 -104.478095) (xy 349.833592 -104.295509) (xy 349.639761 -104.118809)
			(xy 349.440579 -103.948161) (xy 349.236237 -103.783728) (xy 349.026928 -103.625666) (xy 348.812851 -103.474125)
			(xy 348.594209 -103.329248) (xy 348.371209 -103.191172) (xy 348.144063 -103.06003) (xy 347.912985 -102.935944)
			(xy 347.678197 -102.819034) (xy 347.439919 -102.70941) (xy 347.198378 -102.607175) (xy 346.953804 -102.512427)
			(xy 346.706428 -102.425255) (xy 346.456484 -102.345743) (xy 346.204211 -102.273966) (xy 345.949847 -102.209992)
			(xy 345.693633 -102.153881) (xy 345.435813 -102.105686) (xy 345.176631 -102.065455) (xy 344.916334 -102.033223)
			(xy 344.655167 -102.009024) (xy 344.393378 -101.992878) (xy 344.131217 -101.984801) (xy 344.000074 -101.984302)
			(xy 95.999808 -101.984302) (xy 95.868667 -101.984813) (xy 95.606508 -101.992897) (xy 95.344723 -102.009051)
			(xy 95.083559 -102.033258) (xy 94.823265 -102.065496) (xy 94.564087 -102.105734) (xy 94.306271 -102.153934)
			(xy 94.050062 -102.210051) (xy 93.795702 -102.27403) (xy 93.543432 -102.345812) (xy 93.293493 -102.425329)
			(xy 93.046121 -102.512504) (xy 92.801551 -102.607255) (xy 92.560015 -102.709493) (xy 92.321741 -102.81912)
			(xy 92.086957 -102.936032) (xy 91.855883 -103.060119) (xy 91.628741 -103.191263) (xy 91.405745 -103.329339)
			(xy 91.187106 -103.474217) (xy 90.973032 -103.625758) (xy 90.763727 -103.78382) (xy 90.559388 -103.948253)
			(xy 90.360209 -104.118899) (xy 90.16638 -104.295598) (xy 89.978084 -104.478183) (xy 89.7955 -104.666479)
			(xy 89.618801 -104.860308) (xy 89.448154 -105.059486) (xy 89.283722 -105.263825) (xy 89.12566 -105.473131)
			(xy 88.974118 -105.687204) (xy 88.82924 -105.905843) (xy 88.691164 -106.128839) (xy 88.56002 -106.355982)
			(xy 88.435933 -106.587055) (xy 88.319021 -106.82184) (xy 88.209394 -107.060113) (xy 88.107156 -107.301649)
			(xy 88.012404 -107.54622) (xy 87.925229 -107.793591) (xy 87.845713 -108.043531) (xy 87.773931 -108.2958)
			(xy 87.709951 -108.55016) (xy 87.653835 -108.806369) (xy 87.605634 -109.064185) (xy 87.565396 -109.323363)
			(xy 87.533158 -109.583657) (xy 87.508951 -109.844821) (xy 87.492797 -110.106606) (xy 87.484713 -110.368765)
			(xy 87.484204 -110.499906) (xy 87.484204 -153.299922) (xy 87.483771 -153.389333) (xy 87.475747 -153.567975)
			(xy 87.459717 -153.746076) (xy 87.435712 -153.92328) (xy 87.403781 -154.099228) (xy 87.363988 -154.273566)
			(xy 87.316414 -154.445943) (xy 87.261154 -154.616012) (xy 87.19832 -154.783431) (xy 87.128037 -154.947862)
			(xy 87.050448 -155.108974) (xy 86.965709 -155.266443) (xy 86.87399 -155.419952) (xy 86.775477 -155.569191)
			(xy 86.670367 -155.71386) (xy 86.558872 -155.853668) (xy 86.441218 -155.988333) (xy 86.31764 -156.117583)
			(xy 86.188387 -156.241159) (xy 86.053721 -156.358812) (xy 85.913911 -156.470305) (xy 85.76924 -156.575412)
			(xy 85.62 -156.673923) (xy 85.46649 -156.76564) (xy 85.309019 -156.850376) (xy 85.147906 -156.927963)
			(xy 84.983473 -156.998243) (xy 84.816054 -157.061075) (xy 84.645983 -157.116332) (xy 84.473605 -157.163904)
			(xy 84.299267 -157.203694) (xy 84.123318 -157.235622) (xy 83.946115 -157.259624) (xy 83.768013 -157.275652)
			(xy 83.589371 -157.283673) (xy 83.49996 -157.284166) (xy 83.000088 -157.284166) (xy 82.909971 -157.284654)
			(xy 82.729919 -157.292741) (xy 82.55041 -157.308897) (xy 82.371808 -157.333091) (xy 82.19447 -157.365274)
			(xy 82.018755 -157.40538) (xy 81.845017 -157.453329) (xy 81.673604 -157.509025) (xy 81.504863 -157.572355)
			(xy 81.339133 -157.643192) (xy 81.176748 -157.721393) (xy 81.018035 -157.806801) (xy 80.863314 -157.899243)
			(xy 80.712896 -157.998534) (xy 80.567084 -158.104473) (xy 80.426171 -158.216847) (xy 80.290443 -158.33543)
			(xy 80.160171 -158.459983) (xy 80.035618 -158.590256) (xy 79.917036 -158.725985) (xy 79.804662 -158.866898)
			(xy 79.698723 -159.01271) (xy 79.599433 -159.163129) (xy 79.506992 -159.317851) (xy 79.421585 -159.476564)
			(xy 79.343385 -159.638949) (xy 79.272548 -159.80468) (xy 79.209219 -159.973421) (xy 79.153524 -160.144834)
			(xy 79.105575 -160.318573) (xy 79.06547 -160.494288) (xy 79.033288 -160.671625) (xy 79.009095 -160.850228)
			(xy 78.992939 -161.029737) (xy 78.984854 -161.209789) (xy 78.984348 -161.299906) (xy 78.984348 -166.649908)
			(xy 78.98385 -166.739318) (xy 78.975827 -166.917958) (xy 78.959797 -167.096058) (xy 78.935794 -167.273259)
			(xy 78.903864 -167.449206) (xy 78.864072 -167.623542) (xy 78.816499 -167.795918) (xy 78.761241 -167.965986)
			(xy 78.698408 -168.133403) (xy 78.628127 -168.297833) (xy 78.550539 -168.458944) (xy 78.465802 -168.616412)
			(xy 78.374085 -168.76992) (xy 78.275574 -168.919158) (xy 78.170466 -169.063826) (xy 78.058973 -169.203633)
			(xy 77.941321 -169.338298) (xy 77.817745 -169.467548) (xy 77.688495 -169.591123) (xy 77.55383 -169.708776)
			(xy 77.414023 -169.820268) (xy 77.269355 -169.925376) (xy 77.120116 -170.023887) (xy 76.966609 -170.115604)
			(xy 76.809141 -170.200341) (xy 76.648029 -170.277928) (xy 76.483599 -170.348209) (xy 76.316182 -170.411042)
			(xy 76.146114 -170.4663) (xy 75.973738 -170.513873) (xy 75.799402 -170.553664) (xy 75.623456 -170.585594)
			(xy 75.446254 -170.609598) (xy 75.268154 -170.625627) (xy 75.089514 -170.63365) (xy 75.000104 -170.634152)
			(xy 35.999928 -170.634152) (xy 35.910518 -170.633622) (xy 35.731879 -170.625601) (xy 35.553779 -170.609573)
			(xy 35.376577 -170.58557) (xy 35.200631 -170.553642) (xy 35.026295 -170.513852) (xy 34.853919 -170.466281)
			(xy 34.683851 -170.411023) (xy 34.516434 -170.348192) (xy 34.352004 -170.277912) (xy 34.190892 -170.200326)
			(xy 34.033424 -170.11559) (xy 33.879916 -170.023874) (xy 33.730678 -169.925364) (xy 33.586009 -169.820257)
			(xy 33.446202 -169.708765) (xy 33.311537 -169.591114) (xy 33.182287 -169.467539) (xy 33.058711 -169.338289)
			(xy 32.941058 -169.203626) (xy 32.829565 -169.06382) (xy 32.724457 -168.919152) (xy 32.625945 -168.769914)
			(xy 32.534228 -168.616407) (xy 32.44949 -168.45894) (xy 32.371903 -168.297829) (xy 32.301622 -168.1334)
			(xy 32.238789 -167.965983) (xy 32.18353 -167.795915) (xy 32.135957 -167.62354) (xy 32.096165 -167.449204)
			(xy 32.064235 -167.273258) (xy 32.040231 -167.096057) (xy 32.024201 -166.917957) (xy 32.016178 -166.739318)
			(xy 32.015684 -166.649908) (xy 32.015684 -163.299902) (xy 32.015188 -163.190021) (xy 32.007162 -162.970406)
			(xy 31.99112 -162.75123) (xy 31.967085 -162.532786) (xy 31.935087 -162.315366) (xy 31.89517 -162.099259)
			(xy 31.847388 -161.884755) (xy 31.791802 -161.672139) (xy 31.728489 -161.461694) (xy 31.657532 -161.253703)
			(xy 31.579027 -161.048442) (xy 31.493077 -160.846184) (xy 31.399797 -160.647201) (xy 31.299313 -160.451757)
			(xy 31.191757 -160.260114) (xy 31.077274 -160.072527) (xy 30.956017 -159.889246) (xy 30.828146 -159.710515)
			(xy 30.693834 -159.536574) (xy 30.553258 -159.367655) (xy 30.406606 -159.203982) (xy 30.254075 -159.045775)
			(xy 30.095868 -158.893244) (xy 29.932195 -158.746592) (xy 29.763276 -158.606016) (xy 29.589335 -158.471704)
			(xy 29.410604 -158.343833) (xy 29.227323 -158.222576) (xy 29.039736 -158.108093) (xy 28.848093 -158.000537)
			(xy 28.652649 -157.900053) (xy 28.453666 -157.806773) (xy 28.251408 -157.720823) (xy 28.046147 -157.642318)
			(xy 27.838156 -157.571361) (xy 27.627711 -157.508048) (xy 27.415095 -157.452462) (xy 27.200591 -157.40468)
			(xy 26.984484 -157.364763) (xy 26.767064 -157.332765) (xy 26.54862 -157.30873) (xy 26.329444 -157.292688)
			(xy 26.109829 -157.284662) (xy 25.999948 -157.284166) (xy 4.99999 -157.284166) (xy 4.91058 -157.283664)
			(xy 4.73194 -157.275642) (xy 4.55384 -157.259612) (xy 4.376638 -157.235609) (xy 4.200692 -157.203679)
			(xy 4.026356 -157.163888) (xy 3.85398 -157.116315) (xy 3.683912 -157.061057) (xy 3.516495 -156.998224)
			(xy 3.352065 -156.927943) (xy 3.190953 -156.850356) (xy 3.033485 -156.765619) (xy 2.879978 -156.673902)
			(xy 2.730739 -156.575391) (xy 2.586071 -156.470283) (xy 2.446264 -156.358791) (xy 2.3116 -156.241138)
			(xy 2.182349 -156.117563) (xy 2.058774 -155.988312) (xy 1.941121 -155.853648) (xy 1.829629 -155.713841)
			(xy 1.724521 -155.569173) (xy 1.62601 -155.419934) (xy 1.534293 -155.266427) (xy 1.449556 -155.108959)
			(xy 1.371969 -154.947847) (xy 1.301688 -154.783417) (xy 1.238855 -154.616) (xy 1.183597 -154.445932)
			(xy 1.136024 -154.273556) (xy 1.096233 -154.09922) (xy 1.064303 -153.923274) (xy 1.0403 -153.746072)
			(xy 1.02427 -153.567972) (xy 1.016248 -153.389332) (xy 1.015746 -153.299922) (xy 0.508 -153.299922)
			(xy 0.508499 -153.395277) (xy 0.516593 -153.585815) (xy 0.532766 -153.775839) (xy 0.55699 -153.965004)
			(xy 0.58922 -154.152971) (xy 0.629399 -154.339401) (xy 0.677453 -154.523958) (xy 0.733298 -154.706308)
			(xy 0.796831 -154.886125) (xy 0.867938 -155.063083) (xy 0.946492 -155.236863) (xy 1.032351 -155.407153)
			(xy 1.125359 -155.573646) (xy 1.22535 -155.736041) (xy 1.332143 -155.894047) (xy 1.445545 -156.047377)
			(xy 1.565353 -156.195756) (xy 1.691351 -156.338917) (xy 1.82331 -156.476602) (xy 1.960995 -156.608561)
			(xy 2.104156 -156.734559) (xy 2.252535 -156.854367) (xy 2.405865 -156.967769) (xy 2.563871 -157.074562)
			(xy 2.726266 -157.174553) (xy 2.892759 -157.267561) (xy 3.063049 -157.35342) (xy 3.236829 -157.431974)
			(xy 3.413787 -157.503081) (xy 3.593604 -157.566614) (xy 3.775954 -157.622459) (xy 3.960511 -157.670513)
			(xy 4.146941 -157.710692) (xy 4.334908 -157.742922) (xy 4.524073 -157.767146) (xy 4.714097 -157.783319)
			(xy 4.904635 -157.791413) (xy 4.99999 -157.791912) (xy 25.999948 -157.791912) (xy 26.105463 -157.792411)
			(xy 26.316337 -157.800494) (xy 26.526747 -157.816648) (xy 26.736385 -157.84085) (xy 26.944941 -157.873063)
			(xy 27.15211 -157.913241) (xy 27.357588 -157.961325) (xy 27.561074 -158.017244) (xy 27.762269 -158.080916)
			(xy 27.960877 -158.152247) (xy 28.156608 -158.231133) (xy 28.349173 -158.317459) (xy 28.53829 -158.411097)
			(xy 28.723682 -158.51191) (xy 28.905076 -158.61975) (xy 29.082207 -158.734458) (xy 29.254814 -158.855867)
			(xy 29.422645 -158.983799) (xy 29.585451 -159.118065) (xy 29.742996 -159.258468) (xy 29.895047 -159.404803)
			(xy 30.041382 -159.556854) (xy 30.181785 -159.714399) (xy 30.316051 -159.877205) (xy 30.443983 -160.045036)
			(xy 30.565392 -160.217643) (xy 30.6801 -160.394774) (xy 30.78794 -160.576168) (xy 30.888753 -160.76156)
			(xy 30.982391 -160.950677) (xy 31.068717 -161.143242) (xy 31.147603 -161.338973) (xy 31.218934 -161.537581)
			(xy 31.282606 -161.738776) (xy 31.338525 -161.942262) (xy 31.386609 -162.14774) (xy 31.426787 -162.354909)
			(xy 31.459 -162.563465) (xy 31.483202 -162.773103) (xy 31.499356 -162.983513) (xy 31.507439 -163.194387)
			(xy 31.507938 -163.299902) (xy 31.507938 -166.649908) (xy 31.508444 -166.745263) (xy 31.516538 -166.935801)
			(xy 31.532711 -167.125824) (xy 31.556935 -167.314989) (xy 31.589165 -167.502956) (xy 31.629343 -167.689386)
			(xy 31.677398 -167.873942) (xy 31.733242 -168.056293) (xy 31.796775 -168.236109) (xy 31.867882 -168.413067)
			(xy 31.946436 -168.586847) (xy 32.032294 -168.757137) (xy 32.125303 -168.923629) (xy 32.225293 -169.086025)
			(xy 32.332086 -169.24403) (xy 32.445488 -169.39736) (xy 32.565296 -169.545739) (xy 32.691293 -169.6889)
			(xy 32.823253 -169.826584) (xy 32.960937 -169.958544) (xy 33.104098 -170.084541) (xy 33.252477 -170.204349)
			(xy 33.405807 -170.317752) (xy 33.563812 -170.424545) (xy 33.726207 -170.524535) (xy 33.8927 -170.617544)
			(xy 34.062989 -170.703402) (xy 34.23677 -170.781956) (xy 34.413727 -170.853064) (xy 34.593543 -170.916597)
			(xy 34.775894 -170.972441) (xy 34.96045 -171.020496) (xy 35.14688 -171.060675) (xy 35.334847 -171.092905)
			(xy 35.524012 -171.117128) (xy 35.714035 -171.133302) (xy 35.904573 -171.141396) (xy 35.999928 -171.141898)
		)
		(stroke
			(width 0)
			(type solid)
		)
		(fill yes)
		(layer "In7.Cu")
		(net "GND")
	)
	(gr_poly
		(pts
			(xy 400.819874 -169.53738) (xy 400.826986 -169.530014) (xy 401.178014 -169.178986) (xy 401.184868 -169.171591)
			(xy 401.19261 -169.152992) (xy 401.193 -169.142918) (xy 401.193 -149.373082) (xy 401.193427 -149.363013)
			(xy 401.201146 -149.344414) (xy 401.207986 -149.337014) (xy 402.194014 -148.350986) (xy 402.201409 -148.344132)
			(xy 402.220008 -148.33639) (xy 402.230082 -148.336) (xy 413.882078 -148.336) (xy 413.900874 -148.32838)
			(xy 413.907986 -148.321014) (xy 415.006028 -147.222972) (xy 415.012878 -147.215575) (xy 415.020613 -147.196977)
			(xy 415.021014 -147.186904) (xy 415.021014 -136.814814) (xy 415.021274 -136.807926) (xy 415.025 -136.794659)
			(xy 415.02838 -136.788652) (xy 415.028634 -136.788398) (xy 415.03219 -136.782302) (xy 415.033968 -136.775952)
			(xy 415.036 -136.761982) (xy 415.036 -54.112922) (xy 415.02838 -54.094126) (xy 415.021014 -54.087014)
			(xy 406.809448 -45.875448) (xy 406.802605 -45.868049) (xy 406.794882 -45.84945) (xy 406.794462 -45.83938)
			(xy 406.794462 -43.215306) (xy 406.794039 -43.205236) (xy 406.786322 -43.186634) (xy 406.779476 -43.179238)
			(xy 405.017986 -41.417748) (xy 405.011139 -41.410351) (xy 405.00341 -41.391752) (xy 405.003 -41.38168)
			(xy 405.003 -39.359078) (xy 405.002573 -39.34901) (xy 404.994853 -39.330411) (xy 404.988014 -39.32301)
			(xy 404.916894 -39.25189) (xy 404.909499 -39.245035) (xy 404.8909 -39.237288) (xy 404.880826 -39.236904)
			(xy 403.745192 -39.236904) (xy 403.735122 -39.236479) (xy 403.71652 -39.228763) (xy 403.709124 -39.221918)
			(xy 403.1107 -38.623494) (xy 403.103854 -38.616095) (xy 403.096122 -38.597497) (xy 403.095714 -38.587426)
			(xy 403.095714 -32.696912) (xy 403.095294 -32.68684) (xy 403.087584 -32.668231) (xy 403.080728 -32.660844)
			(xy 402.934932 -32.515048) (xy 402.927532 -32.508207) (xy 402.908933 -32.50049) (xy 402.898864 -32.500062)
			(xy 392.466576 -32.500062) (xy 392.456509 -32.500491) (xy 392.437917 -32.508219) (xy 392.430508 -32.515048)
			(xy 392.149838 -32.795718) (xy 392.14244 -32.802563) (xy 392.123841 -32.810288) (xy 392.11377 -32.810704)
			(xy 367.491772 -32.810704) (xy 367.481704 -32.810276) (xy 367.463107 -32.802555) (xy 367.455704 -32.795718)
			(xy 354.344986 -19.685) (xy 328.68235 -19.685) (xy 328.5744 -19.79295) (xy 328.5744 -24.383492) (xy 328.6252 -24.434292)
			(xy 338.657692 -24.434292) (xy 339.493606 -25.270206) (xy 339.493606 -29.974794) (xy 338.632292 -30.836108)
			(xy 328.69124 -30.836108) (xy 328.5744 -30.952948) (xy 328.5744 -35.661092) (xy 328.6252 -35.711892)
			(xy 338.632292 -35.711892) (xy 339.6234 -36.703) (xy 339.6234 -40.682348) (xy 343.306396 -40.682348)
			(xy 343.306396 -40.597652) (xy 343.314447 -40.513338) (xy 343.330476 -40.430172) (xy 343.354337 -40.348905)
			(xy 343.385816 -40.270275) (xy 343.424627 -40.194994) (xy 343.470417 -40.123742) (xy 343.522773 -40.057166)
			(xy 343.581221 -39.995868) (xy 343.645231 -39.940403) (xy 343.714223 -39.891274) (xy 343.787573 -39.848925)
			(xy 343.864616 -39.813741) (xy 343.944655 -39.786039) (xy 344.026964 -39.766071) (xy 344.110799 -39.754018)
			(xy 344.1954 -39.749988) (xy 344.280001 -39.754018) (xy 344.363836 -39.766071) (xy 344.446145 -39.786039)
			(xy 344.526184 -39.813741) (xy 344.603227 -39.848925) (xy 344.676577 -39.891274) (xy 344.745569 -39.940403)
			(xy 344.809579 -39.995868) (xy 344.868027 -40.057166) (xy 344.920383 -40.123742) (xy 344.966173 -40.194994)
			(xy 345.004984 -40.270275) (xy 345.036463 -40.348905) (xy 345.060324 -40.430172) (xy 345.076353 -40.513338)
			(xy 345.084404 -40.597652) (xy 345.084908 -40.64) (xy 345.084404 -40.682348) (xy 345.076353 -40.766662)
			(xy 345.060324 -40.849828) (xy 345.036463 -40.931095) (xy 345.004984 -41.009725) (xy 344.966173 -41.085006)
			(xy 344.920383 -41.156258) (xy 344.868027 -41.222834) (xy 344.809579 -41.284132) (xy 344.745569 -41.339597)
			(xy 344.676577 -41.388726) (xy 344.603227 -41.431075) (xy 344.526184 -41.466259) (xy 344.446145 -41.493961)
			(xy 344.363836 -41.513929) (xy 344.280001 -41.525982) (xy 344.1954 -41.530013) (xy 344.110799 -41.525982)
			(xy 344.026964 -41.513929) (xy 343.944655 -41.493961) (xy 343.864616 -41.466259) (xy 343.787573 -41.431075)
			(xy 343.714223 -41.388726) (xy 343.645231 -41.339597) (xy 343.581221 -41.284132) (xy 343.522773 -41.222834)
			(xy 343.470417 -41.156258) (xy 343.424627 -41.085006) (xy 343.385816 -41.009725) (xy 343.354337 -40.931095)
			(xy 343.330476 -40.849828) (xy 343.314447 -40.766662) (xy 343.306396 -40.682348) (xy 339.6234 -40.682348)
			(xy 339.6234 -41.73601) (xy 339.260688 -42.098722) (xy 339.253293 -42.105575) (xy 339.234694 -42.113317)
			(xy 339.22462 -42.113708) (xy 328.712068 -42.113708) (xy 328.702001 -42.114137) (xy 328.683405 -42.121861)
			(xy 328.676 -42.128694) (xy 328.589386 -42.215308) (xy 328.582532 -42.222703) (xy 328.574786 -42.241302)
			(xy 328.5744 -42.251376) (xy 328.5744 -46.91761) (xy 328.574825 -46.927679) (xy 328.582542 -46.946281)
			(xy 328.589386 -46.953678) (xy 328.610214 -46.974506) (xy 328.617614 -46.98135) (xy 328.636211 -46.989078)
			(xy 328.646282 -46.989492) (xy 339.300312 -46.989492) (xy 339.310381 -46.989917) (xy 339.328984 -46.997633)
			(xy 339.33638 -47.004478) (xy 339.6234 -47.291498) (xy 339.6234 -50.919888) (xy 376.553995 -50.919888)
			(xy 376.55797 -50.809847) (xy 376.569876 -50.70038) (xy 376.589649 -50.592057) (xy 376.617187 -50.485443)
			(xy 376.652346 -50.381095) (xy 376.694943 -50.279555) (xy 376.744756 -50.181354) (xy 376.801525 -50.087003)
			(xy 376.864954 -49.996994) (xy 376.934713 -49.911797) (xy 377.010437 -49.831856) (xy 377.091733 -49.757587)
			(xy 377.178175 -49.689378) (xy 377.269314 -49.627584) (xy 377.364675 -49.572528) (xy 377.463759 -49.524496)
			(xy 377.566052 -49.483739) (xy 377.671018 -49.450469) (xy 377.778111 -49.424861) (xy 377.886774 -49.407047)
			(xy 377.996438 -49.39712) (xy 378.106533 -49.395132) (xy 378.216484 -49.401093) (xy 378.325718 -49.414973)
			(xy 378.433667 -49.436698) (xy 378.539766 -49.466157) (xy 378.643463 -49.503194) (xy 378.744217 -49.547617)
			(xy 378.841503 -49.599195) (xy 378.934813 -49.657658) (xy 379.023662 -49.722702) (xy 379.107586 -49.793987)
			(xy 379.186147 -49.871143) (xy 379.258936 -49.953766) (xy 379.325573 -50.041426) (xy 379.385711 -50.133666)
			(xy 379.439037 -50.230005) (xy 379.485272 -50.32994) (xy 379.524176 -50.432952) (xy 379.555545 -50.538502)
			(xy 379.579216 -50.64604) (xy 379.595065 -50.755006) (xy 379.603011 -50.864832) (xy 379.603508 -50.919888)
			(xy 396.111995 -50.919888) (xy 396.11597 -50.809847) (xy 396.127876 -50.70038) (xy 396.147649 -50.592057)
			(xy 396.175187 -50.485443) (xy 396.210346 -50.381095) (xy 396.252943 -50.279555) (xy 396.302756 -50.181354)
			(xy 396.359525 -50.087003) (xy 396.422954 -49.996994) (xy 396.492713 -49.911797) (xy 396.568437 -49.831856)
			(xy 396.649733 -49.757587) (xy 396.736175 -49.689378) (xy 396.827314 -49.627584) (xy 396.922675 -49.572528)
			(xy 397.021759 -49.524496) (xy 397.124052 -49.483739) (xy 397.229018 -49.450469) (xy 397.336111 -49.424861)
			(xy 397.444774 -49.407047) (xy 397.554438 -49.39712) (xy 397.664533 -49.395132) (xy 397.774484 -49.401093)
			(xy 397.883718 -49.414973) (xy 397.991667 -49.436698) (xy 398.097766 -49.466157) (xy 398.201463 -49.503194)
			(xy 398.302217 -49.547617) (xy 398.399503 -49.599195) (xy 398.492813 -49.657658) (xy 398.581662 -49.722702)
			(xy 398.665586 -49.793987) (xy 398.744147 -49.871143) (xy 398.816936 -49.953766) (xy 398.883573 -50.041426)
			(xy 398.943711 -50.133666) (xy 398.997037 -50.230005) (xy 399.043272 -50.32994) (xy 399.082176 -50.432952)
			(xy 399.113545 -50.538502) (xy 399.137216 -50.64604) (xy 399.153065 -50.755006) (xy 399.161011 -50.864832)
			(xy 399.161508 -50.919888) (xy 399.161011 -50.974944) (xy 399.153065 -51.08477) (xy 399.137216 -51.193736)
			(xy 399.113545 -51.301274) (xy 399.082176 -51.406824) (xy 399.043272 -51.509836) (xy 398.997037 -51.609771)
			(xy 398.943711 -51.70611) (xy 398.883573 -51.79835) (xy 398.816936 -51.88601) (xy 398.744147 -51.968633)
			(xy 398.665586 -52.045789) (xy 398.581662 -52.117074) (xy 398.492813 -52.182118) (xy 398.399503 -52.240581)
			(xy 398.302217 -52.292159) (xy 398.201463 -52.336582) (xy 398.097766 -52.373619) (xy 397.991667 -52.403078)
			(xy 397.883718 -52.424803) (xy 397.774484 -52.438683) (xy 397.664533 -52.444644) (xy 397.554438 -52.442656)
			(xy 397.444774 -52.432729) (xy 397.336111 -52.414915) (xy 397.229018 -52.389307) (xy 397.124052 -52.356037)
			(xy 397.021759 -52.31528) (xy 396.922675 -52.267248) (xy 396.827314 -52.212192) (xy 396.736175 -52.150398)
			(xy 396.649733 -52.082189) (xy 396.568437 -52.00792) (xy 396.492713 -51.927979) (xy 396.422954 -51.842782)
			(xy 396.359525 -51.752773) (xy 396.302756 -51.658422) (xy 396.252943 -51.560221) (xy 396.210346 -51.458681)
			(xy 396.175187 -51.354333) (xy 396.147649 -51.247719) (xy 396.127876 -51.139396) (xy 396.11597 -51.029929)
			(xy 396.111995 -50.919888) (xy 379.603508 -50.919888) (xy 379.603011 -50.974944) (xy 379.595065 -51.08477)
			(xy 379.579216 -51.193736) (xy 379.555545 -51.301274) (xy 379.524176 -51.406824) (xy 379.485272 -51.509836)
			(xy 379.439037 -51.609771) (xy 379.385711 -51.70611) (xy 379.325573 -51.79835) (xy 379.258936 -51.88601)
			(xy 379.186147 -51.968633) (xy 379.107586 -52.045789) (xy 379.023662 -52.117074) (xy 378.934813 -52.182118)
			(xy 378.841503 -52.240581) (xy 378.744217 -52.292159) (xy 378.643463 -52.336582) (xy 378.539766 -52.373619)
			(xy 378.433667 -52.403078) (xy 378.325718 -52.424803) (xy 378.216484 -52.438683) (xy 378.106533 -52.444644)
			(xy 377.996438 -52.442656) (xy 377.886774 -52.432729) (xy 377.778111 -52.414915) (xy 377.671018 -52.389307)
			(xy 377.566052 -52.356037) (xy 377.463759 -52.31528) (xy 377.364675 -52.267248) (xy 377.269314 -52.212192)
			(xy 377.178175 -52.150398) (xy 377.091733 -52.082189) (xy 377.010437 -52.00792) (xy 376.934713 -51.927979)
			(xy 376.864954 -51.842782) (xy 376.801525 -51.752773) (xy 376.744756 -51.658422) (xy 376.694943 -51.560221)
			(xy 376.652346 -51.458681) (xy 376.617187 -51.354333) (xy 376.589649 -51.247719) (xy 376.569876 -51.139396)
			(xy 376.55797 -51.029929) (xy 376.553995 -50.919888) (xy 339.6234 -50.919888) (xy 339.6234 -51.959948)
			(xy 343.280996 -51.959948) (xy 343.280996 -51.875252) (xy 343.289047 -51.790938) (xy 343.305076 -51.707772)
			(xy 343.328937 -51.626505) (xy 343.360416 -51.547875) (xy 343.399227 -51.472594) (xy 343.445017 -51.401342)
			(xy 343.497373 -51.334766) (xy 343.555821 -51.273468) (xy 343.619831 -51.218003) (xy 343.688823 -51.168874)
			(xy 343.762173 -51.126525) (xy 343.839216 -51.091341) (xy 343.919255 -51.063639) (xy 344.001564 -51.043671)
			(xy 344.085399 -51.031618) (xy 344.17 -51.027588) (xy 344.254601 -51.031618) (xy 344.338436 -51.043671)
			(xy 344.420745 -51.063639) (xy 344.500784 -51.091341) (xy 344.577827 -51.126525) (xy 344.651177 -51.168874)
			(xy 344.720169 -51.218003) (xy 344.784179 -51.273468) (xy 344.842627 -51.334766) (xy 344.894983 -51.401342)
			(xy 344.940773 -51.472594) (xy 344.979584 -51.547875) (xy 345.011063 -51.626505) (xy 345.034924 -51.707772)
			(xy 345.050953 -51.790938) (xy 345.059004 -51.875252) (xy 345.059508 -51.9176) (xy 345.059004 -51.959948)
			(xy 345.050953 -52.044262) (xy 345.034924 -52.127428) (xy 345.011063 -52.208695) (xy 344.979584 -52.287325)
			(xy 344.940773 -52.362606) (xy 344.894983 -52.433858) (xy 344.842627 -52.500434) (xy 344.784179 -52.561732)
			(xy 344.720169 -52.617197) (xy 344.651177 -52.666326) (xy 344.577827 -52.708675) (xy 344.500784 -52.743859)
			(xy 344.420745 -52.771561) (xy 344.338436 -52.791529) (xy 344.254601 -52.803582) (xy 344.17 -52.807613)
			(xy 344.085399 -52.803582) (xy 344.001564 -52.791529) (xy 343.919255 -52.771561) (xy 343.839216 -52.743859)
			(xy 343.762173 -52.708675) (xy 343.688823 -52.666326) (xy 343.619831 -52.617197) (xy 343.555821 -52.561732)
			(xy 343.497373 -52.500434) (xy 343.445017 -52.433858) (xy 343.399227 -52.362606) (xy 343.360416 -52.287325)
			(xy 343.328937 -52.208695) (xy 343.305076 -52.127428) (xy 343.289047 -52.044262) (xy 343.280996 -51.959948)
			(xy 339.6234 -51.959948) (xy 339.6234 -52.872132) (xy 339.11921 -53.376322) (xy 339.111816 -53.383179)
			(xy 339.093217 -53.390929) (xy 339.083142 -53.391308) (xy 328.712068 -53.391308) (xy 328.702001 -53.391737)
			(xy 328.683405 -53.399461) (xy 328.676 -53.406294) (xy 328.589386 -53.492908) (xy 328.582532 -53.500303)
			(xy 328.574786 -53.518902) (xy 328.5744 -53.528976) (xy 328.5744 -58.19521) (xy 328.574825 -58.205279)
			(xy 328.582542 -58.223881) (xy 328.589386 -58.231278) (xy 328.610214 -58.252106) (xy 328.617614 -58.25895)
			(xy 328.636211 -58.266678) (xy 328.646282 -58.267092) (xy 339.23859 -58.267092) (xy 339.248661 -58.267513)
			(xy 339.267269 -58.275224) (xy 339.274658 -58.282078) (xy 339.41258 -58.42) (xy 377.061994 -58.42)
			(xy 377.065974 -58.330117) (xy 377.077882 -58.240937) (xy 377.097625 -58.153159) (xy 377.125049 -58.067469)
			(xy 377.159938 -57.984538) (xy 377.202021 -57.905016) (xy 377.250967 -57.829523) (xy 377.306394 -57.758652)
			(xy 377.367867 -57.692957) (xy 377.434906 -57.632952) (xy 377.506986 -57.579107) (xy 377.583542 -57.531843)
			(xy 377.663977 -57.49153) (xy 377.747659 -57.458483) (xy 377.833934 -57.432962) (xy 377.922128 -57.415166)
			(xy 378.011549 -57.405233) (xy 378.101498 -57.403243) (xy 378.191271 -57.40921) (xy 378.280166 -57.423088)
			(xy 378.367486 -57.444768) (xy 378.452548 -57.474081) (xy 378.534687 -57.510797) (xy 378.613259 -57.554628)
			(xy 378.68765 -57.605232) (xy 378.757277 -57.662213) (xy 378.821596 -57.725125) (xy 378.880104 -57.793475)
			(xy 378.932341 -57.866728) (xy 378.9779 -57.944311) (xy 379.016424 -58.025618) (xy 379.047611 -58.110011)
			(xy 379.071218 -58.19683) (xy 379.087059 -58.285395) (xy 379.095011 -58.375014) (xy 379.095508 -58.42)
			(xy 396.619994 -58.42) (xy 396.623974 -58.330117) (xy 396.635882 -58.240937) (xy 396.655625 -58.153159)
			(xy 396.683049 -58.067469) (xy 396.717938 -57.984538) (xy 396.760021 -57.905016) (xy 396.808967 -57.829523)
			(xy 396.864394 -57.758652) (xy 396.925867 -57.692957) (xy 396.992906 -57.632952) (xy 397.064986 -57.579107)
			(xy 397.141542 -57.531843) (xy 397.221977 -57.49153) (xy 397.305659 -57.458483) (xy 397.391934 -57.432962)
			(xy 397.480128 -57.415166) (xy 397.569549 -57.405233) (xy 397.659498 -57.403243) (xy 397.749271 -57.40921)
			(xy 397.838166 -57.423088) (xy 397.925486 -57.444768) (xy 398.010548 -57.474081) (xy 398.092687 -57.510797)
			(xy 398.171259 -57.554628) (xy 398.24565 -57.605232) (xy 398.315277 -57.662213) (xy 398.379596 -57.725125)
			(xy 398.438104 -57.793475) (xy 398.490341 -57.866728) (xy 398.5359 -57.944311) (xy 398.574424 -58.025618)
			(xy 398.605611 -58.110011) (xy 398.629218 -58.19683) (xy 398.645059 -58.285395) (xy 398.653011 -58.375014)
			(xy 398.653508 -58.42) (xy 398.653011 -58.464986) (xy 398.645059 -58.554605) (xy 398.629218 -58.64317)
			(xy 398.605611 -58.729989) (xy 398.574424 -58.814382) (xy 398.5359 -58.895689) (xy 398.490341 -58.973272)
			(xy 398.438104 -59.046525) (xy 398.379596 -59.114875) (xy 398.315277 -59.177787) (xy 398.24565 -59.234768)
			(xy 398.171259 -59.285372) (xy 398.092687 -59.329203) (xy 398.010548 -59.365919) (xy 397.925486 -59.395232)
			(xy 397.838166 -59.416912) (xy 397.749271 -59.43079) (xy 397.659498 -59.436757) (xy 397.569549 -59.434767)
			(xy 397.480128 -59.424834) (xy 397.391934 -59.407038) (xy 397.305659 -59.381517) (xy 397.221977 -59.34847)
			(xy 397.141542 -59.308157) (xy 397.064986 -59.260893) (xy 396.992906 -59.207048) (xy 396.925867 -59.147043)
			(xy 396.864394 -59.081348) (xy 396.808967 -59.010477) (xy 396.760021 -58.934984) (xy 396.717938 -58.855462)
			(xy 396.683049 -58.772531) (xy 396.655625 -58.686841) (xy 396.635882 -58.599063) (xy 396.623974 -58.509883)
			(xy 396.619994 -58.42) (xy 379.095508 -58.42) (xy 379.095011 -58.464986) (xy 379.087059 -58.554605)
			(xy 379.071218 -58.64317) (xy 379.047611 -58.729989) (xy 379.016424 -58.814382) (xy 378.9779 -58.895689)
			(xy 378.932341 -58.973272) (xy 378.880104 -59.046525) (xy 378.821596 -59.114875) (xy 378.757277 -59.177787)
			(xy 378.68765 -59.234768) (xy 378.613259 -59.285372) (xy 378.534687 -59.329203) (xy 378.452548 -59.365919)
			(xy 378.367486 -59.395232) (xy 378.280166 -59.416912) (xy 378.191271 -59.43079) (xy 378.101498 -59.436757)
			(xy 378.011549 -59.434767) (xy 377.922128 -59.424834) (xy 377.833934 -59.407038) (xy 377.747659 -59.381517)
			(xy 377.663977 -59.34847) (xy 377.583542 -59.308157) (xy 377.506986 -59.260893) (xy 377.434906 -59.207048)
			(xy 377.367867 -59.147043) (xy 377.306394 -59.081348) (xy 377.250967 -59.010477) (xy 377.202021 -58.934984)
			(xy 377.159938 -58.855462) (xy 377.125049 -58.772531) (xy 377.097625 -58.686841) (xy 377.077882 -58.599063)
			(xy 377.065974 -58.509883) (xy 377.061994 -58.42) (xy 339.41258 -58.42) (xy 339.6234 -58.63082) (xy 339.6234 -63.977012)
			(xy 338.94649 -64.653922) (xy 338.939095 -64.660775) (xy 338.920496 -64.668518) (xy 338.910422 -64.668908)
			(xy 328.712068 -64.668908) (xy 328.702001 -64.669337) (xy 328.683405 -64.677061) (xy 328.676 -64.683894)
			(xy 328.589386 -64.770508) (xy 328.582532 -64.777903) (xy 328.574786 -64.796502) (xy 328.5744 -64.806576)
			(xy 328.5744 -69.47281) (xy 328.574825 -69.482879) (xy 328.582542 -69.501481) (xy 328.589386 -69.508878)
			(xy 328.610214 -69.529706) (xy 328.617614 -69.53655) (xy 328.636211 -69.544278) (xy 328.646282 -69.544692)
			(xy 339.160866 -69.544692) (xy 339.170931 -69.545127) (xy 339.189519 -69.552857) (xy 339.196934 -69.559678)
			(xy 339.6234 -69.986144) (xy 339.6234 -71.239888) (xy 376.553995 -71.239888) (xy 376.55797 -71.129847)
			(xy 376.569876 -71.02038) (xy 376.589649 -70.912057) (xy 376.617187 -70.805443) (xy 376.652346 -70.701095)
			(xy 376.694943 -70.599555) (xy 376.744756 -70.501354) (xy 376.801525 -70.407003) (xy 376.864954 -70.316994)
			(xy 376.934713 -70.231797) (xy 377.010437 -70.151856) (xy 377.091733 -70.077587) (xy 377.178175 -70.009378)
			(xy 377.269314 -69.947584) (xy 377.364675 -69.892528) (xy 377.463759 -69.844496) (xy 377.566052 -69.803739)
			(xy 377.671018 -69.770469) (xy 377.778111 -69.744861) (xy 377.886774 -69.727047) (xy 377.996438 -69.71712)
			(xy 378.106533 -69.715132) (xy 378.216484 -69.721093) (xy 378.325718 -69.734973) (xy 378.433667 -69.756698)
			(xy 378.539766 -69.786157) (xy 378.643463 -69.823194) (xy 378.744217 -69.867617) (xy 378.841503 -69.919195)
			(xy 378.934813 -69.977658) (xy 379.023662 -70.042702) (xy 379.107586 -70.113987) (xy 379.186147 -70.191143)
			(xy 379.258936 -70.273766) (xy 379.325573 -70.361426) (xy 379.385711 -70.453666) (xy 379.439037 -70.550005)
			(xy 379.485272 -70.64994) (xy 379.524176 -70.752952) (xy 379.555545 -70.858502) (xy 379.579216 -70.96604)
			(xy 379.595065 -71.075006) (xy 379.603011 -71.184832) (xy 379.603508 -71.239888) (xy 396.111995 -71.239888)
			(xy 396.11597 -71.129847) (xy 396.127876 -71.02038) (xy 396.147649 -70.912057) (xy 396.175187 -70.805443)
			(xy 396.210346 -70.701095) (xy 396.252943 -70.599555) (xy 396.302756 -70.501354) (xy 396.359525 -70.407003)
			(xy 396.422954 -70.316994) (xy 396.492713 -70.231797) (xy 396.568437 -70.151856) (xy 396.649733 -70.077587)
			(xy 396.736175 -70.009378) (xy 396.827314 -69.947584) (xy 396.922675 -69.892528) (xy 397.021759 -69.844496)
			(xy 397.124052 -69.803739) (xy 397.229018 -69.770469) (xy 397.336111 -69.744861) (xy 397.444774 -69.727047)
			(xy 397.554438 -69.71712) (xy 397.664533 -69.715132) (xy 397.774484 -69.721093) (xy 397.883718 -69.734973)
			(xy 397.991667 -69.756698) (xy 398.097766 -69.786157) (xy 398.201463 -69.823194) (xy 398.302217 -69.867617)
			(xy 398.399503 -69.919195) (xy 398.492813 -69.977658) (xy 398.581662 -70.042702) (xy 398.665586 -70.113987)
			(xy 398.744147 -70.191143) (xy 398.816936 -70.273766) (xy 398.883573 -70.361426) (xy 398.943711 -70.453666)
			(xy 398.997037 -70.550005) (xy 399.043272 -70.64994) (xy 399.082176 -70.752952) (xy 399.113545 -70.858502)
			(xy 399.137216 -70.96604) (xy 399.153065 -71.075006) (xy 399.161011 -71.184832) (xy 399.161508 -71.239888)
			(xy 399.161011 -71.294944) (xy 399.153065 -71.40477) (xy 399.137216 -71.513736) (xy 399.113545 -71.621274)
			(xy 399.082176 -71.726824) (xy 399.043272 -71.829836) (xy 398.997037 -71.929771) (xy 398.943711 -72.02611)
			(xy 398.883573 -72.11835) (xy 398.816936 -72.20601) (xy 398.744147 -72.288633) (xy 398.665586 -72.365789)
			(xy 398.581662 -72.437074) (xy 398.492813 -72.502118) (xy 398.399503 -72.560581) (xy 398.302217 -72.612159)
			(xy 398.201463 -72.656582) (xy 398.097766 -72.693619) (xy 397.991667 -72.723078) (xy 397.883718 -72.744803)
			(xy 397.774484 -72.758683) (xy 397.664533 -72.764644) (xy 397.554438 -72.762656) (xy 397.444774 -72.752729)
			(xy 397.336111 -72.734915) (xy 397.229018 -72.709307) (xy 397.124052 -72.676037) (xy 397.021759 -72.63528)
			(xy 396.922675 -72.587248) (xy 396.827314 -72.532192) (xy 396.736175 -72.470398) (xy 396.649733 -72.402189)
			(xy 396.568437 -72.32792) (xy 396.492713 -72.247979) (xy 396.422954 -72.162782) (xy 396.359525 -72.072773)
			(xy 396.302756 -71.978422) (xy 396.252943 -71.880221) (xy 396.210346 -71.778681) (xy 396.175187 -71.674333)
			(xy 396.147649 -71.567719) (xy 396.127876 -71.459396) (xy 396.11597 -71.349929) (xy 396.111995 -71.239888)
			(xy 379.603508 -71.239888) (xy 379.603011 -71.294944) (xy 379.595065 -71.40477) (xy 379.579216 -71.513736)
			(xy 379.555545 -71.621274) (xy 379.524176 -71.726824) (xy 379.485272 -71.829836) (xy 379.439037 -71.929771)
			(xy 379.385711 -72.02611) (xy 379.325573 -72.11835) (xy 379.258936 -72.20601) (xy 379.186147 -72.288633)
			(xy 379.107586 -72.365789) (xy 379.023662 -72.437074) (xy 378.934813 -72.502118) (xy 378.841503 -72.560581)
			(xy 378.744217 -72.612159) (xy 378.643463 -72.656582) (xy 378.539766 -72.693619) (xy 378.433667 -72.723078)
			(xy 378.325718 -72.744803) (xy 378.216484 -72.758683) (xy 378.106533 -72.764644) (xy 377.996438 -72.762656)
			(xy 377.886774 -72.752729) (xy 377.778111 -72.734915) (xy 377.671018 -72.709307) (xy 377.566052 -72.676037)
			(xy 377.463759 -72.63528) (xy 377.364675 -72.587248) (xy 377.269314 -72.532192) (xy 377.178175 -72.470398)
			(xy 377.091733 -72.402189) (xy 377.010437 -72.32792) (xy 376.934713 -72.247979) (xy 376.864954 -72.162782)
			(xy 376.801525 -72.072773) (xy 376.744756 -71.978422) (xy 376.694943 -71.880221) (xy 376.652346 -71.778681)
			(xy 376.617187 -71.674333) (xy 376.589649 -71.567719) (xy 376.569876 -71.459396) (xy 376.55797 -71.349929)
			(xy 376.553995 -71.239888) (xy 339.6234 -71.239888) (xy 339.6234 -75.378818) (xy 339.071204 -75.931014)
			(xy 339.06381 -75.93787) (xy 339.045211 -75.94562) (xy 339.035136 -75.946) (xy 328.71283 -75.946)
			(xy 328.702765 -75.946436) (xy 328.68418 -75.954168) (xy 328.676762 -75.960986) (xy 328.589386 -76.048362)
			(xy 328.58254 -76.05576) (xy 328.574815 -76.074359) (xy 328.5744 -76.08443) (xy 328.5744 -78.74)
			(xy 377.061994 -78.74) (xy 377.065974 -78.650117) (xy 377.077882 -78.560937) (xy 377.097625 -78.473159)
			(xy 377.125049 -78.387469) (xy 377.159938 -78.304538) (xy 377.202021 -78.225016) (xy 377.250967 -78.149523)
			(xy 377.306394 -78.078652) (xy 377.367867 -78.012957) (xy 377.434906 -77.952952) (xy 377.506986 -77.899107)
			(xy 377.583542 -77.851843) (xy 377.663977 -77.81153) (xy 377.747659 -77.778483) (xy 377.833934 -77.752962)
			(xy 377.922128 -77.735166) (xy 378.011549 -77.725233) (xy 378.101498 -77.723243) (xy 378.191271 -77.72921)
			(xy 378.280166 -77.743088) (xy 378.367486 -77.764768) (xy 378.452548 -77.794081) (xy 378.534687 -77.830797)
			(xy 378.613259 -77.874628) (xy 378.68765 -77.925232) (xy 378.757277 -77.982213) (xy 378.821596 -78.045125)
			(xy 378.880104 -78.113475) (xy 378.932341 -78.186728) (xy 378.9779 -78.264311) (xy 379.016424 -78.345618)
			(xy 379.047611 -78.430011) (xy 379.071218 -78.51683) (xy 379.087059 -78.605395) (xy 379.095011 -78.695014)
			(xy 379.095508 -78.74) (xy 396.619994 -78.74) (xy 396.623974 -78.650117) (xy 396.635882 -78.560937)
			(xy 396.655625 -78.473159) (xy 396.683049 -78.387469) (xy 396.717938 -78.304538) (xy 396.760021 -78.225016)
			(xy 396.808967 -78.149523) (xy 396.864394 -78.078652) (xy 396.925867 -78.012957) (xy 396.992906 -77.952952)
			(xy 397.064986 -77.899107) (xy 397.141542 -77.851843) (xy 397.221977 -77.81153) (xy 397.305659 -77.778483)
			(xy 397.391934 -77.752962) (xy 397.480128 -77.735166) (xy 397.569549 -77.725233) (xy 397.659498 -77.723243)
			(xy 397.749271 -77.72921) (xy 397.838166 -77.743088) (xy 397.925486 -77.764768) (xy 398.010548 -77.794081)
			(xy 398.092687 -77.830797) (xy 398.171259 -77.874628) (xy 398.24565 -77.925232) (xy 398.315277 -77.982213)
			(xy 398.379596 -78.045125) (xy 398.438104 -78.113475) (xy 398.490341 -78.186728) (xy 398.5359 -78.264311)
			(xy 398.574424 -78.345618) (xy 398.605611 -78.430011) (xy 398.629218 -78.51683) (xy 398.645059 -78.605395)
			(xy 398.653011 -78.695014) (xy 398.653508 -78.74) (xy 398.653011 -78.784986) (xy 398.645059 -78.874605)
			(xy 398.629218 -78.96317) (xy 398.605611 -79.049989) (xy 398.574424 -79.134382) (xy 398.5359 -79.215689)
			(xy 398.490341 -79.293272) (xy 398.438104 -79.366525) (xy 398.379596 -79.434875) (xy 398.315277 -79.497787)
			(xy 398.24565 -79.554768) (xy 398.171259 -79.605372) (xy 398.092687 -79.649203) (xy 398.010548 -79.685919)
			(xy 397.925486 -79.715232) (xy 397.838166 -79.736912) (xy 397.749271 -79.75079) (xy 397.659498 -79.756757)
			(xy 397.569549 -79.754767) (xy 397.480128 -79.744834) (xy 397.391934 -79.727038) (xy 397.305659 -79.701517)
			(xy 397.221977 -79.66847) (xy 397.141542 -79.628157) (xy 397.064986 -79.580893) (xy 396.992906 -79.527048)
			(xy 396.925867 -79.467043) (xy 396.864394 -79.401348) (xy 396.808967 -79.330477) (xy 396.760021 -79.254984)
			(xy 396.717938 -79.175462) (xy 396.683049 -79.092531) (xy 396.655625 -79.006841) (xy 396.635882 -78.919063)
			(xy 396.623974 -78.829883) (xy 396.619994 -78.74) (xy 379.095508 -78.74) (xy 379.095011 -78.784986)
			(xy 379.087059 -78.874605) (xy 379.071218 -78.96317) (xy 379.047611 -79.049989) (xy 379.016424 -79.134382)
			(xy 378.9779 -79.215689) (xy 378.932341 -79.293272) (xy 378.880104 -79.366525) (xy 378.821596 -79.434875)
			(xy 378.757277 -79.497787) (xy 378.68765 -79.554768) (xy 378.613259 -79.605372) (xy 378.534687 -79.649203)
			(xy 378.452548 -79.685919) (xy 378.367486 -79.715232) (xy 378.280166 -79.736912) (xy 378.191271 -79.75079)
			(xy 378.101498 -79.756757) (xy 378.011549 -79.754767) (xy 377.922128 -79.744834) (xy 377.833934 -79.727038)
			(xy 377.747659 -79.701517) (xy 377.663977 -79.66847) (xy 377.583542 -79.628157) (xy 377.506986 -79.580893)
			(xy 377.434906 -79.527048) (xy 377.367867 -79.467043) (xy 377.306394 -79.401348) (xy 377.250967 -79.330477)
			(xy 377.202021 -79.254984) (xy 377.159938 -79.175462) (xy 377.125049 -79.092531) (xy 377.097625 -79.006841)
			(xy 377.077882 -78.919063) (xy 377.065974 -78.829883) (xy 377.061994 -78.74) (xy 328.5744 -78.74)
			(xy 328.5744 -79.607918) (xy 328.574827 -79.617987) (xy 328.582546 -79.636586) (xy 328.589386 -79.643986)
			(xy 328.813414 -79.868014) (xy 328.820809 -79.874868) (xy 328.839408 -79.88261) (xy 328.849482 -79.883)
			(xy 345.405202 -79.883) (xy 345.415272 -79.883424) (xy 345.433876 -79.891139) (xy 345.44127 -79.897986)
			(xy 346.307664 -80.76438) (xy 346.310924 -80.767485) (xy 346.318333 -80.7726) (xy 346.322396 -80.77454)
			(xy 346.322396 -80.779112) (xy 348.2086 -82.665316) (xy 348.2086 -91.559888) (xy 376.553995 -91.559888)
			(xy 376.55797 -91.449847) (xy 376.569876 -91.34038) (xy 376.589649 -91.232057) (xy 376.617187 -91.125443)
			(xy 376.652346 -91.021095) (xy 376.694943 -90.919555) (xy 376.744756 -90.821354) (xy 376.801525 -90.727003)
			(xy 376.864954 -90.636994) (xy 376.934713 -90.551797) (xy 377.010437 -90.471856) (xy 377.091733 -90.397587)
			(xy 377.178175 -90.329378) (xy 377.269314 -90.267584) (xy 377.364675 -90.212528) (xy 377.463759 -90.164496)
			(xy 377.566052 -90.123739) (xy 377.671018 -90.090469) (xy 377.778111 -90.064861) (xy 377.886774 -90.047047)
			(xy 377.996438 -90.03712) (xy 378.106533 -90.035132) (xy 378.216484 -90.041093) (xy 378.325718 -90.054973)
			(xy 378.433667 -90.076698) (xy 378.539766 -90.106157) (xy 378.643463 -90.143194) (xy 378.744217 -90.187617)
			(xy 378.841503 -90.239195) (xy 378.934813 -90.297658) (xy 379.023662 -90.362702) (xy 379.107586 -90.433987)
			(xy 379.186147 -90.511143) (xy 379.258936 -90.593766) (xy 379.325573 -90.681426) (xy 379.385711 -90.773666)
			(xy 379.439037 -90.870005) (xy 379.485272 -90.96994) (xy 379.524176 -91.072952) (xy 379.555545 -91.178502)
			(xy 379.579216 -91.28604) (xy 379.595065 -91.395006) (xy 379.603011 -91.504832) (xy 379.603508 -91.559888)
			(xy 396.111995 -91.559888) (xy 396.11597 -91.449847) (xy 396.127876 -91.34038) (xy 396.147649 -91.232057)
			(xy 396.175187 -91.125443) (xy 396.210346 -91.021095) (xy 396.252943 -90.919555) (xy 396.302756 -90.821354)
			(xy 396.359525 -90.727003) (xy 396.422954 -90.636994) (xy 396.492713 -90.551797) (xy 396.568437 -90.471856)
			(xy 396.649733 -90.397587) (xy 396.736175 -90.329378) (xy 396.827314 -90.267584) (xy 396.922675 -90.212528)
			(xy 397.021759 -90.164496) (xy 397.124052 -90.123739) (xy 397.229018 -90.090469) (xy 397.336111 -90.064861)
			(xy 397.444774 -90.047047) (xy 397.554438 -90.03712) (xy 397.664533 -90.035132) (xy 397.774484 -90.041093)
			(xy 397.883718 -90.054973) (xy 397.991667 -90.076698) (xy 398.097766 -90.106157) (xy 398.201463 -90.143194)
			(xy 398.302217 -90.187617) (xy 398.399503 -90.239195) (xy 398.492813 -90.297658) (xy 398.581662 -90.362702)
			(xy 398.665586 -90.433987) (xy 398.744147 -90.511143) (xy 398.816936 -90.593766) (xy 398.883573 -90.681426)
			(xy 398.943711 -90.773666) (xy 398.997037 -90.870005) (xy 399.043272 -90.96994) (xy 399.082176 -91.072952)
			(xy 399.113545 -91.178502) (xy 399.137216 -91.28604) (xy 399.153065 -91.395006) (xy 399.161011 -91.504832)
			(xy 399.161508 -91.559888) (xy 399.161011 -91.614944) (xy 399.153065 -91.72477) (xy 399.137216 -91.833736)
			(xy 399.113545 -91.941274) (xy 399.082176 -92.046824) (xy 399.043272 -92.149836) (xy 398.997037 -92.249771)
			(xy 398.943711 -92.34611) (xy 398.883573 -92.43835) (xy 398.816936 -92.52601) (xy 398.744147 -92.608633)
			(xy 398.665586 -92.685789) (xy 398.581662 -92.757074) (xy 398.492813 -92.822118) (xy 398.399503 -92.880581)
			(xy 398.302217 -92.932159) (xy 398.201463 -92.976582) (xy 398.097766 -93.013619) (xy 397.991667 -93.043078)
			(xy 397.883718 -93.064803) (xy 397.774484 -93.078683) (xy 397.664533 -93.084644) (xy 397.554438 -93.082656)
			(xy 397.444774 -93.072729) (xy 397.336111 -93.054915) (xy 397.229018 -93.029307) (xy 397.124052 -92.996037)
			(xy 397.021759 -92.95528) (xy 396.922675 -92.907248) (xy 396.827314 -92.852192) (xy 396.736175 -92.790398)
			(xy 396.649733 -92.722189) (xy 396.568437 -92.64792) (xy 396.492713 -92.567979) (xy 396.422954 -92.482782)
			(xy 396.359525 -92.392773) (xy 396.302756 -92.298422) (xy 396.252943 -92.200221) (xy 396.210346 -92.098681)
			(xy 396.175187 -91.994333) (xy 396.147649 -91.887719) (xy 396.127876 -91.779396) (xy 396.11597 -91.669929)
			(xy 396.111995 -91.559888) (xy 379.603508 -91.559888) (xy 379.603011 -91.614944) (xy 379.595065 -91.72477)
			(xy 379.579216 -91.833736) (xy 379.555545 -91.941274) (xy 379.524176 -92.046824) (xy 379.485272 -92.149836)
			(xy 379.439037 -92.249771) (xy 379.385711 -92.34611) (xy 379.325573 -92.43835) (xy 379.258936 -92.52601)
			(xy 379.186147 -92.608633) (xy 379.107586 -92.685789) (xy 379.023662 -92.757074) (xy 378.934813 -92.822118)
			(xy 378.841503 -92.880581) (xy 378.744217 -92.932159) (xy 378.643463 -92.976582) (xy 378.539766 -93.013619)
			(xy 378.433667 -93.043078) (xy 378.325718 -93.064803) (xy 378.216484 -93.078683) (xy 378.106533 -93.084644)
			(xy 377.996438 -93.082656) (xy 377.886774 -93.072729) (xy 377.778111 -93.054915) (xy 377.671018 -93.029307)
			(xy 377.566052 -92.996037) (xy 377.463759 -92.95528) (xy 377.364675 -92.907248) (xy 377.269314 -92.852192)
			(xy 377.178175 -92.790398) (xy 377.091733 -92.722189) (xy 377.010437 -92.64792) (xy 376.934713 -92.567979)
			(xy 376.864954 -92.482782) (xy 376.801525 -92.392773) (xy 376.744756 -92.298422) (xy 376.694943 -92.200221)
			(xy 376.652346 -92.098681) (xy 376.617187 -91.994333) (xy 376.589649 -91.887719) (xy 376.569876 -91.779396)
			(xy 376.55797 -91.669929) (xy 376.553995 -91.559888) (xy 348.2086 -91.559888) (xy 348.2086 -99.06)
			(xy 377.061994 -99.06) (xy 377.065974 -98.970117) (xy 377.077882 -98.880937) (xy 377.097625 -98.793159)
			(xy 377.125049 -98.707469) (xy 377.159938 -98.624538) (xy 377.202021 -98.545016) (xy 377.250967 -98.469523)
			(xy 377.306394 -98.398652) (xy 377.367867 -98.332957) (xy 377.434906 -98.272952) (xy 377.506986 -98.219107)
			(xy 377.583542 -98.171843) (xy 377.663977 -98.13153) (xy 377.747659 -98.098483) (xy 377.833934 -98.072962)
			(xy 377.922128 -98.055166) (xy 378.011549 -98.045233) (xy 378.101498 -98.043243) (xy 378.191271 -98.04921)
			(xy 378.280166 -98.063088) (xy 378.367486 -98.084768) (xy 378.452548 -98.114081) (xy 378.534687 -98.150797)
			(xy 378.613259 -98.194628) (xy 378.68765 -98.245232) (xy 378.757277 -98.302213) (xy 378.821596 -98.365125)
			(xy 378.880104 -98.433475) (xy 378.932341 -98.506728) (xy 378.9779 -98.584311) (xy 379.016424 -98.665618)
			(xy 379.047611 -98.750011) (xy 379.071218 -98.83683) (xy 379.087059 -98.925395) (xy 379.095011 -99.015014)
			(xy 379.095508 -99.06) (xy 396.619994 -99.06) (xy 396.623974 -98.970117) (xy 396.635882 -98.880937)
			(xy 396.655625 -98.793159) (xy 396.683049 -98.707469) (xy 396.717938 -98.624538) (xy 396.760021 -98.545016)
			(xy 396.808967 -98.469523) (xy 396.864394 -98.398652) (xy 396.925867 -98.332957) (xy 396.992906 -98.272952)
			(xy 397.064986 -98.219107) (xy 397.141542 -98.171843) (xy 397.221977 -98.13153) (xy 397.305659 -98.098483)
			(xy 397.391934 -98.072962) (xy 397.480128 -98.055166) (xy 397.569549 -98.045233) (xy 397.659498 -98.043243)
			(xy 397.749271 -98.04921) (xy 397.838166 -98.063088) (xy 397.925486 -98.084768) (xy 398.010548 -98.114081)
			(xy 398.092687 -98.150797) (xy 398.171259 -98.194628) (xy 398.24565 -98.245232) (xy 398.315277 -98.302213)
			(xy 398.379596 -98.365125) (xy 398.438104 -98.433475) (xy 398.490341 -98.506728) (xy 398.5359 -98.584311)
			(xy 398.574424 -98.665618) (xy 398.605611 -98.750011) (xy 398.629218 -98.83683) (xy 398.645059 -98.925395)
			(xy 398.653011 -99.015014) (xy 398.653508 -99.06) (xy 398.653011 -99.104986) (xy 398.645059 -99.194605)
			(xy 398.629218 -99.28317) (xy 398.605611 -99.369989) (xy 398.574424 -99.454382) (xy 398.5359 -99.535689)
			(xy 398.490341 -99.613272) (xy 398.438104 -99.686525) (xy 398.379596 -99.754875) (xy 398.315277 -99.817787)
			(xy 398.24565 -99.874768) (xy 398.171259 -99.925372) (xy 398.092687 -99.969203) (xy 398.010548 -100.005919)
			(xy 397.925486 -100.035232) (xy 397.838166 -100.056912) (xy 397.749271 -100.07079) (xy 397.659498 -100.076757)
			(xy 397.569549 -100.074767) (xy 397.480128 -100.064834) (xy 397.391934 -100.047038) (xy 397.305659 -100.021517)
			(xy 397.221977 -99.98847) (xy 397.141542 -99.948157) (xy 397.064986 -99.900893) (xy 396.992906 -99.847048)
			(xy 396.925867 -99.787043) (xy 396.864394 -99.721348) (xy 396.808967 -99.650477) (xy 396.760021 -99.574984)
			(xy 396.717938 -99.495462) (xy 396.683049 -99.412531) (xy 396.655625 -99.326841) (xy 396.635882 -99.239063)
			(xy 396.623974 -99.149883) (xy 396.619994 -99.06) (xy 379.095508 -99.06) (xy 379.095011 -99.104986)
			(xy 379.087059 -99.194605) (xy 379.071218 -99.28317) (xy 379.047611 -99.369989) (xy 379.016424 -99.454382)
			(xy 378.9779 -99.535689) (xy 378.932341 -99.613272) (xy 378.880104 -99.686525) (xy 378.821596 -99.754875)
			(xy 378.757277 -99.817787) (xy 378.68765 -99.874768) (xy 378.613259 -99.925372) (xy 378.534687 -99.969203)
			(xy 378.452548 -100.005919) (xy 378.367486 -100.035232) (xy 378.280166 -100.056912) (xy 378.191271 -100.07079)
			(xy 378.101498 -100.076757) (xy 378.011549 -100.074767) (xy 377.922128 -100.064834) (xy 377.833934 -100.047038)
			(xy 377.747659 -100.021517) (xy 377.663977 -99.98847) (xy 377.583542 -99.948157) (xy 377.506986 -99.900893)
			(xy 377.434906 -99.847048) (xy 377.367867 -99.787043) (xy 377.306394 -99.721348) (xy 377.250967 -99.650477)
			(xy 377.202021 -99.574984) (xy 377.159938 -99.495462) (xy 377.125049 -99.412531) (xy 377.097625 -99.326841)
			(xy 377.077882 -99.239063) (xy 377.065974 -99.149883) (xy 377.061994 -99.06) (xy 348.2086 -99.06)
			(xy 348.2086 -100.6602) (xy 355.356414 -107.808014) (xy 355.363268 -107.815409) (xy 355.37101 -107.834008)
			(xy 355.3714 -107.844082) (xy 355.3714 -111.879888) (xy 376.553995 -111.879888) (xy 376.55797 -111.769847)
			(xy 376.569876 -111.66038) (xy 376.589649 -111.552057) (xy 376.617187 -111.445443) (xy 376.652346 -111.341095)
			(xy 376.694943 -111.239555) (xy 376.744756 -111.141354) (xy 376.801525 -111.047003) (xy 376.864954 -110.956994)
			(xy 376.934713 -110.871797) (xy 377.010437 -110.791856) (xy 377.091733 -110.717587) (xy 377.178175 -110.649378)
			(xy 377.269314 -110.587584) (xy 377.364675 -110.532528) (xy 377.463759 -110.484496) (xy 377.566052 -110.443739)
			(xy 377.671018 -110.410469) (xy 377.778111 -110.384861) (xy 377.886774 -110.367047) (xy 377.996438 -110.35712)
			(xy 378.106533 -110.355132) (xy 378.216484 -110.361093) (xy 378.325718 -110.374973) (xy 378.433667 -110.396698)
			(xy 378.539766 -110.426157) (xy 378.643463 -110.463194) (xy 378.744217 -110.507617) (xy 378.841503 -110.559195)
			(xy 378.934813 -110.617658) (xy 379.023662 -110.682702) (xy 379.107586 -110.753987) (xy 379.186147 -110.831143)
			(xy 379.258936 -110.913766) (xy 379.325573 -111.001426) (xy 379.385711 -111.093666) (xy 379.439037 -111.190005)
			(xy 379.485272 -111.28994) (xy 379.524176 -111.392952) (xy 379.555545 -111.498502) (xy 379.579216 -111.60604)
			(xy 379.595065 -111.715006) (xy 379.603011 -111.824832) (xy 379.603508 -111.879888) (xy 396.111995 -111.879888)
			(xy 396.11597 -111.769847) (xy 396.127876 -111.66038) (xy 396.147649 -111.552057) (xy 396.175187 -111.445443)
			(xy 396.210346 -111.341095) (xy 396.252943 -111.239555) (xy 396.302756 -111.141354) (xy 396.359525 -111.047003)
			(xy 396.422954 -110.956994) (xy 396.492713 -110.871797) (xy 396.568437 -110.791856) (xy 396.649733 -110.717587)
			(xy 396.736175 -110.649378) (xy 396.827314 -110.587584) (xy 396.922675 -110.532528) (xy 397.021759 -110.484496)
			(xy 397.124052 -110.443739) (xy 397.229018 -110.410469) (xy 397.336111 -110.384861) (xy 397.444774 -110.367047)
			(xy 397.554438 -110.35712) (xy 397.664533 -110.355132) (xy 397.774484 -110.361093) (xy 397.883718 -110.374973)
			(xy 397.991667 -110.396698) (xy 398.097766 -110.426157) (xy 398.201463 -110.463194) (xy 398.302217 -110.507617)
			(xy 398.399503 -110.559195) (xy 398.492813 -110.617658) (xy 398.581662 -110.682702) (xy 398.665586 -110.753987)
			(xy 398.744147 -110.831143) (xy 398.816936 -110.913766) (xy 398.883573 -111.001426) (xy 398.943711 -111.093666)
			(xy 398.997037 -111.190005) (xy 399.043272 -111.28994) (xy 399.082176 -111.392952) (xy 399.113545 -111.498502)
			(xy 399.137216 -111.60604) (xy 399.153065 -111.715006) (xy 399.161011 -111.824832) (xy 399.161508 -111.879888)
			(xy 399.161011 -111.934944) (xy 399.153065 -112.04477) (xy 399.137216 -112.153736) (xy 399.113545 -112.261274)
			(xy 399.082176 -112.366824) (xy 399.043272 -112.469836) (xy 398.997037 -112.569771) (xy 398.943711 -112.66611)
			(xy 398.883573 -112.75835) (xy 398.816936 -112.84601) (xy 398.744147 -112.928633) (xy 398.665586 -113.005789)
			(xy 398.581662 -113.077074) (xy 398.492813 -113.142118) (xy 398.399503 -113.200581) (xy 398.302217 -113.252159)
			(xy 398.201463 -113.296582) (xy 398.097766 -113.333619) (xy 397.991667 -113.363078) (xy 397.883718 -113.384803)
			(xy 397.774484 -113.398683) (xy 397.664533 -113.404644) (xy 397.554438 -113.402656) (xy 397.444774 -113.392729)
			(xy 397.336111 -113.374915) (xy 397.229018 -113.349307) (xy 397.124052 -113.316037) (xy 397.021759 -113.27528)
			(xy 396.922675 -113.227248) (xy 396.827314 -113.172192) (xy 396.736175 -113.110398) (xy 396.649733 -113.042189)
			(xy 396.568437 -112.96792) (xy 396.492713 -112.887979) (xy 396.422954 -112.802782) (xy 396.359525 -112.712773)
			(xy 396.302756 -112.618422) (xy 396.252943 -112.520221) (xy 396.210346 -112.418681) (xy 396.175187 -112.314333)
			(xy 396.147649 -112.207719) (xy 396.127876 -112.099396) (xy 396.11597 -111.989929) (xy 396.111995 -111.879888)
			(xy 379.603508 -111.879888) (xy 379.603011 -111.934944) (xy 379.595065 -112.04477) (xy 379.579216 -112.153736)
			(xy 379.555545 -112.261274) (xy 379.524176 -112.366824) (xy 379.485272 -112.469836) (xy 379.439037 -112.569771)
			(xy 379.385711 -112.66611) (xy 379.325573 -112.75835) (xy 379.258936 -112.84601) (xy 379.186147 -112.928633)
			(xy 379.107586 -113.005789) (xy 379.023662 -113.077074) (xy 378.934813 -113.142118) (xy 378.841503 -113.200581)
			(xy 378.744217 -113.252159) (xy 378.643463 -113.296582) (xy 378.539766 -113.333619) (xy 378.433667 -113.363078)
			(xy 378.325718 -113.384803) (xy 378.216484 -113.398683) (xy 378.106533 -113.404644) (xy 377.996438 -113.402656)
			(xy 377.886774 -113.392729) (xy 377.778111 -113.374915) (xy 377.671018 -113.349307) (xy 377.566052 -113.316037)
			(xy 377.463759 -113.27528) (xy 377.364675 -113.227248) (xy 377.269314 -113.172192) (xy 377.178175 -113.110398)
			(xy 377.091733 -113.042189) (xy 377.010437 -112.96792) (xy 376.934713 -112.887979) (xy 376.864954 -112.802782)
			(xy 376.801525 -112.712773) (xy 376.744756 -112.618422) (xy 376.694943 -112.520221) (xy 376.652346 -112.418681)
			(xy 376.617187 -112.314333) (xy 376.589649 -112.207719) (xy 376.569876 -112.099396) (xy 376.55797 -111.989929)
			(xy 376.553995 -111.879888) (xy 355.3714 -111.879888) (xy 355.3714 -119.38) (xy 377.061994 -119.38)
			(xy 377.065974 -119.290117) (xy 377.077882 -119.200937) (xy 377.097625 -119.113159) (xy 377.125049 -119.027469)
			(xy 377.159938 -118.944538) (xy 377.202021 -118.865016) (xy 377.250967 -118.789523) (xy 377.306394 -118.718652)
			(xy 377.367867 -118.652957) (xy 377.434906 -118.592952) (xy 377.506986 -118.539107) (xy 377.583542 -118.491843)
			(xy 377.663977 -118.45153) (xy 377.747659 -118.418483) (xy 377.833934 -118.392962) (xy 377.922128 -118.375166)
			(xy 378.011549 -118.365233) (xy 378.101498 -118.363243) (xy 378.191271 -118.36921) (xy 378.280166 -118.383088)
			(xy 378.367486 -118.404768) (xy 378.452548 -118.434081) (xy 378.534687 -118.470797) (xy 378.613259 -118.514628)
			(xy 378.68765 -118.565232) (xy 378.757277 -118.622213) (xy 378.821596 -118.685125) (xy 378.880104 -118.753475)
			(xy 378.932341 -118.826728) (xy 378.9779 -118.904311) (xy 379.016424 -118.985618) (xy 379.047611 -119.070011)
			(xy 379.071218 -119.15683) (xy 379.087059 -119.245395) (xy 379.095011 -119.335014) (xy 379.095508 -119.38)
			(xy 396.619994 -119.38) (xy 396.623974 -119.290117) (xy 396.635882 -119.200937) (xy 396.655625 -119.113159)
			(xy 396.683049 -119.027469) (xy 396.717938 -118.944538) (xy 396.760021 -118.865016) (xy 396.808967 -118.789523)
			(xy 396.864394 -118.718652) (xy 396.925867 -118.652957) (xy 396.992906 -118.592952) (xy 397.064986 -118.539107)
			(xy 397.141542 -118.491843) (xy 397.221977 -118.45153) (xy 397.305659 -118.418483) (xy 397.391934 -118.392962)
			(xy 397.480128 -118.375166) (xy 397.569549 -118.365233) (xy 397.659498 -118.363243) (xy 397.749271 -118.36921)
			(xy 397.838166 -118.383088) (xy 397.925486 -118.404768) (xy 398.010548 -118.434081) (xy 398.092687 -118.470797)
			(xy 398.171259 -118.514628) (xy 398.24565 -118.565232) (xy 398.315277 -118.622213) (xy 398.379596 -118.685125)
			(xy 398.438104 -118.753475) (xy 398.490341 -118.826728) (xy 398.5359 -118.904311) (xy 398.574424 -118.985618)
			(xy 398.605611 -119.070011) (xy 398.629218 -119.15683) (xy 398.645059 -119.245395) (xy 398.653011 -119.335014)
			(xy 398.653508 -119.38) (xy 398.653011 -119.424986) (xy 398.645059 -119.514605) (xy 398.629218 -119.60317)
			(xy 398.605611 -119.689989) (xy 398.574424 -119.774382) (xy 398.5359 -119.855689) (xy 398.490341 -119.933272)
			(xy 398.438104 -120.006525) (xy 398.379596 -120.074875) (xy 398.315277 -120.137787) (xy 398.24565 -120.194768)
			(xy 398.171259 -120.245372) (xy 398.092687 -120.289203) (xy 398.010548 -120.325919) (xy 397.925486 -120.355232)
			(xy 397.838166 -120.376912) (xy 397.749271 -120.39079) (xy 397.659498 -120.396757) (xy 397.569549 -120.394767)
			(xy 397.480128 -120.384834) (xy 397.391934 -120.367038) (xy 397.305659 -120.341517) (xy 397.221977 -120.30847)
			(xy 397.141542 -120.268157) (xy 397.064986 -120.220893) (xy 396.992906 -120.167048) (xy 396.925867 -120.107043)
			(xy 396.864394 -120.041348) (xy 396.808967 -119.970477) (xy 396.760021 -119.894984) (xy 396.717938 -119.815462)
			(xy 396.683049 -119.732531) (xy 396.655625 -119.646841) (xy 396.635882 -119.559063) (xy 396.623974 -119.469883)
			(xy 396.619994 -119.38) (xy 379.095508 -119.38) (xy 379.095011 -119.424986) (xy 379.087059 -119.514605)
			(xy 379.071218 -119.60317) (xy 379.047611 -119.689989) (xy 379.016424 -119.774382) (xy 378.9779 -119.855689)
			(xy 378.932341 -119.933272) (xy 378.880104 -120.006525) (xy 378.821596 -120.074875) (xy 378.757277 -120.137787)
			(xy 378.68765 -120.194768) (xy 378.613259 -120.245372) (xy 378.534687 -120.289203) (xy 378.452548 -120.325919)
			(xy 378.367486 -120.355232) (xy 378.280166 -120.376912) (xy 378.191271 -120.39079) (xy 378.101498 -120.396757)
			(xy 378.011549 -120.394767) (xy 377.922128 -120.384834) (xy 377.833934 -120.367038) (xy 377.747659 -120.341517)
			(xy 377.663977 -120.30847) (xy 377.583542 -120.268157) (xy 377.506986 -120.220893) (xy 377.434906 -120.167048)
			(xy 377.367867 -120.107043) (xy 377.306394 -120.041348) (xy 377.250967 -119.970477) (xy 377.202021 -119.894984)
			(xy 377.159938 -119.815462) (xy 377.125049 -119.732531) (xy 377.097625 -119.646841) (xy 377.077882 -119.559063)
			(xy 377.065974 -119.469883) (xy 377.061994 -119.38) (xy 355.3714 -119.38) (xy 355.3714 -132.199888)
			(xy 376.553995 -132.199888) (xy 376.55797 -132.089847) (xy 376.569876 -131.98038) (xy 376.589649 -131.872057)
			(xy 376.617187 -131.765443) (xy 376.652346 -131.661095) (xy 376.694943 -131.559555) (xy 376.744756 -131.461354)
			(xy 376.801525 -131.367003) (xy 376.864954 -131.276994) (xy 376.934713 -131.191797) (xy 377.010437 -131.111856)
			(xy 377.091733 -131.037587) (xy 377.178175 -130.969378) (xy 377.269314 -130.907584) (xy 377.364675 -130.852528)
			(xy 377.463759 -130.804496) (xy 377.566052 -130.763739) (xy 377.671018 -130.730469) (xy 377.778111 -130.704861)
			(xy 377.886774 -130.687047) (xy 377.996438 -130.67712) (xy 378.106533 -130.675132) (xy 378.216484 -130.681093)
			(xy 378.325718 -130.694973) (xy 378.433667 -130.716698) (xy 378.539766 -130.746157) (xy 378.643463 -130.783194)
			(xy 378.744217 -130.827617) (xy 378.841503 -130.879195) (xy 378.934813 -130.937658) (xy 379.023662 -131.002702)
			(xy 379.107586 -131.073987) (xy 379.186147 -131.151143) (xy 379.258936 -131.233766) (xy 379.325573 -131.321426)
			(xy 379.385711 -131.413666) (xy 379.439037 -131.510005) (xy 379.485272 -131.60994) (xy 379.524176 -131.712952)
			(xy 379.555545 -131.818502) (xy 379.579216 -131.92604) (xy 379.595065 -132.035006) (xy 379.603011 -132.144832)
			(xy 379.603508 -132.199888) (xy 396.111995 -132.199888) (xy 396.11597 -132.089847) (xy 396.127876 -131.98038)
			(xy 396.147649 -131.872057) (xy 396.175187 -131.765443) (xy 396.210346 -131.661095) (xy 396.252943 -131.559555)
			(xy 396.302756 -131.461354) (xy 396.359525 -131.367003) (xy 396.422954 -131.276994) (xy 396.492713 -131.191797)
			(xy 396.568437 -131.111856) (xy 396.649733 -131.037587) (xy 396.736175 -130.969378) (xy 396.827314 -130.907584)
			(xy 396.922675 -130.852528) (xy 397.021759 -130.804496) (xy 397.124052 -130.763739) (xy 397.229018 -130.730469)
			(xy 397.336111 -130.704861) (xy 397.444774 -130.687047) (xy 397.554438 -130.67712) (xy 397.664533 -130.675132)
			(xy 397.774484 -130.681093) (xy 397.883718 -130.694973) (xy 397.991667 -130.716698) (xy 398.097766 -130.746157)
			(xy 398.201463 -130.783194) (xy 398.302217 -130.827617) (xy 398.399503 -130.879195) (xy 398.492813 -130.937658)
			(xy 398.581662 -131.002702) (xy 398.665586 -131.073987) (xy 398.744147 -131.151143) (xy 398.816936 -131.233766)
			(xy 398.883573 -131.321426) (xy 398.943711 -131.413666) (xy 398.997037 -131.510005) (xy 399.043272 -131.60994)
			(xy 399.082176 -131.712952) (xy 399.113545 -131.818502) (xy 399.137216 -131.92604) (xy 399.153065 -132.035006)
			(xy 399.161011 -132.144832) (xy 399.161508 -132.199888) (xy 399.161011 -132.254944) (xy 399.153065 -132.36477)
			(xy 399.137216 -132.473736) (xy 399.113545 -132.581274) (xy 399.082176 -132.686824) (xy 399.043272 -132.789836)
			(xy 398.997037 -132.889771) (xy 398.943711 -132.98611) (xy 398.883573 -133.07835) (xy 398.816936 -133.16601)
			(xy 398.744147 -133.248633) (xy 398.665586 -133.325789) (xy 398.581662 -133.397074) (xy 398.492813 -133.462118)
			(xy 398.399503 -133.520581) (xy 398.302217 -133.572159) (xy 398.201463 -133.616582) (xy 398.097766 -133.653619)
			(xy 397.991667 -133.683078) (xy 397.883718 -133.704803) (xy 397.774484 -133.718683) (xy 397.664533 -133.724644)
			(xy 397.554438 -133.722656) (xy 397.444774 -133.712729) (xy 397.336111 -133.694915) (xy 397.229018 -133.669307)
			(xy 397.124052 -133.636037) (xy 397.021759 -133.59528) (xy 396.922675 -133.547248) (xy 396.827314 -133.492192)
			(xy 396.736175 -133.430398) (xy 396.649733 -133.362189) (xy 396.568437 -133.28792) (xy 396.492713 -133.207979)
			(xy 396.422954 -133.122782) (xy 396.359525 -133.032773) (xy 396.302756 -132.938422) (xy 396.252943 -132.840221)
			(xy 396.210346 -132.738681) (xy 396.175187 -132.634333) (xy 396.147649 -132.527719) (xy 396.127876 -132.419396)
			(xy 396.11597 -132.309929) (xy 396.111995 -132.199888) (xy 379.603508 -132.199888) (xy 379.603011 -132.254944)
			(xy 379.595065 -132.36477) (xy 379.579216 -132.473736) (xy 379.555545 -132.581274) (xy 379.524176 -132.686824)
			(xy 379.485272 -132.789836) (xy 379.439037 -132.889771) (xy 379.385711 -132.98611) (xy 379.325573 -133.07835)
			(xy 379.258936 -133.16601) (xy 379.186147 -133.248633) (xy 379.107586 -133.325789) (xy 379.023662 -133.397074)
			(xy 378.934813 -133.462118) (xy 378.841503 -133.520581) (xy 378.744217 -133.572159) (xy 378.643463 -133.616582)
			(xy 378.539766 -133.653619) (xy 378.433667 -133.683078) (xy 378.325718 -133.704803) (xy 378.216484 -133.718683)
			(xy 378.106533 -133.724644) (xy 377.996438 -133.722656) (xy 377.886774 -133.712729) (xy 377.778111 -133.694915)
			(xy 377.671018 -133.669307) (xy 377.566052 -133.636037) (xy 377.463759 -133.59528) (xy 377.364675 -133.547248)
			(xy 377.269314 -133.492192) (xy 377.178175 -133.430398) (xy 377.091733 -133.362189) (xy 377.010437 -133.28792)
			(xy 376.934713 -133.207979) (xy 376.864954 -133.122782) (xy 376.801525 -133.032773) (xy 376.744756 -132.938422)
			(xy 376.694943 -132.840221) (xy 376.652346 -132.738681) (xy 376.617187 -132.634333) (xy 376.589649 -132.527719)
			(xy 376.569876 -132.419396) (xy 376.55797 -132.309929) (xy 376.553995 -132.199888) (xy 355.3714 -132.199888)
			(xy 355.3714 -135.12546) (xy 355.371834 -135.135525) (xy 355.379564 -135.154114) (xy 355.386386 -135.161528)
			(xy 355.876352 -135.651494) (xy 355.883753 -135.658333) (xy 355.902351 -135.666049) (xy 355.91242 -135.66648)
			(xy 362.998004 -135.66648) (xy 363.008074 -135.666903) (xy 363.02668 -135.674616) (xy 363.034072 -135.681466)
			(xy 366.632998 -139.280392) (xy 366.639846 -139.28779) (xy 366.647584 -139.306388) (xy 366.647984 -139.31646)
			(xy 366.647984 -139.7) (xy 377.061994 -139.7) (xy 377.065974 -139.610117) (xy 377.077882 -139.520937)
			(xy 377.097625 -139.433159) (xy 377.125049 -139.347469) (xy 377.159938 -139.264538) (xy 377.202021 -139.185016)
			(xy 377.250967 -139.109523) (xy 377.306394 -139.038652) (xy 377.367867 -138.972957) (xy 377.434906 -138.912952)
			(xy 377.506986 -138.859107) (xy 377.583542 -138.811843) (xy 377.663977 -138.77153) (xy 377.747659 -138.738483)
			(xy 377.833934 -138.712962) (xy 377.922128 -138.695166) (xy 378.011549 -138.685233) (xy 378.101498 -138.683243)
			(xy 378.191271 -138.68921) (xy 378.280166 -138.703088) (xy 378.367486 -138.724768) (xy 378.452548 -138.754081)
			(xy 378.534687 -138.790797) (xy 378.613259 -138.834628) (xy 378.68765 -138.885232) (xy 378.757277 -138.942213)
			(xy 378.821596 -139.005125) (xy 378.880104 -139.073475) (xy 378.932341 -139.146728) (xy 378.9779 -139.224311)
			(xy 379.016424 -139.305618) (xy 379.047611 -139.390011) (xy 379.071218 -139.47683) (xy 379.087059 -139.565395)
			(xy 379.095011 -139.655014) (xy 379.095508 -139.7) (xy 396.619994 -139.7) (xy 396.623974 -139.610117)
			(xy 396.635882 -139.520937) (xy 396.655625 -139.433159) (xy 396.683049 -139.347469) (xy 396.717938 -139.264538)
			(xy 396.760021 -139.185016) (xy 396.808967 -139.109523) (xy 396.864394 -139.038652) (xy 396.925867 -138.972957)
			(xy 396.992906 -138.912952) (xy 397.064986 -138.859107) (xy 397.141542 -138.811843) (xy 397.221977 -138.77153)
			(xy 397.305659 -138.738483) (xy 397.391934 -138.712962) (xy 397.480128 -138.695166) (xy 397.569549 -138.685233)
			(xy 397.659498 -138.683243) (xy 397.749271 -138.68921) (xy 397.838166 -138.703088) (xy 397.925486 -138.724768)
			(xy 398.010548 -138.754081) (xy 398.092687 -138.790797) (xy 398.171259 -138.834628) (xy 398.24565 -138.885232)
			(xy 398.315277 -138.942213) (xy 398.379596 -139.005125) (xy 398.438104 -139.073475) (xy 398.490341 -139.146728)
			(xy 398.5359 -139.224311) (xy 398.574424 -139.305618) (xy 398.605611 -139.390011) (xy 398.629218 -139.47683)
			(xy 398.645059 -139.565395) (xy 398.653011 -139.655014) (xy 398.653508 -139.7) (xy 398.653011 -139.744986)
			(xy 398.645059 -139.834605) (xy 398.629218 -139.92317) (xy 398.605611 -140.009989) (xy 398.574424 -140.094382)
			(xy 398.5359 -140.175689) (xy 398.490341 -140.253272) (xy 398.438104 -140.326525) (xy 398.379596 -140.394875)
			(xy 398.315277 -140.457787) (xy 398.24565 -140.514768) (xy 398.171259 -140.565372) (xy 398.092687 -140.609203)
			(xy 398.010548 -140.645919) (xy 397.925486 -140.675232) (xy 397.838166 -140.696912) (xy 397.749271 -140.71079)
			(xy 397.659498 -140.716757) (xy 397.569549 -140.714767) (xy 397.480128 -140.704834) (xy 397.391934 -140.687038)
			(xy 397.305659 -140.661517) (xy 397.221977 -140.62847) (xy 397.141542 -140.588157) (xy 397.064986 -140.540893)
			(xy 396.992906 -140.487048) (xy 396.925867 -140.427043) (xy 396.864394 -140.361348) (xy 396.808967 -140.290477)
			(xy 396.760021 -140.214984) (xy 396.717938 -140.135462) (xy 396.683049 -140.052531) (xy 396.655625 -139.966841)
			(xy 396.635882 -139.879063) (xy 396.623974 -139.789883) (xy 396.619994 -139.7) (xy 379.095508 -139.7)
			(xy 379.095011 -139.744986) (xy 379.087059 -139.834605) (xy 379.071218 -139.92317) (xy 379.047611 -140.009989)
			(xy 379.016424 -140.094382) (xy 378.9779 -140.175689) (xy 378.932341 -140.253272) (xy 378.880104 -140.326525)
			(xy 378.821596 -140.394875) (xy 378.757277 -140.457787) (xy 378.68765 -140.514768) (xy 378.613259 -140.565372)
			(xy 378.534687 -140.609203) (xy 378.452548 -140.645919) (xy 378.367486 -140.675232) (xy 378.280166 -140.696912)
			(xy 378.191271 -140.71079) (xy 378.101498 -140.716757) (xy 378.011549 -140.714767) (xy 377.922128 -140.704834)
			(xy 377.833934 -140.687038) (xy 377.747659 -140.661517) (xy 377.663977 -140.62847) (xy 377.583542 -140.588157)
			(xy 377.506986 -140.540893) (xy 377.434906 -140.487048) (xy 377.367867 -140.427043) (xy 377.306394 -140.361348)
			(xy 377.250967 -140.290477) (xy 377.202021 -140.214984) (xy 377.159938 -140.135462) (xy 377.125049 -140.052531)
			(xy 377.097625 -139.966841) (xy 377.077882 -139.879063) (xy 377.065974 -139.789883) (xy 377.061994 -139.7)
			(xy 366.647984 -139.7) (xy 366.647984 -150.643844) (xy 366.647552 -150.65391) (xy 366.639825 -150.672502)
			(xy 366.632998 -150.679912) (xy 362.563156 -154.749754) (xy 362.556312 -154.757153) (xy 362.548588 -154.775752)
			(xy 362.54817 -154.785822) (xy 362.54817 -159.684424) (xy 371.51385 -159.684424) (xy 371.51385 -159.575796)
			(xy 371.521779 -159.467458) (xy 371.537596 -159.359987) (xy 371.561215 -159.253958) (xy 371.592511 -159.149936)
			(xy 371.631316 -159.048475) (xy 371.677424 -158.950118) (xy 371.730588 -158.855389) (xy 371.790526 -158.764794)
			(xy 371.856916 -158.678815) (xy 371.929406 -158.597912) (xy 372.007607 -158.522516) (xy 372.091104 -158.45303)
			(xy 372.17945 -158.389823) (xy 372.272174 -158.333235) (xy 372.368782 -158.283565) (xy 372.468757 -158.24108)
			(xy 372.571567 -158.206007) (xy 372.676663 -158.178531) (xy 372.783484 -158.1588) (xy 372.89146 -158.146919)
			(xy 373.000016 -158.142952) (xy 373.108572 -158.146919) (xy 373.216548 -158.1588) (xy 373.323369 -158.178531)
			(xy 373.428465 -158.206007) (xy 373.531275 -158.24108) (xy 373.63125 -158.283565) (xy 373.727858 -158.333235)
			(xy 373.820582 -158.389823) (xy 373.908928 -158.45303) (xy 373.992425 -158.522516) (xy 374.070626 -158.597912)
			(xy 374.143116 -158.678815) (xy 374.209506 -158.764794) (xy 374.269444 -158.855389) (xy 374.322608 -158.950118)
			(xy 374.368716 -159.048475) (xy 374.407521 -159.149936) (xy 374.438817 -159.253958) (xy 374.462436 -159.359987)
			(xy 374.478253 -159.467458) (xy 374.486182 -159.575796) (xy 374.486678 -159.63011) (xy 374.486182 -159.684424)
			(xy 374.478253 -159.792762) (xy 374.462436 -159.900233) (xy 374.438817 -160.006262) (xy 374.407521 -160.110284)
			(xy 374.368716 -160.211745) (xy 374.322608 -160.310102) (xy 374.269444 -160.404831) (xy 374.209506 -160.495426)
			(xy 374.143116 -160.581405) (xy 374.070626 -160.662308) (xy 373.992425 -160.737704) (xy 373.908928 -160.80719)
			(xy 373.820582 -160.870397) (xy 373.727858 -160.926985) (xy 373.63125 -160.976655) (xy 373.531275 -161.01914)
			(xy 373.428465 -161.054213) (xy 373.323369 -161.081689) (xy 373.216548 -161.10142) (xy 373.108572 -161.113301)
			(xy 373.000016 -161.117268) (xy 372.89146 -161.113301) (xy 372.783484 -161.10142) (xy 372.676663 -161.081689)
			(xy 372.571567 -161.054213) (xy 372.468757 -161.01914) (xy 372.368782 -160.976655) (xy 372.272174 -160.926985)
			(xy 372.17945 -160.870397) (xy 372.091104 -160.80719) (xy 372.007607 -160.737704) (xy 371.929406 -160.662308)
			(xy 371.856916 -160.581405) (xy 371.790526 -160.495426) (xy 371.730588 -160.404831) (xy 371.677424 -160.310102)
			(xy 371.631316 -160.211745) (xy 371.592511 -160.110284) (xy 371.561215 -160.006262) (xy 371.537596 -159.900233)
			(xy 371.521779 -159.792762) (xy 371.51385 -159.684424) (xy 362.54817 -159.684424) (xy 362.54817 -161.484564)
			(xy 362.548673 -161.494616) (xy 362.55639 -161.513181) (xy 362.563156 -161.520632) (xy 362.698538 -161.656014)
			(xy 362.705934 -161.662864) (xy 362.724534 -161.670598) (xy 362.734606 -161.671) (xy 385.865116 -161.671)
			(xy 385.874275 -161.670568) (xy 385.891406 -161.664064) (xy 385.905187 -161.651987) (xy 385.90982 -161.644076)
			(xy 385.935868 -161.596174) (xy 385.994105 -161.503979) (xy 386.059053 -161.416382) (xy 386.130352 -161.333872)
			(xy 386.207603 -161.256906) (xy 386.290378 -161.185914) (xy 386.378214 -161.121291) (xy 386.470625 -161.063397)
			(xy 386.567094 -161.012553) (xy 386.667086 -160.969042) (xy 386.770043 -160.933108) (xy 386.875393 -160.90495)
			(xy 386.982548 -160.884724) (xy 387.090914 -160.872543) (xy 387.199886 -160.868475) (xy 387.308858 -160.872543)
			(xy 387.417224 -160.884724) (xy 387.524379 -160.90495) (xy 387.629729 -160.933108) (xy 387.732686 -160.969042)
			(xy 387.832678 -161.012553) (xy 387.929147 -161.063397) (xy 388.021558 -161.121291) (xy 388.109394 -161.185914)
			(xy 388.192169 -161.256906) (xy 388.26942 -161.333872) (xy 388.340719 -161.416382) (xy 388.405667 -161.503979)
			(xy 388.463904 -161.596174) (xy 388.489952 -161.644076) (xy 388.494582 -161.651999) (xy 388.508332 -161.664131)
			(xy 388.525487 -161.670606) (xy 388.534656 -161.671) (xy 396.345918 -161.671) (xy 396.355987 -161.671427)
			(xy 396.374586 -161.679146) (xy 396.381986 -161.685986) (xy 396.733014 -162.037014) (xy 396.739868 -162.044409)
			(xy 396.74761 -162.063008) (xy 396.748 -162.073082) (xy 396.748 -168.899078) (xy 396.75562 -168.917874)
			(xy 396.762986 -168.924986) (xy 397.368014 -169.530014) (xy 397.375409 -169.536868) (xy 397.394008 -169.54461)
			(xy 397.404082 -169.545) (xy 400.801078 -169.545)
		)
		(stroke
			(width 0)
			(type solid)
		)
		(fill yes)
		(layer "In7.Cu")
		(net "P52V_HS1")
	)
	(gr_poly
		(pts
			(xy 37.382958 -169.545) (xy 37.393023 -169.544566) (xy 37.411613 -169.536837) (xy 37.419026 -169.530014)
			(xy 37.62883 -169.32021) (xy 37.635686 -169.312815) (xy 37.643435 -169.294217) (xy 37.643816 -169.284142)
			(xy 37.643816 -151.221186) (xy 37.644242 -151.211117) (xy 37.651962 -151.192518) (xy 37.658802 -151.185118)
			(xy 38.197282 -150.646638) (xy 38.204683 -150.6398) (xy 38.223282 -150.63209) (xy 38.23335 -150.631652)
			(xy 47.243746 -150.631652) (xy 47.253811 -150.632085) (xy 47.272399 -150.639817) (xy 47.279814 -150.646638)
			(xy 47.729648 -151.096472) (xy 47.736489 -151.103872) (xy 47.744205 -151.122471) (xy 47.744634 -151.13254)
			(xy 47.744634 -159.684424) (xy 71.513942 -159.684424) (xy 71.513942 -159.575796) (xy 71.521871 -159.467458)
			(xy 71.537688 -159.359987) (xy 71.561307 -159.253958) (xy 71.592603 -159.149936) (xy 71.631408 -159.048475)
			(xy 71.677516 -158.950118) (xy 71.73068 -158.855389) (xy 71.790618 -158.764794) (xy 71.857008 -158.678815)
			(xy 71.929498 -158.597912) (xy 72.007699 -158.522516) (xy 72.091196 -158.45303) (xy 72.179542 -158.389823)
			(xy 72.272266 -158.333235) (xy 72.368874 -158.283565) (xy 72.468849 -158.24108) (xy 72.571659 -158.206007)
			(xy 72.676755 -158.178531) (xy 72.783576 -158.1588) (xy 72.891552 -158.146919) (xy 73.000108 -158.142952)
			(xy 73.108664 -158.146919) (xy 73.21664 -158.1588) (xy 73.323461 -158.178531) (xy 73.428557 -158.206007)
			(xy 73.531367 -158.24108) (xy 73.631342 -158.283565) (xy 73.72795 -158.333235) (xy 73.820674 -158.389823)
			(xy 73.90902 -158.45303) (xy 73.992517 -158.522516) (xy 74.070718 -158.597912) (xy 74.143208 -158.678815)
			(xy 74.209598 -158.764794) (xy 74.269536 -158.855389) (xy 74.3227 -158.950118) (xy 74.368808 -159.048475)
			(xy 74.407613 -159.149936) (xy 74.438909 -159.253958) (xy 74.462528 -159.359987) (xy 74.478345 -159.467458)
			(xy 74.486274 -159.575796) (xy 74.48677 -159.63011) (xy 74.486274 -159.684424) (xy 74.478345 -159.792762)
			(xy 74.462528 -159.900233) (xy 74.438909 -160.006262) (xy 74.407613 -160.110284) (xy 74.368808 -160.211745)
			(xy 74.3227 -160.310102) (xy 74.269536 -160.404831) (xy 74.209598 -160.495426) (xy 74.143208 -160.581405)
			(xy 74.070718 -160.662308) (xy 73.992517 -160.737704) (xy 73.90902 -160.80719) (xy 73.820674 -160.870397)
			(xy 73.72795 -160.926985) (xy 73.631342 -160.976655) (xy 73.531367 -161.01914) (xy 73.428557 -161.054213)
			(xy 73.323461 -161.081689) (xy 73.21664 -161.10142) (xy 73.108664 -161.113301) (xy 73.000108 -161.117268)
			(xy 72.891552 -161.113301) (xy 72.783576 -161.10142) (xy 72.676755 -161.081689) (xy 72.571659 -161.054213)
			(xy 72.468849 -161.01914) (xy 72.368874 -160.976655) (xy 72.272266 -160.926985) (xy 72.179542 -160.870397)
			(xy 72.091196 -160.80719) (xy 72.007699 -160.737704) (xy 71.929498 -160.662308) (xy 71.857008 -160.581405)
			(xy 71.790618 -160.495426) (xy 71.73068 -160.404831) (xy 71.677516 -160.310102) (xy 71.631408 -160.211745)
			(xy 71.592603 -160.110284) (xy 71.561307 -160.006262) (xy 71.537688 -159.900233) (xy 71.521871 -159.792762)
			(xy 71.513942 -159.684424) (xy 47.744634 -159.684424) (xy 47.744634 -161.007298) (xy 47.745057 -161.017368)
			(xy 47.752775 -161.03597) (xy 47.75962 -161.043366) (xy 48.372268 -161.656014) (xy 48.379666 -161.662859)
			(xy 48.398265 -161.670582) (xy 48.408336 -161.671) (xy 51.465226 -161.671) (xy 51.474385 -161.670566)
			(xy 51.491513 -161.66406) (xy 51.505291 -161.651983) (xy 51.50993 -161.644076) (xy 51.535978 -161.596174)
			(xy 51.594215 -161.503979) (xy 51.659163 -161.416382) (xy 51.730462 -161.333872) (xy 51.807713 -161.256906)
			(xy 51.890488 -161.185914) (xy 51.978324 -161.121291) (xy 52.070735 -161.063397) (xy 52.167204 -161.012553)
			(xy 52.267196 -160.969042) (xy 52.370153 -160.933108) (xy 52.475503 -160.90495) (xy 52.582658 -160.884724)
			(xy 52.691024 -160.872543) (xy 52.799996 -160.868475) (xy 52.908968 -160.872543) (xy 53.017334 -160.884724)
			(xy 53.124489 -160.90495) (xy 53.229839 -160.933108) (xy 53.332796 -160.969042) (xy 53.432788 -161.012553)
			(xy 53.529257 -161.063397) (xy 53.621668 -161.121291) (xy 53.709504 -161.185914) (xy 53.792279 -161.256906)
			(xy 53.86953 -161.333872) (xy 53.940829 -161.416382) (xy 54.005777 -161.503979) (xy 54.064014 -161.596174)
			(xy 54.090062 -161.644076) (xy 54.094693 -161.651998) (xy 54.108443 -161.664126) (xy 54.125598 -161.670598)
			(xy 54.134766 -161.671) (xy 77.243686 -161.671) (xy 77.253749 -161.670561) (xy 77.272331 -161.662825)
			(xy 77.279754 -161.656014) (xy 77.83449 -161.101278) (xy 77.841334 -161.093879) (xy 77.849062 -161.075281)
			(xy 77.849476 -161.06521) (xy 77.849476 -154.975814) (xy 77.849037 -154.965751) (xy 77.841298 -154.947172)
			(xy 77.83449 -154.939746) (xy 73.201276 -150.306532) (xy 73.194432 -150.299133) (xy 73.186711 -150.280534)
			(xy 73.18629 -150.270464) (xy 73.18629 -139.098274) (xy 73.186717 -139.088206) (xy 73.194437 -139.069607)
			(xy 73.201276 -139.062206) (xy 76.420218 -135.843264) (xy 76.427615 -135.836414) (xy 76.446213 -135.828676)
			(xy 76.456286 -135.828278) (xy 83.667854 -135.828278) (xy 83.677919 -135.827844) (xy 83.696508 -135.820114)
			(xy 83.703922 -135.813292) (xy 85.075014 -134.4422) (xy 85.08187 -134.434806) (xy 85.089618 -134.416207)
			(xy 85.09 -134.406132) (xy 85.09 -106.064558) (xy 85.090431 -106.054491) (xy 85.098156 -106.035898)
			(xy 85.104986 -106.02849) (xy 91.283028 -99.850448) (xy 91.290426 -99.843601) (xy 91.309024 -99.835869)
			(xy 91.319096 -99.835462) (xy 110.112556 -99.835462) (xy 112.230408 -97.71761) (xy 112.230408 -86.467696)
			(xy 107.5944 -81.831688) (xy 107.5944 -75.08621) (xy 108.066332 -74.614278) (xy 108.073728 -74.607428)
			(xy 108.092327 -74.599693) (xy 108.1024 -74.599292) (xy 118.730014 -74.599292) (xy 118.740083 -74.598866)
			(xy 118.758683 -74.591147) (xy 118.766082 -74.584306) (xy 118.942866 -74.407522) (xy 118.949704 -74.400121)
			(xy 118.957415 -74.381522) (xy 118.957852 -74.371454) (xy 118.957852 -69.994272) (xy 118.957422 -69.984205)
			(xy 118.949695 -69.965613) (xy 118.942866 -69.958204) (xy 118.697756 -69.713094) (xy 118.690355 -69.706255)
			(xy 118.671757 -69.698538) (xy 118.661688 -69.698108) (xy 108.430822 -69.698108) (xy 108.420758 -69.697671)
			(xy 108.402173 -69.689938) (xy 108.394754 -69.683122) (xy 107.5944 -68.882768) (xy 107.5944 -63.793116)
			(xy 108.050838 -63.336678) (xy 108.058235 -63.329829) (xy 108.076834 -63.322096) (xy 108.086906 -63.321692)
			(xy 118.730014 -63.321692) (xy 118.740083 -63.321266) (xy 118.758683 -63.313547) (xy 118.766082 -63.306706)
			(xy 118.942866 -63.129922) (xy 118.949704 -63.122521) (xy 118.957415 -63.103922) (xy 118.957852 -63.093854)
			(xy 118.957852 -58.716672) (xy 118.957422 -58.706605) (xy 118.949695 -58.688013) (xy 118.942866 -58.680604)
			(xy 118.697756 -58.435494) (xy 118.690355 -58.428655) (xy 118.671757 -58.420938) (xy 118.661688 -58.420508)
			(xy 108.288582 -58.420508) (xy 108.278513 -58.420082) (xy 108.259912 -58.412364) (xy 108.252514 -58.405522)
			(xy 107.5944 -57.747408) (xy 107.5944 -52.339494) (xy 107.874816 -52.059078) (xy 107.882212 -52.052226)
			(xy 107.900811 -52.044485) (xy 107.910884 -52.044092) (xy 118.730014 -52.044092) (xy 118.740083 -52.043666)
			(xy 118.758683 -52.035947) (xy 118.766082 -52.029106) (xy 118.942866 -51.852322) (xy 118.949704 -51.844921)
			(xy 118.957415 -51.826322) (xy 118.957852 -51.816254) (xy 118.957852 -47.439072) (xy 118.957422 -47.429005)
			(xy 118.949695 -47.410413) (xy 118.942866 -47.403004) (xy 118.697756 -47.157894) (xy 118.690355 -47.151055)
			(xy 118.671757 -47.143338) (xy 118.661688 -47.142908) (xy 108.755942 -47.142908) (xy 108.745876 -47.142475)
			(xy 108.727286 -47.134746) (xy 108.719874 -47.127922) (xy 107.5944 -46.002448) (xy 107.5944 -41.5798)
			(xy 108.392722 -40.781478) (xy 118.73611 -40.781478) (xy 118.957852 -40.559736) (xy 118.957852 -36.14039)
			(xy 118.68277 -35.865308) (xy 108.483908 -35.865308) (xy 108.0516 -35.433) (xy 108.0516 -29.9212)
			(xy 108.483908 -29.488892) (xy 118.751096 -29.488892) (xy 118.957852 -29.282136) (xy 118.957852 -24.862536)
			(xy 118.683024 -24.587708) (xy 108.560108 -24.587708) (xy 108.0516 -24.0792) (xy 108.0516 -18.542)
			(xy 108.4072 -18.1864) (xy 118.775988 -18.1864) (xy 118.957852 -18.004536) (xy 118.957852 -13.58519)
			(xy 118.68277 -13.310108) (xy 101.467666 -13.310108) (xy 99.619054 -15.15872) (xy 99.608988 -15.159152)
			(xy 99.590397 -15.16688) (xy 99.582986 -15.173706) (xy 90.508074 -24.248618) (xy 90.500678 -24.255469)
			(xy 90.482079 -24.263207) (xy 90.472006 -24.263604) (xy 81.92008 -24.263604) (xy 81.910012 -24.264031)
			(xy 81.891413 -24.271751) (xy 81.884012 -24.27859) (xy 77.40142 -28.761182) (xy 77.394018 -28.768018)
			(xy 77.37542 -28.775726) (xy 77.365352 -28.776168) (xy 58.691272 -28.776168) (xy 58.681203 -28.776595)
			(xy 58.662603 -28.784313) (xy 58.655204 -28.791154) (xy 55.15229 -32.294068) (xy 42.022268 -32.294068)
			(xy 34.057082 -40.259) (xy 34.050227 -40.266395) (xy 34.042479 -40.284994) (xy 34.042096 -40.295068)
			(xy 34.042096 -45.787748) (xy 102.768396 -45.787748) (xy 102.768396 -45.703052) (xy 102.776447 -45.618738)
			(xy 102.792476 -45.535572) (xy 102.816337 -45.454305) (xy 102.847816 -45.375675) (xy 102.886627 -45.300394)
			(xy 102.932417 -45.229142) (xy 102.984773 -45.162566) (xy 103.043221 -45.101268) (xy 103.107231 -45.045803)
			(xy 103.176223 -44.996674) (xy 103.249573 -44.954325) (xy 103.326616 -44.919141) (xy 103.406655 -44.891439)
			(xy 103.488964 -44.871471) (xy 103.572799 -44.859418) (xy 103.6574 -44.855388) (xy 103.742001 -44.859418)
			(xy 103.825836 -44.871471) (xy 103.908145 -44.891439) (xy 103.988184 -44.919141) (xy 104.065227 -44.954325)
			(xy 104.138577 -44.996674) (xy 104.207569 -45.045803) (xy 104.271579 -45.101268) (xy 104.330027 -45.162566)
			(xy 104.382383 -45.229142) (xy 104.428173 -45.300394) (xy 104.466984 -45.375675) (xy 104.498463 -45.454305)
			(xy 104.522324 -45.535572) (xy 104.538353 -45.618738) (xy 104.546404 -45.703052) (xy 104.546908 -45.7454)
			(xy 104.546404 -45.787748) (xy 104.538353 -45.872062) (xy 104.522324 -45.955228) (xy 104.498463 -46.036495)
			(xy 104.466984 -46.115125) (xy 104.428173 -46.190406) (xy 104.382383 -46.261658) (xy 104.330027 -46.328234)
			(xy 104.271579 -46.389532) (xy 104.207569 -46.444997) (xy 104.138577 -46.494126) (xy 104.065227 -46.536475)
			(xy 103.988184 -46.571659) (xy 103.908145 -46.599361) (xy 103.825836 -46.619329) (xy 103.742001 -46.631382)
			(xy 103.6574 -46.635413) (xy 103.572799 -46.631382) (xy 103.488964 -46.619329) (xy 103.406655 -46.599361)
			(xy 103.326616 -46.571659) (xy 103.249573 -46.536475) (xy 103.176223 -46.494126) (xy 103.107231 -46.444997)
			(xy 103.043221 -46.389532) (xy 102.984773 -46.328234) (xy 102.932417 -46.261658) (xy 102.886627 -46.190406)
			(xy 102.847816 -46.115125) (xy 102.816337 -46.036495) (xy 102.792476 -45.955228) (xy 102.776447 -45.872062)
			(xy 102.768396 -45.787748) (xy 34.042096 -45.787748) (xy 34.042096 -50.919888) (xy 40.838385 -50.919888)
			(xy 40.84236 -50.809847) (xy 40.854266 -50.70038) (xy 40.874039 -50.592057) (xy 40.901577 -50.485443)
			(xy 40.936736 -50.381095) (xy 40.979333 -50.279555) (xy 41.029146 -50.181354) (xy 41.085915 -50.087003)
			(xy 41.149344 -49.996994) (xy 41.219103 -49.911797) (xy 41.294827 -49.831856) (xy 41.376123 -49.757587)
			(xy 41.462565 -49.689378) (xy 41.553704 -49.627584) (xy 41.649065 -49.572528) (xy 41.748149 -49.524496)
			(xy 41.850442 -49.483739) (xy 41.955408 -49.450469) (xy 42.062501 -49.424861) (xy 42.171164 -49.407047)
			(xy 42.280828 -49.39712) (xy 42.390923 -49.395132) (xy 42.500874 -49.401093) (xy 42.610108 -49.414973)
			(xy 42.718057 -49.436698) (xy 42.824156 -49.466157) (xy 42.927853 -49.503194) (xy 43.028607 -49.547617)
			(xy 43.125893 -49.599195) (xy 43.219203 -49.657658) (xy 43.308052 -49.722702) (xy 43.391976 -49.793987)
			(xy 43.470537 -49.871143) (xy 43.543326 -49.953766) (xy 43.609963 -50.041426) (xy 43.670101 -50.133666)
			(xy 43.723427 -50.230005) (xy 43.769662 -50.32994) (xy 43.808566 -50.432952) (xy 43.839935 -50.538502)
			(xy 43.863606 -50.64604) (xy 43.879455 -50.755006) (xy 43.887401 -50.864832) (xy 43.887898 -50.919888)
			(xy 60.396385 -50.919888) (xy 60.40036 -50.809847) (xy 60.412266 -50.70038) (xy 60.432039 -50.592057)
			(xy 60.459577 -50.485443) (xy 60.494736 -50.381095) (xy 60.537333 -50.279555) (xy 60.587146 -50.181354)
			(xy 60.643915 -50.087003) (xy 60.707344 -49.996994) (xy 60.777103 -49.911797) (xy 60.852827 -49.831856)
			(xy 60.934123 -49.757587) (xy 61.020565 -49.689378) (xy 61.111704 -49.627584) (xy 61.207065 -49.572528)
			(xy 61.306149 -49.524496) (xy 61.408442 -49.483739) (xy 61.513408 -49.450469) (xy 61.620501 -49.424861)
			(xy 61.729164 -49.407047) (xy 61.838828 -49.39712) (xy 61.948923 -49.395132) (xy 62.058874 -49.401093)
			(xy 62.168108 -49.414973) (xy 62.276057 -49.436698) (xy 62.382156 -49.466157) (xy 62.485853 -49.503194)
			(xy 62.586607 -49.547617) (xy 62.683893 -49.599195) (xy 62.777203 -49.657658) (xy 62.866052 -49.722702)
			(xy 62.949976 -49.793987) (xy 63.028537 -49.871143) (xy 63.101326 -49.953766) (xy 63.167963 -50.041426)
			(xy 63.228101 -50.133666) (xy 63.281427 -50.230005) (xy 63.327662 -50.32994) (xy 63.366566 -50.432952)
			(xy 63.397935 -50.538502) (xy 63.421606 -50.64604) (xy 63.437455 -50.755006) (xy 63.445401 -50.864832)
			(xy 63.445898 -50.919888) (xy 63.445401 -50.974944) (xy 63.437455 -51.08477) (xy 63.421606 -51.193736)
			(xy 63.397935 -51.301274) (xy 63.366566 -51.406824) (xy 63.327662 -51.509836) (xy 63.281427 -51.609771)
			(xy 63.228101 -51.70611) (xy 63.167963 -51.79835) (xy 63.101326 -51.88601) (xy 63.028537 -51.968633)
			(xy 62.949976 -52.045789) (xy 62.866052 -52.117074) (xy 62.777203 -52.182118) (xy 62.683893 -52.240581)
			(xy 62.586607 -52.292159) (xy 62.485853 -52.336582) (xy 62.382156 -52.373619) (xy 62.276057 -52.403078)
			(xy 62.168108 -52.424803) (xy 62.058874 -52.438683) (xy 61.948923 -52.444644) (xy 61.838828 -52.442656)
			(xy 61.729164 -52.432729) (xy 61.620501 -52.414915) (xy 61.513408 -52.389307) (xy 61.408442 -52.356037)
			(xy 61.306149 -52.31528) (xy 61.207065 -52.267248) (xy 61.111704 -52.212192) (xy 61.020565 -52.150398)
			(xy 60.934123 -52.082189) (xy 60.852827 -52.00792) (xy 60.777103 -51.927979) (xy 60.707344 -51.842782)
			(xy 60.643915 -51.752773) (xy 60.587146 -51.658422) (xy 60.537333 -51.560221) (xy 60.494736 -51.458681)
			(xy 60.459577 -51.354333) (xy 60.432039 -51.247719) (xy 60.412266 -51.139396) (xy 60.40036 -51.029929)
			(xy 60.396385 -50.919888) (xy 43.887898 -50.919888) (xy 43.887401 -50.974944) (xy 43.879455 -51.08477)
			(xy 43.863606 -51.193736) (xy 43.839935 -51.301274) (xy 43.808566 -51.406824) (xy 43.769662 -51.509836)
			(xy 43.723427 -51.609771) (xy 43.670101 -51.70611) (xy 43.609963 -51.79835) (xy 43.543326 -51.88601)
			(xy 43.470537 -51.968633) (xy 43.391976 -52.045789) (xy 43.308052 -52.117074) (xy 43.219203 -52.182118)
			(xy 43.125893 -52.240581) (xy 43.028607 -52.292159) (xy 42.927853 -52.336582) (xy 42.824156 -52.373619)
			(xy 42.718057 -52.403078) (xy 42.610108 -52.424803) (xy 42.500874 -52.438683) (xy 42.390923 -52.444644)
			(xy 42.280828 -52.442656) (xy 42.171164 -52.432729) (xy 42.062501 -52.414915) (xy 41.955408 -52.389307)
			(xy 41.850442 -52.356037) (xy 41.748149 -52.31528) (xy 41.649065 -52.267248) (xy 41.553704 -52.212192)
			(xy 41.462565 -52.150398) (xy 41.376123 -52.082189) (xy 41.294827 -52.00792) (xy 41.219103 -51.927979)
			(xy 41.149344 -51.842782) (xy 41.085915 -51.752773) (xy 41.029146 -51.658422) (xy 40.979333 -51.560221)
			(xy 40.936736 -51.458681) (xy 40.901577 -51.354333) (xy 40.874039 -51.247719) (xy 40.854266 -51.139396)
			(xy 40.84236 -51.029929) (xy 40.838385 -50.919888) (xy 34.042096 -50.919888) (xy 34.042096 -57.065348)
			(xy 102.768396 -57.065348) (xy 102.768396 -56.980652) (xy 102.776447 -56.896338) (xy 102.792476 -56.813172)
			(xy 102.816337 -56.731905) (xy 102.847816 -56.653275) (xy 102.886627 -56.577994) (xy 102.932417 -56.506742)
			(xy 102.984773 -56.440166) (xy 103.043221 -56.378868) (xy 103.107231 -56.323403) (xy 103.176223 -56.274274)
			(xy 103.249573 -56.231925) (xy 103.326616 -56.196741) (xy 103.406655 -56.169039) (xy 103.488964 -56.149071)
			(xy 103.572799 -56.137018) (xy 103.6574 -56.132988) (xy 103.742001 -56.137018) (xy 103.825836 -56.149071)
			(xy 103.908145 -56.169039) (xy 103.988184 -56.196741) (xy 104.065227 -56.231925) (xy 104.138577 -56.274274)
			(xy 104.207569 -56.323403) (xy 104.271579 -56.378868) (xy 104.330027 -56.440166) (xy 104.382383 -56.506742)
			(xy 104.428173 -56.577994) (xy 104.466984 -56.653275) (xy 104.498463 -56.731905) (xy 104.522324 -56.813172)
			(xy 104.538353 -56.896338) (xy 104.546404 -56.980652) (xy 104.546908 -57.023) (xy 104.546404 -57.065348)
			(xy 104.538353 -57.149662) (xy 104.522324 -57.232828) (xy 104.498463 -57.314095) (xy 104.466984 -57.392725)
			(xy 104.428173 -57.468006) (xy 104.382383 -57.539258) (xy 104.330027 -57.605834) (xy 104.271579 -57.667132)
			(xy 104.207569 -57.722597) (xy 104.138577 -57.771726) (xy 104.065227 -57.814075) (xy 103.988184 -57.849259)
			(xy 103.908145 -57.876961) (xy 103.825836 -57.896929) (xy 103.742001 -57.908982) (xy 103.6574 -57.913013)
			(xy 103.572799 -57.908982) (xy 103.488964 -57.896929) (xy 103.406655 -57.876961) (xy 103.326616 -57.849259)
			(xy 103.249573 -57.814075) (xy 103.176223 -57.771726) (xy 103.107231 -57.722597) (xy 103.043221 -57.667132)
			(xy 102.984773 -57.605834) (xy 102.932417 -57.539258) (xy 102.886627 -57.468006) (xy 102.847816 -57.392725)
			(xy 102.816337 -57.314095) (xy 102.792476 -57.232828) (xy 102.776447 -57.149662) (xy 102.768396 -57.065348)
			(xy 34.042096 -57.065348) (xy 34.042096 -58.42) (xy 41.346384 -58.42) (xy 41.350364 -58.330117) (xy 41.362272 -58.240937)
			(xy 41.382015 -58.153159) (xy 41.409439 -58.067469) (xy 41.444328 -57.984538) (xy 41.486411 -57.905016)
			(xy 41.535357 -57.829523) (xy 41.590784 -57.758652) (xy 41.652257 -57.692957) (xy 41.719296 -57.632952)
			(xy 41.791376 -57.579107) (xy 41.867932 -57.531843) (xy 41.948367 -57.49153) (xy 42.032049 -57.458483)
			(xy 42.118324 -57.432962) (xy 42.206518 -57.415166) (xy 42.295939 -57.405233) (xy 42.385888 -57.403243)
			(xy 42.475661 -57.40921) (xy 42.564556 -57.423088) (xy 42.651876 -57.444768) (xy 42.736938 -57.474081)
			(xy 42.819077 -57.510797) (xy 42.897649 -57.554628) (xy 42.97204 -57.605232) (xy 43.041667 -57.662213)
			(xy 43.105986 -57.725125) (xy 43.164494 -57.793475) (xy 43.216731 -57.866728) (xy 43.26229 -57.944311)
			(xy 43.300814 -58.025618) (xy 43.332001 -58.110011) (xy 43.355608 -58.19683) (xy 43.371449 -58.285395)
			(xy 43.379401 -58.375014) (xy 43.379898 -58.42) (xy 60.904384 -58.42) (xy 60.908364 -58.330117) (xy 60.920272 -58.240937)
			(xy 60.940015 -58.153159) (xy 60.967439 -58.067469) (xy 61.002328 -57.984538) (xy 61.044411 -57.905016)
			(xy 61.093357 -57.829523) (xy 61.148784 -57.758652) (xy 61.210257 -57.692957) (xy 61.277296 -57.632952)
			(xy 61.349376 -57.579107) (xy 61.425932 -57.531843) (xy 61.506367 -57.49153) (xy 61.590049 -57.458483)
			(xy 61.676324 -57.432962) (xy 61.764518 -57.415166) (xy 61.853939 -57.405233) (xy 61.943888 -57.403243)
			(xy 62.033661 -57.40921) (xy 62.122556 -57.423088) (xy 62.209876 -57.444768) (xy 62.294938 -57.474081)
			(xy 62.377077 -57.510797) (xy 62.455649 -57.554628) (xy 62.53004 -57.605232) (xy 62.599667 -57.662213)
			(xy 62.663986 -57.725125) (xy 62.722494 -57.793475) (xy 62.774731 -57.866728) (xy 62.82029 -57.944311)
			(xy 62.858814 -58.025618) (xy 62.890001 -58.110011) (xy 62.913608 -58.19683) (xy 62.929449 -58.285395)
			(xy 62.937401 -58.375014) (xy 62.937898 -58.42) (xy 62.937401 -58.464986) (xy 62.929449 -58.554605)
			(xy 62.913608 -58.64317) (xy 62.890001 -58.729989) (xy 62.858814 -58.814382) (xy 62.82029 -58.895689)
			(xy 62.774731 -58.973272) (xy 62.722494 -59.046525) (xy 62.663986 -59.114875) (xy 62.599667 -59.177787)
			(xy 62.53004 -59.234768) (xy 62.455649 -59.285372) (xy 62.377077 -59.329203) (xy 62.294938 -59.365919)
			(xy 62.209876 -59.395232) (xy 62.122556 -59.416912) (xy 62.033661 -59.43079) (xy 61.943888 -59.436757)
			(xy 61.853939 -59.434767) (xy 61.764518 -59.424834) (xy 61.676324 -59.407038) (xy 61.590049 -59.381517)
			(xy 61.506367 -59.34847) (xy 61.425932 -59.308157) (xy 61.349376 -59.260893) (xy 61.277296 -59.207048)
			(xy 61.210257 -59.147043) (xy 61.148784 -59.081348) (xy 61.093357 -59.010477) (xy 61.044411 -58.934984)
			(xy 61.002328 -58.855462) (xy 60.967439 -58.772531) (xy 60.940015 -58.686841) (xy 60.920272 -58.599063)
			(xy 60.908364 -58.509883) (xy 60.904384 -58.42) (xy 43.379898 -58.42) (xy 43.379401 -58.464986) (xy 43.371449 -58.554605)
			(xy 43.355608 -58.64317) (xy 43.332001 -58.729989) (xy 43.300814 -58.814382) (xy 43.26229 -58.895689)
			(xy 43.216731 -58.973272) (xy 43.164494 -59.046525) (xy 43.105986 -59.114875) (xy 43.041667 -59.177787)
			(xy 42.97204 -59.234768) (xy 42.897649 -59.285372) (xy 42.819077 -59.329203) (xy 42.736938 -59.365919)
			(xy 42.651876 -59.395232) (xy 42.564556 -59.416912) (xy 42.475661 -59.43079) (xy 42.385888 -59.436757)
			(xy 42.295939 -59.434767) (xy 42.206518 -59.424834) (xy 42.118324 -59.407038) (xy 42.032049 -59.381517)
			(xy 41.948367 -59.34847) (xy 41.867932 -59.308157) (xy 41.791376 -59.260893) (xy 41.719296 -59.207048)
			(xy 41.652257 -59.147043) (xy 41.590784 -59.081348) (xy 41.535357 -59.010477) (xy 41.486411 -58.934984)
			(xy 41.444328 -58.855462) (xy 41.409439 -58.772531) (xy 41.382015 -58.686841) (xy 41.362272 -58.599063)
			(xy 41.350364 -58.509883) (xy 41.346384 -58.42) (xy 34.042096 -58.42) (xy 34.042096 -71.239888) (xy 40.838385 -71.239888)
			(xy 40.84236 -71.129847) (xy 40.854266 -71.02038) (xy 40.874039 -70.912057) (xy 40.901577 -70.805443)
			(xy 40.936736 -70.701095) (xy 40.979333 -70.599555) (xy 41.029146 -70.501354) (xy 41.085915 -70.407003)
			(xy 41.149344 -70.316994) (xy 41.219103 -70.231797) (xy 41.294827 -70.151856) (xy 41.376123 -70.077587)
			(xy 41.462565 -70.009378) (xy 41.553704 -69.947584) (xy 41.649065 -69.892528) (xy 41.748149 -69.844496)
			(xy 41.850442 -69.803739) (xy 41.955408 -69.770469) (xy 42.062501 -69.744861) (xy 42.171164 -69.727047)
			(xy 42.280828 -69.71712) (xy 42.390923 -69.715132) (xy 42.500874 -69.721093) (xy 42.610108 -69.734973)
			(xy 42.718057 -69.756698) (xy 42.824156 -69.786157) (xy 42.927853 -69.823194) (xy 43.028607 -69.867617)
			(xy 43.125893 -69.919195) (xy 43.219203 -69.977658) (xy 43.308052 -70.042702) (xy 43.391976 -70.113987)
			(xy 43.470537 -70.191143) (xy 43.543326 -70.273766) (xy 43.609963 -70.361426) (xy 43.670101 -70.453666)
			(xy 43.723427 -70.550005) (xy 43.769662 -70.64994) (xy 43.808566 -70.752952) (xy 43.839935 -70.858502)
			(xy 43.863606 -70.96604) (xy 43.879455 -71.075006) (xy 43.887401 -71.184832) (xy 43.887898 -71.239888)
			(xy 60.396385 -71.239888) (xy 60.40036 -71.129847) (xy 60.412266 -71.02038) (xy 60.432039 -70.912057)
			(xy 60.459577 -70.805443) (xy 60.494736 -70.701095) (xy 60.537333 -70.599555) (xy 60.587146 -70.501354)
			(xy 60.643915 -70.407003) (xy 60.707344 -70.316994) (xy 60.777103 -70.231797) (xy 60.852827 -70.151856)
			(xy 60.934123 -70.077587) (xy 61.020565 -70.009378) (xy 61.111704 -69.947584) (xy 61.207065 -69.892528)
			(xy 61.306149 -69.844496) (xy 61.408442 -69.803739) (xy 61.513408 -69.770469) (xy 61.620501 -69.744861)
			(xy 61.729164 -69.727047) (xy 61.838828 -69.71712) (xy 61.948923 -69.715132) (xy 62.058874 -69.721093)
			(xy 62.168108 -69.734973) (xy 62.276057 -69.756698) (xy 62.382156 -69.786157) (xy 62.485853 -69.823194)
			(xy 62.586607 -69.867617) (xy 62.683893 -69.919195) (xy 62.777203 -69.977658) (xy 62.866052 -70.042702)
			(xy 62.949976 -70.113987) (xy 63.028537 -70.191143) (xy 63.101326 -70.273766) (xy 63.167963 -70.361426)
			(xy 63.228101 -70.453666) (xy 63.281427 -70.550005) (xy 63.327662 -70.64994) (xy 63.366566 -70.752952)
			(xy 63.397935 -70.858502) (xy 63.421606 -70.96604) (xy 63.437455 -71.075006) (xy 63.445401 -71.184832)
			(xy 63.445898 -71.239888) (xy 63.445401 -71.294944) (xy 63.437455 -71.40477) (xy 63.421606 -71.513736)
			(xy 63.397935 -71.621274) (xy 63.366566 -71.726824) (xy 63.327662 -71.829836) (xy 63.281427 -71.929771)
			(xy 63.228101 -72.02611) (xy 63.167963 -72.11835) (xy 63.101326 -72.20601) (xy 63.028537 -72.288633)
			(xy 62.949976 -72.365789) (xy 62.866052 -72.437074) (xy 62.777203 -72.502118) (xy 62.683893 -72.560581)
			(xy 62.586607 -72.612159) (xy 62.485853 -72.656582) (xy 62.382156 -72.693619) (xy 62.276057 -72.723078)
			(xy 62.168108 -72.744803) (xy 62.058874 -72.758683) (xy 61.948923 -72.764644) (xy 61.838828 -72.762656)
			(xy 61.729164 -72.752729) (xy 61.620501 -72.734915) (xy 61.513408 -72.709307) (xy 61.408442 -72.676037)
			(xy 61.306149 -72.63528) (xy 61.207065 -72.587248) (xy 61.111704 -72.532192) (xy 61.020565 -72.470398)
			(xy 60.934123 -72.402189) (xy 60.852827 -72.32792) (xy 60.777103 -72.247979) (xy 60.707344 -72.162782)
			(xy 60.643915 -72.072773) (xy 60.587146 -71.978422) (xy 60.537333 -71.880221) (xy 60.494736 -71.778681)
			(xy 60.459577 -71.674333) (xy 60.432039 -71.567719) (xy 60.412266 -71.459396) (xy 60.40036 -71.349929)
			(xy 60.396385 -71.239888) (xy 43.887898 -71.239888) (xy 43.887401 -71.294944) (xy 43.879455 -71.40477)
			(xy 43.863606 -71.513736) (xy 43.839935 -71.621274) (xy 43.808566 -71.726824) (xy 43.769662 -71.829836)
			(xy 43.723427 -71.929771) (xy 43.670101 -72.02611) (xy 43.609963 -72.11835) (xy 43.543326 -72.20601)
			(xy 43.470537 -72.288633) (xy 43.391976 -72.365789) (xy 43.308052 -72.437074) (xy 43.219203 -72.502118)
			(xy 43.125893 -72.560581) (xy 43.028607 -72.612159) (xy 42.927853 -72.656582) (xy 42.824156 -72.693619)
			(xy 42.718057 -72.723078) (xy 42.610108 -72.744803) (xy 42.500874 -72.758683) (xy 42.390923 -72.764644)
			(xy 42.280828 -72.762656) (xy 42.171164 -72.752729) (xy 42.062501 -72.734915) (xy 41.955408 -72.709307)
			(xy 41.850442 -72.676037) (xy 41.748149 -72.63528) (xy 41.649065 -72.587248) (xy 41.553704 -72.532192)
			(xy 41.462565 -72.470398) (xy 41.376123 -72.402189) (xy 41.294827 -72.32792) (xy 41.219103 -72.247979)
			(xy 41.149344 -72.162782) (xy 41.085915 -72.072773) (xy 41.029146 -71.978422) (xy 40.979333 -71.880221)
			(xy 40.936736 -71.778681) (xy 40.901577 -71.674333) (xy 40.874039 -71.567719) (xy 40.854266 -71.459396)
			(xy 40.84236 -71.349929) (xy 40.838385 -71.239888) (xy 34.042096 -71.239888) (xy 34.042096 -78.74)
			(xy 41.346384 -78.74) (xy 41.350364 -78.650117) (xy 41.362272 -78.560937) (xy 41.382015 -78.473159)
			(xy 41.409439 -78.387469) (xy 41.444328 -78.304538) (xy 41.486411 -78.225016) (xy 41.535357 -78.149523)
			(xy 41.590784 -78.078652) (xy 41.652257 -78.012957) (xy 41.719296 -77.952952) (xy 41.791376 -77.899107)
			(xy 41.867932 -77.851843) (xy 41.948367 -77.81153) (xy 42.032049 -77.778483) (xy 42.118324 -77.752962)
			(xy 42.206518 -77.735166) (xy 42.295939 -77.725233) (xy 42.385888 -77.723243) (xy 42.475661 -77.72921)
			(xy 42.564556 -77.743088) (xy 42.651876 -77.764768) (xy 42.736938 -77.794081) (xy 42.819077 -77.830797)
			(xy 42.897649 -77.874628) (xy 42.97204 -77.925232) (xy 43.041667 -77.982213) (xy 43.105986 -78.045125)
			(xy 43.164494 -78.113475) (xy 43.216731 -78.186728) (xy 43.26229 -78.264311) (xy 43.300814 -78.345618)
			(xy 43.332001 -78.430011) (xy 43.355608 -78.51683) (xy 43.371449 -78.605395) (xy 43.379401 -78.695014)
			(xy 43.379898 -78.74) (xy 60.904384 -78.74) (xy 60.908364 -78.650117) (xy 60.920272 -78.560937) (xy 60.940015 -78.473159)
			(xy 60.967439 -78.387469) (xy 61.002328 -78.304538) (xy 61.044411 -78.225016) (xy 61.093357 -78.149523)
			(xy 61.148784 -78.078652) (xy 61.210257 -78.012957) (xy 61.277296 -77.952952) (xy 61.349376 -77.899107)
			(xy 61.425932 -77.851843) (xy 61.506367 -77.81153) (xy 61.590049 -77.778483) (xy 61.676324 -77.752962)
			(xy 61.764518 -77.735166) (xy 61.853939 -77.725233) (xy 61.943888 -77.723243) (xy 62.033661 -77.72921)
			(xy 62.122556 -77.743088) (xy 62.209876 -77.764768) (xy 62.294938 -77.794081) (xy 62.377077 -77.830797)
			(xy 62.455649 -77.874628) (xy 62.53004 -77.925232) (xy 62.599667 -77.982213) (xy 62.663986 -78.045125)
			(xy 62.722494 -78.113475) (xy 62.774731 -78.186728) (xy 62.82029 -78.264311) (xy 62.858814 -78.345618)
			(xy 62.890001 -78.430011) (xy 62.913608 -78.51683) (xy 62.929449 -78.605395) (xy 62.937401 -78.695014)
			(xy 62.937898 -78.74) (xy 62.937401 -78.784986) (xy 62.929449 -78.874605) (xy 62.913608 -78.96317)
			(xy 62.890001 -79.049989) (xy 62.858814 -79.134382) (xy 62.82029 -79.215689) (xy 62.774731 -79.293272)
			(xy 62.722494 -79.366525) (xy 62.663986 -79.434875) (xy 62.599667 -79.497787) (xy 62.53004 -79.554768)
			(xy 62.455649 -79.605372) (xy 62.377077 -79.649203) (xy 62.294938 -79.685919) (xy 62.209876 -79.715232)
			(xy 62.122556 -79.736912) (xy 62.033661 -79.75079) (xy 61.943888 -79.756757) (xy 61.853939 -79.754767)
			(xy 61.764518 -79.744834) (xy 61.676324 -79.727038) (xy 61.590049 -79.701517) (xy 61.506367 -79.66847)
			(xy 61.425932 -79.628157) (xy 61.349376 -79.580893) (xy 61.277296 -79.527048) (xy 61.210257 -79.467043)
			(xy 61.148784 -79.401348) (xy 61.093357 -79.330477) (xy 61.044411 -79.254984) (xy 61.002328 -79.175462)
			(xy 60.967439 -79.092531) (xy 60.940015 -79.006841) (xy 60.920272 -78.919063) (xy 60.908364 -78.829883)
			(xy 60.904384 -78.74) (xy 43.379898 -78.74) (xy 43.379401 -78.784986) (xy 43.371449 -78.874605) (xy 43.355608 -78.96317)
			(xy 43.332001 -79.049989) (xy 43.300814 -79.134382) (xy 43.26229 -79.215689) (xy 43.216731 -79.293272)
			(xy 43.164494 -79.366525) (xy 43.105986 -79.434875) (xy 43.041667 -79.497787) (xy 42.97204 -79.554768)
			(xy 42.897649 -79.605372) (xy 42.819077 -79.649203) (xy 42.736938 -79.685919) (xy 42.651876 -79.715232)
			(xy 42.564556 -79.736912) (xy 42.475661 -79.75079) (xy 42.385888 -79.756757) (xy 42.295939 -79.754767)
			(xy 42.206518 -79.744834) (xy 42.118324 -79.727038) (xy 42.032049 -79.701517) (xy 41.948367 -79.66847)
			(xy 41.867932 -79.628157) (xy 41.791376 -79.580893) (xy 41.719296 -79.527048) (xy 41.652257 -79.467043)
			(xy 41.590784 -79.401348) (xy 41.535357 -79.330477) (xy 41.486411 -79.254984) (xy 41.444328 -79.175462)
			(xy 41.409439 -79.092531) (xy 41.382015 -79.006841) (xy 41.362272 -78.919063) (xy 41.350364 -78.829883)
			(xy 41.346384 -78.74) (xy 34.042096 -78.74) (xy 34.042096 -91.559888) (xy 40.838385 -91.559888) (xy 40.84236 -91.449847)
			(xy 40.854266 -91.34038) (xy 40.874039 -91.232057) (xy 40.901577 -91.125443) (xy 40.936736 -91.021095)
			(xy 40.979333 -90.919555) (xy 41.029146 -90.821354) (xy 41.085915 -90.727003) (xy 41.149344 -90.636994)
			(xy 41.219103 -90.551797) (xy 41.294827 -90.471856) (xy 41.376123 -90.397587) (xy 41.462565 -90.329378)
			(xy 41.553704 -90.267584) (xy 41.649065 -90.212528) (xy 41.748149 -90.164496) (xy 41.850442 -90.123739)
			(xy 41.955408 -90.090469) (xy 42.062501 -90.064861) (xy 42.171164 -90.047047) (xy 42.280828 -90.03712)
			(xy 42.390923 -90.035132) (xy 42.500874 -90.041093) (xy 42.610108 -90.054973) (xy 42.718057 -90.076698)
			(xy 42.824156 -90.106157) (xy 42.927853 -90.143194) (xy 43.028607 -90.187617) (xy 43.125893 -90.239195)
			(xy 43.219203 -90.297658) (xy 43.308052 -90.362702) (xy 43.391976 -90.433987) (xy 43.470537 -90.511143)
			(xy 43.543326 -90.593766) (xy 43.609963 -90.681426) (xy 43.670101 -90.773666) (xy 43.723427 -90.870005)
			(xy 43.769662 -90.96994) (xy 43.808566 -91.072952) (xy 43.839935 -91.178502) (xy 43.863606 -91.28604)
			(xy 43.879455 -91.395006) (xy 43.887401 -91.504832) (xy 43.887898 -91.559888) (xy 60.396385 -91.559888)
			(xy 60.40036 -91.449847) (xy 60.412266 -91.34038) (xy 60.432039 -91.232057) (xy 60.459577 -91.125443)
			(xy 60.494736 -91.021095) (xy 60.537333 -90.919555) (xy 60.587146 -90.821354) (xy 60.643915 -90.727003)
			(xy 60.707344 -90.636994) (xy 60.777103 -90.551797) (xy 60.852827 -90.471856) (xy 60.934123 -90.397587)
			(xy 61.020565 -90.329378) (xy 61.111704 -90.267584) (xy 61.207065 -90.212528) (xy 61.306149 -90.164496)
			(xy 61.408442 -90.123739) (xy 61.513408 -90.090469) (xy 61.620501 -90.064861) (xy 61.729164 -90.047047)
			(xy 61.838828 -90.03712) (xy 61.948923 -90.035132) (xy 62.058874 -90.041093) (xy 62.168108 -90.054973)
			(xy 62.276057 -90.076698) (xy 62.382156 -90.106157) (xy 62.485853 -90.143194) (xy 62.586607 -90.187617)
			(xy 62.683893 -90.239195) (xy 62.777203 -90.297658) (xy 62.866052 -90.362702) (xy 62.949976 -90.433987)
			(xy 63.028537 -90.511143) (xy 63.101326 -90.593766) (xy 63.167963 -90.681426) (xy 63.228101 -90.773666)
			(xy 63.281427 -90.870005) (xy 63.327662 -90.96994) (xy 63.366566 -91.072952) (xy 63.397935 -91.178502)
			(xy 63.421606 -91.28604) (xy 63.437455 -91.395006) (xy 63.445401 -91.504832) (xy 63.445898 -91.559888)
			(xy 63.445401 -91.614944) (xy 63.437455 -91.72477) (xy 63.421606 -91.833736) (xy 63.397935 -91.941274)
			(xy 63.366566 -92.046824) (xy 63.327662 -92.149836) (xy 63.281427 -92.249771) (xy 63.228101 -92.34611)
			(xy 63.167963 -92.43835) (xy 63.120949 -92.500196) (xy 94.864936 -92.500196) (xy 94.864936 -87.500206)
			(xy 94.865431 -87.399365) (xy 94.873349 -87.197838) (xy 94.889173 -86.996778) (xy 94.912878 -86.796494)
			(xy 94.944428 -86.597295) (xy 94.983774 -86.399488) (xy 95.030856 -86.203379) (xy 95.085601 -86.009269)
			(xy 95.147924 -85.817458) (xy 95.217729 -85.628241) (xy 95.29491 -85.441912) (xy 95.379346 -85.258755)
			(xy 95.470908 -85.079055) (xy 95.569454 -84.903089) (xy 95.674832 -84.731126) (xy 95.786881 -84.563434)
			(xy 95.905427 -84.40027) (xy 96.030287 -84.241885) (xy 96.161269 -84.088525) (xy 96.298171 -83.940425)
			(xy 96.440781 -83.797815) (xy 96.588881 -83.660913) (xy 96.742241 -83.529931) (xy 96.900626 -83.405071)
			(xy 97.06379 -83.286525) (xy 97.231482 -83.174476) (xy 97.403445 -83.069098) (xy 97.579411 -82.970552)
			(xy 97.759111 -82.87899) (xy 97.942268 -82.794554) (xy 98.128597 -82.717373) (xy 98.317814 -82.647568)
			(xy 98.509625 -82.585245) (xy 98.703735 -82.5305) (xy 98.899844 -82.483418) (xy 99.097651 -82.444072)
			(xy 99.29685 -82.412522) (xy 99.497134 -82.388817) (xy 99.698194 -82.372993) (xy 99.899721 -82.365075)
			(xy 100.101403 -82.365075) (xy 100.30293 -82.372993) (xy 100.50399 -82.388817) (xy 100.704274 -82.412522)
			(xy 100.903473 -82.444072) (xy 101.10128 -82.483418) (xy 101.297389 -82.5305) (xy 101.491499 -82.585245)
			(xy 101.68331 -82.647568) (xy 101.872527 -82.717373) (xy 102.058856 -82.794554) (xy 102.242013 -82.87899)
			(xy 102.421713 -82.970552) (xy 102.597679 -83.069098) (xy 102.769642 -83.174476) (xy 102.937334 -83.286525)
			(xy 103.100498 -83.405071) (xy 103.258883 -83.529931) (xy 103.412243 -83.660913) (xy 103.560343 -83.797815)
			(xy 103.702953 -83.940425) (xy 103.839855 -84.088525) (xy 103.970837 -84.241885) (xy 104.095697 -84.40027)
			(xy 104.214243 -84.563434) (xy 104.326292 -84.731126) (xy 104.43167 -84.903089) (xy 104.530216 -85.079055)
			(xy 104.621778 -85.258755) (xy 104.706214 -85.441912) (xy 104.783395 -85.628241) (xy 104.8532 -85.817458)
			(xy 104.915523 -86.009269) (xy 104.970268 -86.203379) (xy 105.01735 -86.399488) (xy 105.056696 -86.597295)
			(xy 105.088246 -86.796494) (xy 105.111951 -86.996778) (xy 105.127775 -87.197838) (xy 105.135693 -87.399365)
			(xy 105.136188 -87.500206) (xy 105.136188 -92.500196) (xy 105.135693 -92.601037) (xy 105.127775 -92.802564)
			(xy 105.111951 -93.003624) (xy 105.088246 -93.203908) (xy 105.056696 -93.403107) (xy 105.01735 -93.600914)
			(xy 104.970268 -93.797023) (xy 104.915523 -93.991133) (xy 104.8532 -94.182944) (xy 104.783395 -94.372161)
			(xy 104.706214 -94.55849) (xy 104.621778 -94.741647) (xy 104.530216 -94.921347) (xy 104.43167 -95.097313)
			(xy 104.326292 -95.269276) (xy 104.214243 -95.436968) (xy 104.095697 -95.600132) (xy 103.970837 -95.758517)
			(xy 103.839855 -95.911877) (xy 103.702953 -96.059977) (xy 103.560343 -96.202587) (xy 103.412243 -96.339489)
			(xy 103.258883 -96.470471) (xy 103.100498 -96.595331) (xy 102.937334 -96.713877) (xy 102.769642 -96.825926)
			(xy 102.597679 -96.931304) (xy 102.421713 -97.02985) (xy 102.242013 -97.121412) (xy 102.058856 -97.205848)
			(xy 101.872527 -97.283029) (xy 101.68331 -97.352834) (xy 101.491499 -97.415157) (xy 101.297389 -97.469902)
			(xy 101.10128 -97.516984) (xy 100.903473 -97.55633) (xy 100.704274 -97.58788) (xy 100.50399 -97.611585)
			(xy 100.30293 -97.627409) (xy 100.101403 -97.635327) (xy 99.899721 -97.635327) (xy 99.698194 -97.627409)
			(xy 99.497134 -97.611585) (xy 99.29685 -97.58788) (xy 99.097651 -97.55633) (xy 98.899844 -97.516984)
			(xy 98.703735 -97.469902) (xy 98.509625 -97.415157) (xy 98.317814 -97.352834) (xy 98.128597 -97.283029)
			(xy 97.942268 -97.205848) (xy 97.759111 -97.121412) (xy 97.579411 -97.02985) (xy 97.403445 -96.931304)
			(xy 97.231482 -96.825926) (xy 97.06379 -96.713877) (xy 96.900626 -96.595331) (xy 96.742241 -96.470471)
			(xy 96.588881 -96.339489) (xy 96.440781 -96.202587) (xy 96.298171 -96.059977) (xy 96.161269 -95.911877)
			(xy 96.030287 -95.758517) (xy 95.905427 -95.600132) (xy 95.786881 -95.436968) (xy 95.674832 -95.269276)
			(xy 95.569454 -95.097313) (xy 95.470908 -94.921347) (xy 95.379346 -94.741647) (xy 95.29491 -94.55849)
			(xy 95.217729 -94.372161) (xy 95.147924 -94.182944) (xy 95.085601 -93.991133) (xy 95.030856 -93.797023)
			(xy 94.983774 -93.600914) (xy 94.944428 -93.403107) (xy 94.912878 -93.203908) (xy 94.889173 -93.003624)
			(xy 94.873349 -92.802564) (xy 94.865431 -92.601037) (xy 94.864936 -92.500196) (xy 63.120949 -92.500196)
			(xy 63.101326 -92.52601) (xy 63.028537 -92.608633) (xy 62.949976 -92.685789) (xy 62.866052 -92.757074)
			(xy 62.777203 -92.822118) (xy 62.683893 -92.880581) (xy 62.586607 -92.932159) (xy 62.485853 -92.976582)
			(xy 62.382156 -93.013619) (xy 62.276057 -93.043078) (xy 62.168108 -93.064803) (xy 62.058874 -93.078683)
			(xy 61.948923 -93.084644) (xy 61.838828 -93.082656) (xy 61.729164 -93.072729) (xy 61.620501 -93.054915)
			(xy 61.513408 -93.029307) (xy 61.408442 -92.996037) (xy 61.306149 -92.95528) (xy 61.207065 -92.907248)
			(xy 61.111704 -92.852192) (xy 61.020565 -92.790398) (xy 60.934123 -92.722189) (xy 60.852827 -92.64792)
			(xy 60.777103 -92.567979) (xy 60.707344 -92.482782) (xy 60.643915 -92.392773) (xy 60.587146 -92.298422)
			(xy 60.537333 -92.200221) (xy 60.494736 -92.098681) (xy 60.459577 -91.994333) (xy 60.432039 -91.887719)
			(xy 60.412266 -91.779396) (xy 60.40036 -91.669929) (xy 60.396385 -91.559888) (xy 43.887898 -91.559888)
			(xy 43.887401 -91.614944) (xy 43.879455 -91.72477) (xy 43.863606 -91.833736) (xy 43.839935 -91.941274)
			(xy 43.808566 -92.046824) (xy 43.769662 -92.149836) (xy 43.723427 -92.249771) (xy 43.670101 -92.34611)
			(xy 43.609963 -92.43835) (xy 43.543326 -92.52601) (xy 43.470537 -92.608633) (xy 43.391976 -92.685789)
			(xy 43.308052 -92.757074) (xy 43.219203 -92.822118) (xy 43.125893 -92.880581) (xy 43.028607 -92.932159)
			(xy 42.927853 -92.976582) (xy 42.824156 -93.013619) (xy 42.718057 -93.043078) (xy 42.610108 -93.064803)
			(xy 42.500874 -93.078683) (xy 42.390923 -93.084644) (xy 42.280828 -93.082656) (xy 42.171164 -93.072729)
			(xy 42.062501 -93.054915) (xy 41.955408 -93.029307) (xy 41.850442 -92.996037) (xy 41.748149 -92.95528)
			(xy 41.649065 -92.907248) (xy 41.553704 -92.852192) (xy 41.462565 -92.790398) (xy 41.376123 -92.722189)
			(xy 41.294827 -92.64792) (xy 41.219103 -92.567979) (xy 41.149344 -92.482782) (xy 41.085915 -92.392773)
			(xy 41.029146 -92.298422) (xy 40.979333 -92.200221) (xy 40.936736 -92.098681) (xy 40.901577 -91.994333)
			(xy 40.874039 -91.887719) (xy 40.854266 -91.779396) (xy 40.84236 -91.669929) (xy 40.838385 -91.559888)
			(xy 34.042096 -91.559888) (xy 34.042096 -99.06) (xy 41.346384 -99.06) (xy 41.350364 -98.970117) (xy 41.362272 -98.880937)
			(xy 41.382015 -98.793159) (xy 41.409439 -98.707469) (xy 41.444328 -98.624538) (xy 41.486411 -98.545016)
			(xy 41.535357 -98.469523) (xy 41.590784 -98.398652) (xy 41.652257 -98.332957) (xy 41.719296 -98.272952)
			(xy 41.791376 -98.219107) (xy 41.867932 -98.171843) (xy 41.948367 -98.13153) (xy 42.032049 -98.098483)
			(xy 42.118324 -98.072962) (xy 42.206518 -98.055166) (xy 42.295939 -98.045233) (xy 42.385888 -98.043243)
			(xy 42.475661 -98.04921) (xy 42.564556 -98.063088) (xy 42.651876 -98.084768) (xy 42.736938 -98.114081)
			(xy 42.819077 -98.150797) (xy 42.897649 -98.194628) (xy 42.97204 -98.245232) (xy 43.041667 -98.302213)
			(xy 43.105986 -98.365125) (xy 43.164494 -98.433475) (xy 43.216731 -98.506728) (xy 43.26229 -98.584311)
			(xy 43.300814 -98.665618) (xy 43.332001 -98.750011) (xy 43.355608 -98.83683) (xy 43.371449 -98.925395)
			(xy 43.379401 -99.015014) (xy 43.379898 -99.06) (xy 60.904384 -99.06) (xy 60.908364 -98.970117) (xy 60.920272 -98.880937)
			(xy 60.940015 -98.793159) (xy 60.967439 -98.707469) (xy 61.002328 -98.624538) (xy 61.044411 -98.545016)
			(xy 61.093357 -98.469523) (xy 61.148784 -98.398652) (xy 61.210257 -98.332957) (xy 61.277296 -98.272952)
			(xy 61.349376 -98.219107) (xy 61.425932 -98.171843) (xy 61.506367 -98.13153) (xy 61.590049 -98.098483)
			(xy 61.676324 -98.072962) (xy 61.764518 -98.055166) (xy 61.853939 -98.045233) (xy 61.943888 -98.043243)
			(xy 62.033661 -98.04921) (xy 62.122556 -98.063088) (xy 62.209876 -98.084768) (xy 62.294938 -98.114081)
			(xy 62.377077 -98.150797) (xy 62.455649 -98.194628) (xy 62.53004 -98.245232) (xy 62.599667 -98.302213)
			(xy 62.663986 -98.365125) (xy 62.722494 -98.433475) (xy 62.774731 -98.506728) (xy 62.82029 -98.584311)
			(xy 62.858814 -98.665618) (xy 62.890001 -98.750011) (xy 62.913608 -98.83683) (xy 62.929449 -98.925395)
			(xy 62.937401 -99.015014) (xy 62.937898 -99.06) (xy 62.937401 -99.104986) (xy 62.929449 -99.194605)
			(xy 62.913608 -99.28317) (xy 62.890001 -99.369989) (xy 62.858814 -99.454382) (xy 62.82029 -99.535689)
			(xy 62.774731 -99.613272) (xy 62.722494 -99.686525) (xy 62.663986 -99.754875) (xy 62.599667 -99.817787)
			(xy 62.53004 -99.874768) (xy 62.455649 -99.925372) (xy 62.377077 -99.969203) (xy 62.294938 -100.005919)
			(xy 62.209876 -100.035232) (xy 62.122556 -100.056912) (xy 62.033661 -100.07079) (xy 61.943888 -100.076757)
			(xy 61.853939 -100.074767) (xy 61.764518 -100.064834) (xy 61.676324 -100.047038) (xy 61.590049 -100.021517)
			(xy 61.506367 -99.98847) (xy 61.425932 -99.948157) (xy 61.349376 -99.900893) (xy 61.277296 -99.847048)
			(xy 61.210257 -99.787043) (xy 61.148784 -99.721348) (xy 61.093357 -99.650477) (xy 61.044411 -99.574984)
			(xy 61.002328 -99.495462) (xy 60.967439 -99.412531) (xy 60.940015 -99.326841) (xy 60.920272 -99.239063)
			(xy 60.908364 -99.149883) (xy 60.904384 -99.06) (xy 43.379898 -99.06) (xy 43.379401 -99.104986) (xy 43.371449 -99.194605)
			(xy 43.355608 -99.28317) (xy 43.332001 -99.369989) (xy 43.300814 -99.454382) (xy 43.26229 -99.535689)
			(xy 43.216731 -99.613272) (xy 43.164494 -99.686525) (xy 43.105986 -99.754875) (xy 43.041667 -99.817787)
			(xy 42.97204 -99.874768) (xy 42.897649 -99.925372) (xy 42.819077 -99.969203) (xy 42.736938 -100.005919)
			(xy 42.651876 -100.035232) (xy 42.564556 -100.056912) (xy 42.475661 -100.07079) (xy 42.385888 -100.076757)
			(xy 42.295939 -100.074767) (xy 42.206518 -100.064834) (xy 42.118324 -100.047038) (xy 42.032049 -100.021517)
			(xy 41.948367 -99.98847) (xy 41.867932 -99.948157) (xy 41.791376 -99.900893) (xy 41.719296 -99.847048)
			(xy 41.652257 -99.787043) (xy 41.590784 -99.721348) (xy 41.535357 -99.650477) (xy 41.486411 -99.574984)
			(xy 41.444328 -99.495462) (xy 41.409439 -99.412531) (xy 41.382015 -99.326841) (xy 41.362272 -99.239063)
			(xy 41.350364 -99.149883) (xy 41.346384 -99.06) (xy 34.042096 -99.06) (xy 34.042096 -111.879888)
			(xy 40.838385 -111.879888) (xy 40.84236 -111.769847) (xy 40.854266 -111.66038) (xy 40.874039 -111.552057)
			(xy 40.901577 -111.445443) (xy 40.936736 -111.341095) (xy 40.979333 -111.239555) (xy 41.029146 -111.141354)
			(xy 41.085915 -111.047003) (xy 41.149344 -110.956994) (xy 41.219103 -110.871797) (xy 41.294827 -110.791856)
			(xy 41.376123 -110.717587) (xy 41.462565 -110.649378) (xy 41.553704 -110.587584) (xy 41.649065 -110.532528)
			(xy 41.748149 -110.484496) (xy 41.850442 -110.443739) (xy 41.955408 -110.410469) (xy 42.062501 -110.384861)
			(xy 42.171164 -110.367047) (xy 42.280828 -110.35712) (xy 42.390923 -110.355132) (xy 42.500874 -110.361093)
			(xy 42.610108 -110.374973) (xy 42.718057 -110.396698) (xy 42.824156 -110.426157) (xy 42.927853 -110.463194)
			(xy 43.028607 -110.507617) (xy 43.125893 -110.559195) (xy 43.219203 -110.617658) (xy 43.308052 -110.682702)
			(xy 43.391976 -110.753987) (xy 43.470537 -110.831143) (xy 43.543326 -110.913766) (xy 43.609963 -111.001426)
			(xy 43.670101 -111.093666) (xy 43.723427 -111.190005) (xy 43.769662 -111.28994) (xy 43.808566 -111.392952)
			(xy 43.839935 -111.498502) (xy 43.863606 -111.60604) (xy 43.879455 -111.715006) (xy 43.887401 -111.824832)
			(xy 43.887898 -111.879888) (xy 60.396385 -111.879888) (xy 60.40036 -111.769847) (xy 60.412266 -111.66038)
			(xy 60.432039 -111.552057) (xy 60.459577 -111.445443) (xy 60.494736 -111.341095) (xy 60.537333 -111.239555)
			(xy 60.587146 -111.141354) (xy 60.643915 -111.047003) (xy 60.707344 -110.956994) (xy 60.777103 -110.871797)
			(xy 60.852827 -110.791856) (xy 60.934123 -110.717587) (xy 61.020565 -110.649378) (xy 61.111704 -110.587584)
			(xy 61.207065 -110.532528) (xy 61.306149 -110.484496) (xy 61.408442 -110.443739) (xy 61.513408 -110.410469)
			(xy 61.620501 -110.384861) (xy 61.729164 -110.367047) (xy 61.838828 -110.35712) (xy 61.948923 -110.355132)
			(xy 62.058874 -110.361093) (xy 62.168108 -110.374973) (xy 62.276057 -110.396698) (xy 62.382156 -110.426157)
			(xy 62.485853 -110.463194) (xy 62.586607 -110.507617) (xy 62.683893 -110.559195) (xy 62.777203 -110.617658)
			(xy 62.866052 -110.682702) (xy 62.949976 -110.753987) (xy 63.028537 -110.831143) (xy 63.101326 -110.913766)
			(xy 63.167963 -111.001426) (xy 63.228101 -111.093666) (xy 63.281427 -111.190005) (xy 63.327662 -111.28994)
			(xy 63.366566 -111.392952) (xy 63.397935 -111.498502) (xy 63.421606 -111.60604) (xy 63.437455 -111.715006)
			(xy 63.445401 -111.824832) (xy 63.445898 -111.879888) (xy 63.445401 -111.934944) (xy 63.437455 -112.04477)
			(xy 63.421606 -112.153736) (xy 63.397935 -112.261274) (xy 63.366566 -112.366824) (xy 63.327662 -112.469836)
			(xy 63.281427 -112.569771) (xy 63.228101 -112.66611) (xy 63.167963 -112.75835) (xy 63.101326 -112.84601)
			(xy 63.028537 -112.928633) (xy 62.949976 -113.005789) (xy 62.866052 -113.077074) (xy 62.777203 -113.142118)
			(xy 62.683893 -113.200581) (xy 62.586607 -113.252159) (xy 62.485853 -113.296582) (xy 62.382156 -113.333619)
			(xy 62.276057 -113.363078) (xy 62.168108 -113.384803) (xy 62.058874 -113.398683) (xy 61.948923 -113.404644)
			(xy 61.838828 -113.402656) (xy 61.729164 -113.392729) (xy 61.620501 -113.374915) (xy 61.513408 -113.349307)
			(xy 61.408442 -113.316037) (xy 61.306149 -113.27528) (xy 61.207065 -113.227248) (xy 61.111704 -113.172192)
			(xy 61.020565 -113.110398) (xy 60.934123 -113.042189) (xy 60.852827 -112.96792) (xy 60.777103 -112.887979)
			(xy 60.707344 -112.802782) (xy 60.643915 -112.712773) (xy 60.587146 -112.618422) (xy 60.537333 -112.520221)
			(xy 60.494736 -112.418681) (xy 60.459577 -112.314333) (xy 60.432039 -112.207719) (xy 60.412266 -112.099396)
			(xy 60.40036 -111.989929) (xy 60.396385 -111.879888) (xy 43.887898 -111.879888) (xy 43.887401 -111.934944)
			(xy 43.879455 -112.04477) (xy 43.863606 -112.153736) (xy 43.839935 -112.261274) (xy 43.808566 -112.366824)
			(xy 43.769662 -112.469836) (xy 43.723427 -112.569771) (xy 43.670101 -112.66611) (xy 43.609963 -112.75835)
			(xy 43.543326 -112.84601) (xy 43.470537 -112.928633) (xy 43.391976 -113.005789) (xy 43.308052 -113.077074)
			(xy 43.219203 -113.142118) (xy 43.125893 -113.200581) (xy 43.028607 -113.252159) (xy 42.927853 -113.296582)
			(xy 42.824156 -113.333619) (xy 42.718057 -113.363078) (xy 42.610108 -113.384803) (xy 42.500874 -113.398683)
			(xy 42.390923 -113.404644) (xy 42.280828 -113.402656) (xy 42.171164 -113.392729) (xy 42.062501 -113.374915)
			(xy 41.955408 -113.349307) (xy 41.850442 -113.316037) (xy 41.748149 -113.27528) (xy 41.649065 -113.227248)
			(xy 41.553704 -113.172192) (xy 41.462565 -113.110398) (xy 41.376123 -113.042189) (xy 41.294827 -112.96792)
			(xy 41.219103 -112.887979) (xy 41.149344 -112.802782) (xy 41.085915 -112.712773) (xy 41.029146 -112.618422)
			(xy 40.979333 -112.520221) (xy 40.936736 -112.418681) (xy 40.901577 -112.314333) (xy 40.874039 -112.207719)
			(xy 40.854266 -112.099396) (xy 40.84236 -111.989929) (xy 40.838385 -111.879888) (xy 34.042096 -111.879888)
			(xy 34.042096 -119.38) (xy 41.346384 -119.38) (xy 41.350364 -119.290117) (xy 41.362272 -119.200937)
			(xy 41.382015 -119.113159) (xy 41.409439 -119.027469) (xy 41.444328 -118.944538) (xy 41.486411 -118.865016)
			(xy 41.535357 -118.789523) (xy 41.590784 -118.718652) (xy 41.652257 -118.652957) (xy 41.719296 -118.592952)
			(xy 41.791376 -118.539107) (xy 41.867932 -118.491843) (xy 41.948367 -118.45153) (xy 42.032049 -118.418483)
			(xy 42.118324 -118.392962) (xy 42.206518 -118.375166) (xy 42.295939 -118.365233) (xy 42.385888 -118.363243)
			(xy 42.475661 -118.36921) (xy 42.564556 -118.383088) (xy 42.651876 -118.404768) (xy 42.736938 -118.434081)
			(xy 42.819077 -118.470797) (xy 42.897649 -118.514628) (xy 42.97204 -118.565232) (xy 43.041667 -118.622213)
			(xy 43.105986 -118.685125) (xy 43.164494 -118.753475) (xy 43.216731 -118.826728) (xy 43.26229 -118.904311)
			(xy 43.300814 -118.985618) (xy 43.332001 -119.070011) (xy 43.355608 -119.15683) (xy 43.371449 -119.245395)
			(xy 43.379401 -119.335014) (xy 43.379898 -119.38) (xy 60.904384 -119.38) (xy 60.908364 -119.290117)
			(xy 60.920272 -119.200937) (xy 60.940015 -119.113159) (xy 60.967439 -119.027469) (xy 61.002328 -118.944538)
			(xy 61.044411 -118.865016) (xy 61.093357 -118.789523) (xy 61.148784 -118.718652) (xy 61.210257 -118.652957)
			(xy 61.277296 -118.592952) (xy 61.349376 -118.539107) (xy 61.425932 -118.491843) (xy 61.506367 -118.45153)
			(xy 61.590049 -118.418483) (xy 61.676324 -118.392962) (xy 61.764518 -118.375166) (xy 61.853939 -118.365233)
			(xy 61.943888 -118.363243) (xy 62.033661 -118.36921) (xy 62.122556 -118.383088) (xy 62.209876 -118.404768)
			(xy 62.294938 -118.434081) (xy 62.377077 -118.470797) (xy 62.455649 -118.514628) (xy 62.53004 -118.565232)
			(xy 62.599667 -118.622213) (xy 62.663986 -118.685125) (xy 62.722494 -118.753475) (xy 62.774731 -118.826728)
			(xy 62.82029 -118.904311) (xy 62.858814 -118.985618) (xy 62.890001 -119.070011) (xy 62.913608 -119.15683)
			(xy 62.929449 -119.245395) (xy 62.937401 -119.335014) (xy 62.937898 -119.38) (xy 62.937401 -119.424986)
			(xy 62.929449 -119.514605) (xy 62.913608 -119.60317) (xy 62.890001 -119.689989) (xy 62.858814 -119.774382)
			(xy 62.82029 -119.855689) (xy 62.774731 -119.933272) (xy 62.722494 -120.006525) (xy 62.663986 -120.074875)
			(xy 62.599667 -120.137787) (xy 62.53004 -120.194768) (xy 62.455649 -120.245372) (xy 62.377077 -120.289203)
			(xy 62.294938 -120.325919) (xy 62.209876 -120.355232) (xy 62.122556 -120.376912) (xy 62.033661 -120.39079)
			(xy 61.943888 -120.396757) (xy 61.853939 -120.394767) (xy 61.764518 -120.384834) (xy 61.676324 -120.367038)
			(xy 61.590049 -120.341517) (xy 61.506367 -120.30847) (xy 61.425932 -120.268157) (xy 61.349376 -120.220893)
			(xy 61.277296 -120.167048) (xy 61.210257 -120.107043) (xy 61.148784 -120.041348) (xy 61.093357 -119.970477)
			(xy 61.044411 -119.894984) (xy 61.002328 -119.815462) (xy 60.967439 -119.732531) (xy 60.940015 -119.646841)
			(xy 60.920272 -119.559063) (xy 60.908364 -119.469883) (xy 60.904384 -119.38) (xy 43.379898 -119.38)
			(xy 43.379401 -119.424986) (xy 43.371449 -119.514605) (xy 43.355608 -119.60317) (xy 43.332001 -119.689989)
			(xy 43.300814 -119.774382) (xy 43.26229 -119.855689) (xy 43.216731 -119.933272) (xy 43.164494 -120.006525)
			(xy 43.105986 -120.074875) (xy 43.041667 -120.137787) (xy 42.97204 -120.194768) (xy 42.897649 -120.245372)
			(xy 42.819077 -120.289203) (xy 42.736938 -120.325919) (xy 42.651876 -120.355232) (xy 42.564556 -120.376912)
			(xy 42.475661 -120.39079) (xy 42.385888 -120.396757) (xy 42.295939 -120.394767) (xy 42.206518 -120.384834)
			(xy 42.118324 -120.367038) (xy 42.032049 -120.341517) (xy 41.948367 -120.30847) (xy 41.867932 -120.268157)
			(xy 41.791376 -120.220893) (xy 41.719296 -120.167048) (xy 41.652257 -120.107043) (xy 41.590784 -120.041348)
			(xy 41.535357 -119.970477) (xy 41.486411 -119.894984) (xy 41.444328 -119.815462) (xy 41.409439 -119.732531)
			(xy 41.382015 -119.646841) (xy 41.362272 -119.559063) (xy 41.350364 -119.469883) (xy 41.346384 -119.38)
			(xy 34.042096 -119.38) (xy 34.042096 -132.199888) (xy 40.838385 -132.199888) (xy 40.84236 -132.089847)
			(xy 40.854266 -131.98038) (xy 40.874039 -131.872057) (xy 40.901577 -131.765443) (xy 40.936736 -131.661095)
			(xy 40.979333 -131.559555) (xy 41.029146 -131.461354) (xy 41.085915 -131.367003) (xy 41.149344 -131.276994)
			(xy 41.219103 -131.191797) (xy 41.294827 -131.111856) (xy 41.376123 -131.037587) (xy 41.462565 -130.969378)
			(xy 41.553704 -130.907584) (xy 41.649065 -130.852528) (xy 41.748149 -130.804496) (xy 41.850442 -130.763739)
			(xy 41.955408 -130.730469) (xy 42.062501 -130.704861) (xy 42.171164 -130.687047) (xy 42.280828 -130.67712)
			(xy 42.390923 -130.675132) (xy 42.500874 -130.681093) (xy 42.610108 -130.694973) (xy 42.718057 -130.716698)
			(xy 42.824156 -130.746157) (xy 42.927853 -130.783194) (xy 43.028607 -130.827617) (xy 43.125893 -130.879195)
			(xy 43.219203 -130.937658) (xy 43.308052 -131.002702) (xy 43.391976 -131.073987) (xy 43.470537 -131.151143)
			(xy 43.543326 -131.233766) (xy 43.609963 -131.321426) (xy 43.670101 -131.413666) (xy 43.723427 -131.510005)
			(xy 43.769662 -131.60994) (xy 43.808566 -131.712952) (xy 43.839935 -131.818502) (xy 43.863606 -131.92604)
			(xy 43.879455 -132.035006) (xy 43.887401 -132.144832) (xy 43.887898 -132.199888) (xy 60.396385 -132.199888)
			(xy 60.40036 -132.089847) (xy 60.412266 -131.98038) (xy 60.432039 -131.872057) (xy 60.459577 -131.765443)
			(xy 60.494736 -131.661095) (xy 60.537333 -131.559555) (xy 60.587146 -131.461354) (xy 60.643915 -131.367003)
			(xy 60.707344 -131.276994) (xy 60.777103 -131.191797) (xy 60.852827 -131.111856) (xy 60.934123 -131.037587)
			(xy 61.020565 -130.969378) (xy 61.111704 -130.907584) (xy 61.207065 -130.852528) (xy 61.306149 -130.804496)
			(xy 61.408442 -130.763739) (xy 61.513408 -130.730469) (xy 61.620501 -130.704861) (xy 61.729164 -130.687047)
			(xy 61.838828 -130.67712) (xy 61.948923 -130.675132) (xy 62.058874 -130.681093) (xy 62.168108 -130.694973)
			(xy 62.276057 -130.716698) (xy 62.382156 -130.746157) (xy 62.485853 -130.783194) (xy 62.586607 -130.827617)
			(xy 62.683893 -130.879195) (xy 62.777203 -130.937658) (xy 62.866052 -131.002702) (xy 62.949976 -131.073987)
			(xy 63.028537 -131.151143) (xy 63.101326 -131.233766) (xy 63.167963 -131.321426) (xy 63.228101 -131.413666)
			(xy 63.281427 -131.510005) (xy 63.327662 -131.60994) (xy 63.366566 -131.712952) (xy 63.397935 -131.818502)
			(xy 63.421606 -131.92604) (xy 63.437455 -132.035006) (xy 63.445401 -132.144832) (xy 63.445898 -132.199888)
			(xy 63.445401 -132.254944) (xy 63.437455 -132.36477) (xy 63.421606 -132.473736) (xy 63.397935 -132.581274)
			(xy 63.366566 -132.686824) (xy 63.327662 -132.789836) (xy 63.281427 -132.889771) (xy 63.228101 -132.98611)
			(xy 63.167963 -133.07835) (xy 63.101326 -133.16601) (xy 63.028537 -133.248633) (xy 62.949976 -133.325789)
			(xy 62.866052 -133.397074) (xy 62.777203 -133.462118) (xy 62.683893 -133.520581) (xy 62.586607 -133.572159)
			(xy 62.485853 -133.616582) (xy 62.382156 -133.653619) (xy 62.276057 -133.683078) (xy 62.168108 -133.704803)
			(xy 62.058874 -133.718683) (xy 61.948923 -133.724644) (xy 61.838828 -133.722656) (xy 61.729164 -133.712729)
			(xy 61.620501 -133.694915) (xy 61.513408 -133.669307) (xy 61.408442 -133.636037) (xy 61.306149 -133.59528)
			(xy 61.207065 -133.547248) (xy 61.111704 -133.492192) (xy 61.020565 -133.430398) (xy 60.934123 -133.362189)
			(xy 60.852827 -133.28792) (xy 60.777103 -133.207979) (xy 60.707344 -133.122782) (xy 60.643915 -133.032773)
			(xy 60.587146 -132.938422) (xy 60.537333 -132.840221) (xy 60.494736 -132.738681) (xy 60.459577 -132.634333)
			(xy 60.432039 -132.527719) (xy 60.412266 -132.419396) (xy 60.40036 -132.309929) (xy 60.396385 -132.199888)
			(xy 43.887898 -132.199888) (xy 43.887401 -132.254944) (xy 43.879455 -132.36477) (xy 43.863606 -132.473736)
			(xy 43.839935 -132.581274) (xy 43.808566 -132.686824) (xy 43.769662 -132.789836) (xy 43.723427 -132.889771)
			(xy 43.670101 -132.98611) (xy 43.609963 -133.07835) (xy 43.543326 -133.16601) (xy 43.470537 -133.248633)
			(xy 43.391976 -133.325789) (xy 43.308052 -133.397074) (xy 43.219203 -133.462118) (xy 43.125893 -133.520581)
			(xy 43.028607 -133.572159) (xy 42.927853 -133.616582) (xy 42.824156 -133.653619) (xy 42.718057 -133.683078)
			(xy 42.610108 -133.704803) (xy 42.500874 -133.718683) (xy 42.390923 -133.724644) (xy 42.280828 -133.722656)
			(xy 42.171164 -133.712729) (xy 42.062501 -133.694915) (xy 41.955408 -133.669307) (xy 41.850442 -133.636037)
			(xy 41.748149 -133.59528) (xy 41.649065 -133.547248) (xy 41.553704 -133.492192) (xy 41.462565 -133.430398)
			(xy 41.376123 -133.362189) (xy 41.294827 -133.28792) (xy 41.219103 -133.207979) (xy 41.149344 -133.122782)
			(xy 41.085915 -133.032773) (xy 41.029146 -132.938422) (xy 40.979333 -132.840221) (xy 40.936736 -132.738681)
			(xy 40.901577 -132.634333) (xy 40.874039 -132.527719) (xy 40.854266 -132.419396) (xy 40.84236 -132.309929)
			(xy 40.838385 -132.199888) (xy 34.042096 -132.199888) (xy 34.042096 -139.7) (xy 41.346384 -139.7)
			(xy 41.350364 -139.610117) (xy 41.362272 -139.520937) (xy 41.382015 -139.433159) (xy 41.409439 -139.347469)
			(xy 41.444328 -139.264538) (xy 41.486411 -139.185016) (xy 41.535357 -139.109523) (xy 41.590784 -139.038652)
			(xy 41.652257 -138.972957) (xy 41.719296 -138.912952) (xy 41.791376 -138.859107) (xy 41.867932 -138.811843)
			(xy 41.948367 -138.77153) (xy 42.032049 -138.738483) (xy 42.118324 -138.712962) (xy 42.206518 -138.695166)
			(xy 42.295939 -138.685233) (xy 42.385888 -138.683243) (xy 42.475661 -138.68921) (xy 42.564556 -138.703088)
			(xy 42.651876 -138.724768) (xy 42.736938 -138.754081) (xy 42.819077 -138.790797) (xy 42.897649 -138.834628)
			(xy 42.97204 -138.885232) (xy 43.041667 -138.942213) (xy 43.105986 -139.005125) (xy 43.164494 -139.073475)
			(xy 43.216731 -139.146728) (xy 43.26229 -139.224311) (xy 43.300814 -139.305618) (xy 43.332001 -139.390011)
			(xy 43.355608 -139.47683) (xy 43.371449 -139.565395) (xy 43.379401 -139.655014) (xy 43.379898 -139.7)
			(xy 60.904384 -139.7) (xy 60.908364 -139.610117) (xy 60.920272 -139.520937) (xy 60.940015 -139.433159)
			(xy 60.967439 -139.347469) (xy 61.002328 -139.264538) (xy 61.044411 -139.185016) (xy 61.093357 -139.109523)
			(xy 61.148784 -139.038652) (xy 61.210257 -138.972957) (xy 61.277296 -138.912952) (xy 61.349376 -138.859107)
			(xy 61.425932 -138.811843) (xy 61.506367 -138.77153) (xy 61.590049 -138.738483) (xy 61.676324 -138.712962)
			(xy 61.764518 -138.695166) (xy 61.853939 -138.685233) (xy 61.943888 -138.683243) (xy 62.033661 -138.68921)
			(xy 62.122556 -138.703088) (xy 62.209876 -138.724768) (xy 62.294938 -138.754081) (xy 62.377077 -138.790797)
			(xy 62.455649 -138.834628) (xy 62.53004 -138.885232) (xy 62.599667 -138.942213) (xy 62.663986 -139.005125)
			(xy 62.722494 -139.073475) (xy 62.774731 -139.146728) (xy 62.82029 -139.224311) (xy 62.858814 -139.305618)
			(xy 62.890001 -139.390011) (xy 62.913608 -139.47683) (xy 62.929449 -139.565395) (xy 62.937401 -139.655014)
			(xy 62.937898 -139.7) (xy 62.937401 -139.744986) (xy 62.929449 -139.834605) (xy 62.913608 -139.92317)
			(xy 62.890001 -140.009989) (xy 62.858814 -140.094382) (xy 62.82029 -140.175689) (xy 62.774731 -140.253272)
			(xy 62.722494 -140.326525) (xy 62.663986 -140.394875) (xy 62.599667 -140.457787) (xy 62.53004 -140.514768)
			(xy 62.455649 -140.565372) (xy 62.377077 -140.609203) (xy 62.294938 -140.645919) (xy 62.209876 -140.675232)
			(xy 62.122556 -140.696912) (xy 62.033661 -140.71079) (xy 61.943888 -140.716757) (xy 61.853939 -140.714767)
			(xy 61.764518 -140.704834) (xy 61.676324 -140.687038) (xy 61.590049 -140.661517) (xy 61.506367 -140.62847)
			(xy 61.425932 -140.588157) (xy 61.349376 -140.540893) (xy 61.277296 -140.487048) (xy 61.210257 -140.427043)
			(xy 61.148784 -140.361348) (xy 61.093357 -140.290477) (xy 61.044411 -140.214984) (xy 61.002328 -140.135462)
			(xy 60.967439 -140.052531) (xy 60.940015 -139.966841) (xy 60.920272 -139.879063) (xy 60.908364 -139.789883)
			(xy 60.904384 -139.7) (xy 43.379898 -139.7) (xy 43.379401 -139.744986) (xy 43.371449 -139.834605)
			(xy 43.355608 -139.92317) (xy 43.332001 -140.009989) (xy 43.300814 -140.094382) (xy 43.26229 -140.175689)
			(xy 43.216731 -140.253272) (xy 43.164494 -140.326525) (xy 43.105986 -140.394875) (xy 43.041667 -140.457787)
			(xy 42.97204 -140.514768) (xy 42.897649 -140.565372) (xy 42.819077 -140.609203) (xy 42.736938 -140.645919)
			(xy 42.651876 -140.675232) (xy 42.564556 -140.696912) (xy 42.475661 -140.71079) (xy 42.385888 -140.716757)
			(xy 42.295939 -140.714767) (xy 42.206518 -140.704834) (xy 42.118324 -140.687038) (xy 42.032049 -140.661517)
			(xy 41.948367 -140.62847) (xy 41.867932 -140.588157) (xy 41.791376 -140.540893) (xy 41.719296 -140.487048)
			(xy 41.652257 -140.427043) (xy 41.590784 -140.361348) (xy 41.535357 -140.290477) (xy 41.486411 -140.214984)
			(xy 41.444328 -140.135462) (xy 41.409439 -140.052531) (xy 41.382015 -139.966841) (xy 41.362272 -139.879063)
			(xy 41.350364 -139.789883) (xy 41.346384 -139.7) (xy 34.042096 -139.7) (xy 34.042096 -149.315932)
			(xy 34.042525 -149.326) (xy 34.050247 -149.344596) (xy 34.057082 -149.352) (xy 34.057082 -169.142918)
			(xy 34.057508 -169.152987) (xy 34.065225 -169.171589) (xy 34.072068 -169.178986) (xy 34.423096 -169.530014)
			(xy 34.43049 -169.53687) (xy 34.449089 -169.54462) (xy 34.459164 -169.545)
		)
		(stroke
			(width 0)
			(type solid)
		)
		(fill yes)
		(layer "In7.Cu")
		(net "P52V_HS2")
	)
	(gr_poly
		(pts
			(xy 208.15808 -94.941898) (xy 208.165686 -94.940386) (xy 208.179524 -94.933403) (xy 208.185258 -94.928182)
			(xy 208.849468 -94.263972) (xy 208.855564 -94.253812) (xy 208.857342 -94.24797) (xy 208.870462 -94.207934)
			(xy 208.902728 -94.1301) (xy 208.941651 -94.055372) (xy 208.986933 -93.984317) (xy 209.038232 -93.917476)
			(xy 209.095157 -93.855357) (xy 209.157276 -93.798432) (xy 209.224117 -93.747133) (xy 209.295172 -93.701851)
			(xy 209.3699 -93.662928) (xy 209.447734 -93.630662) (xy 209.48777 -93.617542) (xy 209.493612 -93.615764)
			(xy 209.503772 -93.609668) (xy 209.983578 -93.129862) (xy 209.990683 -93.122068) (xy 209.998402 -93.102467)
			(xy 209.997579 -93.081417) (xy 209.993484 -93.071696) (xy 209.951574 -92.985082) (xy 209.946495 -92.975775)
			(xy 209.930372 -92.962046) (xy 209.910069 -92.956027) (xy 209.899504 -92.956888) (xy 209.869406 -92.960461)
			(xy 209.808909 -92.964273) (xy 209.7786 -92.964508) (xy 209.735252 -92.964022) (xy 209.648905 -92.95625)
			(xy 209.563601 -92.94077) (xy 209.480029 -92.917706) (xy 209.398861 -92.887243) (xy 209.320751 -92.849627)
			(xy 209.246326 -92.80516) (xy 209.176188 -92.754201) (xy 209.110899 -92.69716) (xy 209.050986 -92.634497)
			(xy 208.996932 -92.566715) (xy 208.949171 -92.49436) (xy 208.908089 -92.418016) (xy 208.874015 -92.338296)
			(xy 208.847224 -92.255843) (xy 208.827933 -92.171321) (xy 208.816295 -92.085409) (xy 208.812406 -91.9988)
			(xy 208.816295 -91.912191) (xy 208.827933 -91.826279) (xy 208.847224 -91.741757) (xy 208.874015 -91.659304)
			(xy 208.908089 -91.579584) (xy 208.949171 -91.50324) (xy 208.996932 -91.430885) (xy 209.050986 -91.363103)
			(xy 209.110899 -91.30044) (xy 209.176188 -91.243399) (xy 209.246326 -91.19244) (xy 209.320751 -91.147973)
			(xy 209.398861 -91.110357) (xy 209.480029 -91.079894) (xy 209.563601 -91.05683) (xy 209.648905 -91.04135)
			(xy 209.735252 -91.033578) (xy 209.7786 -91.033092) (xy 209.821819 -91.033573) (xy 209.907912 -91.041299)
			(xy 209.99297 -91.056689) (xy 210.076312 -91.079621) (xy 210.15727 -91.10991) (xy 210.235197 -91.147314)
			(xy 210.309469 -91.191534) (xy 210.344766 -91.21648) (xy 210.34502 -91.21648) (xy 210.352776 -91.22158)
			(xy 210.3707 -91.226347) (xy 210.389141 -91.224375) (xy 210.397598 -91.220544) (xy 210.47837 -91.179396)
			(xy 210.486483 -91.174781) (xy 210.498955 -91.160915) (xy 210.505649 -91.143508) (xy 210.506056 -91.134184)
			(xy 210.506056 -83.001866) (xy 210.505725 -82.993321) (xy 210.500095 -82.977185) (xy 210.489472 -82.963797)
			(xy 210.482434 -82.95894) (xy 210.411314 -82.913982) (xy 210.402635 -82.908908) (xy 210.382859 -82.905371)
			(xy 210.37296 -82.907124) (xy 210.361784 -82.909664) (xy 210.356958 -82.91195) (xy 210.276428 -82.949248)
			(xy 210.112325 -83.016882) (xy 209.945116 -83.076422) (xy 209.775198 -83.127725) (xy 209.602978 -83.17067)
			(xy 209.428867 -83.205153) (xy 209.253279 -83.231093) (xy 209.076634 -83.248427) (xy 208.899353 -83.257114)
			(xy 208.810606 -83.257644) (xy 208.810098 -83.257644) (xy 208.724925 -83.257145) (xy 208.554768 -83.24916)
			(xy 208.385171 -83.233209) (xy 208.216508 -83.209326) (xy 208.049151 -83.177563) (xy 207.883466 -83.137991)
			(xy 207.719818 -83.090696) (xy 207.558567 -83.035783) (xy 207.400066 -82.973372) (xy 207.244666 -82.9036)
			(xy 207.092706 -82.826621) (xy 206.944522 -82.742604) (xy 206.800439 -82.651733) (xy 206.660773 -82.554209)
			(xy 206.525832 -82.450246) (xy 206.395913 -82.340072) (xy 206.2713 -82.223929) (xy 206.152268 -82.102073)
			(xy 206.039078 -81.974772) (xy 205.93198 -81.842305) (xy 205.831209 -81.704964) (xy 205.736986 -81.56305)
			(xy 205.649518 -81.416876) (xy 205.568998 -81.266763) (xy 205.495602 -81.113041) (xy 205.429493 -80.956047)
			(xy 205.370815 -80.796128) (xy 205.319697 -80.633633) (xy 205.276251 -80.468922) (xy 205.240574 -80.302355)
			(xy 205.212744 -80.134298) (xy 205.192821 -79.965122) (xy 205.18085 -79.795198) (xy 205.176856 -79.6249)
			(xy 205.18085 -79.454602) (xy 205.192821 -79.284678) (xy 205.212744 -79.115502) (xy 205.240574 -78.947445)
			(xy 205.276251 -78.780878) (xy 205.319697 -78.616167) (xy 205.370815 -78.453672) (xy 205.429493 -78.293753)
			(xy 205.495602 -78.136759) (xy 205.568998 -77.983037) (xy 205.649518 -77.832924) (xy 205.736986 -77.68675)
			(xy 205.831209 -77.544836) (xy 205.93198 -77.407495) (xy 206.039078 -77.275028) (xy 206.152268 -77.147727)
			(xy 206.2713 -77.025871) (xy 206.395913 -76.909728) (xy 206.525832 -76.799554) (xy 206.660773 -76.695591)
			(xy 206.800439 -76.598067) (xy 206.944522 -76.507196) (xy 207.092706 -76.423179) (xy 207.244666 -76.3462)
			(xy 207.400066 -76.276428) (xy 207.558567 -76.214017) (xy 207.719818 -76.159104) (xy 207.883466 -76.111809)
			(xy 208.049151 -76.072237) (xy 208.216508 -76.040474) (xy 208.385171 -76.016591) (xy 208.554768 -76.00064)
			(xy 208.724925 -75.992655) (xy 208.810098 -75.992228) (xy 208.810606 -75.992228) (xy 208.899353 -75.99277)
			(xy 209.076634 -76.001449) (xy 209.25328 -76.018777) (xy 209.428869 -76.044712) (xy 209.602982 -76.079192)
			(xy 209.775202 -76.122136) (xy 209.94512 -76.173439) (xy 210.112329 -76.232981) (xy 210.27643 -76.300618)
			(xy 210.356958 -76.337922) (xy 210.361784 -76.340208) (xy 210.37296 -76.342748) (xy 210.38286 -76.344498)
			(xy 210.402636 -76.340965) (xy 210.411314 -76.33589) (xy 210.482434 -76.290932) (xy 210.489486 -76.286087)
			(xy 210.500125 -76.2727) (xy 210.505759 -76.256556) (xy 210.506056 -76.248006) (xy 210.506056 -54.44109)
			(xy 210.50563 -54.431022) (xy 210.497908 -54.412424) (xy 210.49107 -54.405022) (xy 209.744564 -53.658516)
			(xy 209.737452 -53.65115) (xy 209.718656 -53.64353) (xy 183.198008 -53.64353) (xy 183.187936 -53.643109)
			(xy 183.169327 -53.6354) (xy 183.16194 -53.628544) (xy 180.111146 -50.57775) (xy 180.104302 -50.570351)
			(xy 180.096579 -50.551752) (xy 180.09616 -50.541682) (xy 180.09616 -49.530254) (xy 180.095727 -49.520188)
			(xy 180.087997 -49.5016) (xy 180.081174 -49.494186) (xy 179.859686 -49.272698) (xy 179.852574 -49.265332)
			(xy 179.833778 -49.257712) (xy 178.403758 -49.257712) (xy 178.393691 -49.258143) (xy 178.375099 -49.26587)
			(xy 178.36769 -49.272698) (xy 178.118262 -49.522126) (xy 178.110896 -49.529238) (xy 178.103276 -49.548034)
			(xy 178.103276 -49.688496) (xy 178.104034 -49.700684) (xy 178.115298 -49.722312) (xy 178.124866 -49.729898)
			(xy 178.202844 -49.78527) (xy 178.226974 -49.788572) (xy 178.238658 -49.784508) (xy 178.269188 -49.774486)
			(xy 178.332517 -49.76364) (xy 178.364642 -49.762918) (xy 178.391889 -49.763407) (xy 178.445829 -49.771168)
			(xy 178.498115 -49.786526) (xy 178.547683 -49.809168) (xy 178.593525 -49.838633) (xy 178.634708 -49.874322)
			(xy 178.670392 -49.915508) (xy 178.699853 -49.961353) (xy 178.722489 -50.010924) (xy 178.737841 -50.063212)
			(xy 178.745596 -50.117153) (xy 178.745596 -50.171647) (xy 178.737841 -50.225588) (xy 178.722489 -50.277876)
			(xy 178.699853 -50.327447) (xy 178.670392 -50.373292) (xy 178.634708 -50.414478) (xy 178.593525 -50.450167)
			(xy 178.547683 -50.479632) (xy 178.498115 -50.502274) (xy 178.445829 -50.517632) (xy 178.391889 -50.525393)
			(xy 178.364642 -50.525934) (xy 178.332516 -50.52523) (xy 178.269184 -50.51438) (xy 178.238658 -50.504344)
			(xy 178.226974 -50.50028) (xy 178.202844 -50.503582) (xy 178.124866 -50.558954) (xy 178.115271 -50.566525)
			(xy 178.10398 -50.588156) (xy 178.103276 -50.600356) (xy 178.103276 -54.737) (xy 180.465982 -54.737)
			(xy 180.470053 -54.681378) (xy 180.482179 -54.626941) (xy 180.502102 -54.57485) (xy 180.529398 -54.526215)
			(xy 180.563484 -54.482072) (xy 180.603633 -54.443363) (xy 180.648991 -54.410912) (xy 180.698591 -54.385411)
			(xy 180.751375 -54.367404) (xy 180.806218 -54.357274) (xy 180.861952 -54.355237) (xy 180.917389 -54.361337)
			(xy 180.971346 -54.375443) (xy 181.022675 -54.397255) (xy 181.070281 -54.426309) (xy 181.113149 -54.461984)
			(xy 181.150366 -54.503521) (xy 181.181139 -54.550034) (xy 181.204811 -54.600531) (xy 181.220879 -54.653938)
			(xy 181.228999 -54.709114) (xy 181.229508 -54.737) (xy 181.228999 -54.764886) (xy 181.220879 -54.820062)
			(xy 181.204811 -54.873469) (xy 181.181139 -54.923966) (xy 181.150366 -54.970479) (xy 181.113149 -55.012016)
			(xy 181.070281 -55.047691) (xy 181.022675 -55.076745) (xy 180.971346 -55.098557) (xy 180.917389 -55.112663)
			(xy 180.861952 -55.118763) (xy 180.806218 -55.116726) (xy 180.751375 -55.106596) (xy 180.698591 -55.088589)
			(xy 180.648991 -55.063088) (xy 180.603633 -55.030637) (xy 180.563484 -54.991928) (xy 180.529398 -54.947785)
			(xy 180.502102 -54.89915) (xy 180.482179 -54.847059) (xy 180.470053 -54.792622) (xy 180.465982 -54.737)
			(xy 178.103276 -54.737) (xy 178.103276 -57.693052) (xy 178.102843 -57.703117) (xy 178.095112 -57.721706)
			(xy 178.08829 -57.72912) (xy 176.573688 -59.243722) (xy 176.566293 -59.250575) (xy 176.547694 -59.258317)
			(xy 176.53762 -59.258708) (xy 171.442126 -59.258708) (xy 171.432062 -59.258272) (xy 171.413476 -59.250539)
			(xy 171.406058 -59.243722) (xy 168.942512 -56.780176) (xy 168.9354 -56.77281) (xy 168.916604 -56.76519)
			(xy 159.888682 -56.76519) (xy 159.869886 -56.77281) (xy 159.862774 -56.780176) (xy 156.603081 -60.039758)
			(xy 161.926522 -60.039758) (xy 161.930593 -59.984136) (xy 161.942719 -59.929699) (xy 161.962642 -59.877608)
			(xy 161.989938 -59.828973) (xy 162.024024 -59.78483) (xy 162.064173 -59.746121) (xy 162.109531 -59.71367)
			(xy 162.159131 -59.688169) (xy 162.211915 -59.670162) (xy 162.266758 -59.660032) (xy 162.322492 -59.657995)
			(xy 162.377929 -59.664095) (xy 162.431886 -59.678201) (xy 162.483215 -59.700013) (xy 162.530821 -59.729067)
			(xy 162.573689 -59.764742) (xy 162.610906 -59.806279) (xy 162.641679 -59.852792) (xy 162.665351 -59.903289)
			(xy 162.681419 -59.956696) (xy 162.689539 -60.011872) (xy 162.690048 -60.039758) (xy 162.689539 -60.067644)
			(xy 162.681419 -60.12282) (xy 162.665351 -60.176227) (xy 162.641679 -60.226724) (xy 162.610906 -60.273237)
			(xy 162.573689 -60.314774) (xy 162.530821 -60.350449) (xy 162.489282 -60.3758) (xy 165.632388 -60.3758)
			(xy 165.636418 -60.291199) (xy 165.648471 -60.207364) (xy 165.668439 -60.125055) (xy 165.696141 -60.045016)
			(xy 165.731325 -59.967973) (xy 165.773674 -59.894623) (xy 165.822803 -59.825631) (xy 165.878268 -59.761621)
			(xy 165.939566 -59.703173) (xy 166.006142 -59.650817) (xy 166.077394 -59.605027) (xy 166.152675 -59.566216)
			(xy 166.231305 -59.534737) (xy 166.312572 -59.510876) (xy 166.395738 -59.494847) (xy 166.480052 -59.486796)
			(xy 166.5224 -59.486292) (xy 166.522908 -59.486292) (xy 166.56924 -59.486898) (xy 166.661398 -59.496569)
			(xy 166.752052 -59.515765) (xy 166.840221 -59.544277) (xy 166.882826 -59.562492) (xy 166.892768 -59.566298)
			(xy 166.914032 -59.566298) (xy 166.923974 -59.562492) (xy 166.966577 -59.54427) (xy 167.054744 -59.515752)
			(xy 167.1454 -59.49656) (xy 167.23756 -59.4869) (xy 167.283892 -59.486292) (xy 167.2844 -59.486292)
			(xy 167.326748 -59.486796) (xy 167.411062 -59.494847) (xy 167.494228 -59.510876) (xy 167.575495 -59.534737)
			(xy 167.654125 -59.566216) (xy 167.729406 -59.605027) (xy 167.800658 -59.650817) (xy 167.867234 -59.703173)
			(xy 167.928532 -59.761621) (xy 167.983997 -59.825631) (xy 168.033126 -59.894623) (xy 168.075475 -59.967973)
			(xy 168.110659 -60.045016) (xy 168.138361 -60.125055) (xy 168.158329 -60.207364) (xy 168.170382 -60.291199)
			(xy 168.174413 -60.3758) (xy 168.170382 -60.460401) (xy 168.158329 -60.544236) (xy 168.138361 -60.626545)
			(xy 168.110659 -60.706584) (xy 168.075475 -60.783627) (xy 168.033126 -60.856977) (xy 167.983997 -60.925969)
			(xy 167.928532 -60.989979) (xy 167.867234 -61.048427) (xy 167.800658 -61.100783) (xy 167.729406 -61.146573)
			(xy 167.654125 -61.185384) (xy 167.575495 -61.216863) (xy 167.494228 -61.240724) (xy 167.411062 -61.256753)
			(xy 167.326748 -61.264804) (xy 167.2844 -61.265308) (xy 167.283892 -61.265308) (xy 167.23756 -61.264702)
			(xy 167.145402 -61.255031) (xy 167.054748 -61.235835) (xy 166.966579 -61.207323) (xy 166.923974 -61.189108)
			(xy 166.914032 -61.185302) (xy 166.892768 -61.185302) (xy 166.882826 -61.189108) (xy 166.840223 -61.20733)
			(xy 166.752056 -61.235848) (xy 166.6614 -61.25504) (xy 166.56924 -61.2647) (xy 166.522908 -61.265308)
			(xy 166.5224 -61.265308) (xy 166.480052 -61.264804) (xy 166.395738 -61.256753) (xy 166.312572 -61.240724)
			(xy 166.231305 -61.216863) (xy 166.152675 -61.185384) (xy 166.077394 -61.146573) (xy 166.006142 -61.100783)
			(xy 165.939566 -61.048427) (xy 165.878268 -60.989979) (xy 165.822803 -60.925969) (xy 165.773674 -60.856977)
			(xy 165.731325 -60.783627) (xy 165.696141 -60.706584) (xy 165.668439 -60.626545) (xy 165.648471 -60.544236)
			(xy 165.636418 -60.460401) (xy 165.632388 -60.3758) (xy 162.489282 -60.3758) (xy 162.483215 -60.379503)
			(xy 162.431886 -60.401315) (xy 162.377929 -60.415421) (xy 162.322492 -60.421521) (xy 162.266758 -60.419484)
			(xy 162.211915 -60.409354) (xy 162.159131 -60.391347) (xy 162.109531 -60.365846) (xy 162.064173 -60.333395)
			(xy 162.024024 -60.294686) (xy 161.989938 -60.250543) (xy 161.962642 -60.201908) (xy 161.942719 -60.149817)
			(xy 161.930593 -60.09538) (xy 161.926522 -60.039758) (xy 156.603081 -60.039758) (xy 155.895921 -60.746894)
			(xy 157.250382 -60.746894) (xy 157.254453 -60.691272) (xy 157.266579 -60.636835) (xy 157.286502 -60.584744)
			(xy 157.313798 -60.536109) (xy 157.347884 -60.491966) (xy 157.388033 -60.453257) (xy 157.433391 -60.420806)
			(xy 157.482991 -60.395305) (xy 157.535775 -60.377298) (xy 157.590618 -60.367168) (xy 157.646352 -60.365131)
			(xy 157.701789 -60.371231) (xy 157.755746 -60.385337) (xy 157.807075 -60.407149) (xy 157.854681 -60.436203)
			(xy 157.897549 -60.471878) (xy 157.934766 -60.513415) (xy 157.965539 -60.559928) (xy 157.989211 -60.610425)
			(xy 158.005279 -60.663832) (xy 158.013399 -60.719008) (xy 158.013908 -60.746894) (xy 158.013399 -60.77478)
			(xy 158.005279 -60.829956) (xy 157.989211 -60.883363) (xy 157.965539 -60.93386) (xy 157.934766 -60.980373)
			(xy 157.897549 -61.02191) (xy 157.854681 -61.057585) (xy 157.807075 -61.086639) (xy 157.755746 -61.108451)
			(xy 157.701789 -61.122557) (xy 157.646352 -61.128657) (xy 157.590618 -61.12662) (xy 157.535775 -61.11649)
			(xy 157.482991 -61.098483) (xy 157.433391 -61.072982) (xy 157.388033 -61.040531) (xy 157.347884 -61.001822)
			(xy 157.313798 -60.957679) (xy 157.286502 -60.909044) (xy 157.266579 -60.856953) (xy 157.254453 -60.802516)
			(xy 157.250382 -60.746894) (xy 155.895921 -60.746894) (xy 155.123989 -61.5188) (xy 163.676582 -61.5188)
			(xy 163.680653 -61.463178) (xy 163.692779 -61.408741) (xy 163.712702 -61.35665) (xy 163.739998 -61.308015)
			(xy 163.774084 -61.263872) (xy 163.814233 -61.225163) (xy 163.859591 -61.192712) (xy 163.909191 -61.167211)
			(xy 163.961975 -61.149204) (xy 164.016818 -61.139074) (xy 164.072552 -61.137037) (xy 164.127989 -61.143137)
			(xy 164.181946 -61.157243) (xy 164.233275 -61.179055) (xy 164.280881 -61.208109) (xy 164.323749 -61.243784)
			(xy 164.360966 -61.285321) (xy 164.391739 -61.331834) (xy 164.415411 -61.382331) (xy 164.431479 -61.435738)
			(xy 164.439599 -61.490914) (xy 164.440108 -61.5188) (xy 164.439599 -61.546686) (xy 164.431479 -61.601862)
			(xy 164.415411 -61.655269) (xy 164.391739 -61.705766) (xy 164.360966 -61.752279) (xy 164.323749 -61.793816)
			(xy 164.280881 -61.829491) (xy 164.233275 -61.858545) (xy 164.181946 -61.880357) (xy 164.127989 -61.894463)
			(xy 164.072552 -61.900563) (xy 164.016818 -61.898526) (xy 163.961975 -61.888396) (xy 163.909191 -61.870389)
			(xy 163.859591 -61.844888) (xy 163.814233 -61.812437) (xy 163.774084 -61.773728) (xy 163.739998 -61.729585)
			(xy 163.712702 -61.68095) (xy 163.692779 -61.628859) (xy 163.680653 -61.574422) (xy 163.676582 -61.5188)
			(xy 155.123989 -61.5188) (xy 153.945643 -62.697106) (xy 163.32149 -62.697106) (xy 163.325561 -62.641484)
			(xy 163.337687 -62.587047) (xy 163.35761 -62.534956) (xy 163.384906 -62.486321) (xy 163.418992 -62.442178)
			(xy 163.459141 -62.403469) (xy 163.504499 -62.371018) (xy 163.554099 -62.345517) (xy 163.606883 -62.32751)
			(xy 163.661726 -62.31738) (xy 163.71746 -62.315343) (xy 163.772897 -62.321443) (xy 163.826854 -62.335549)
			(xy 163.878183 -62.357361) (xy 163.925789 -62.386415) (xy 163.968657 -62.42209) (xy 164.005874 -62.463627)
			(xy 164.036647 -62.51014) (xy 164.060319 -62.560637) (xy 164.076387 -62.614044) (xy 164.084507 -62.66922)
			(xy 164.085016 -62.697106) (xy 164.084507 -62.724992) (xy 164.076387 -62.780168) (xy 164.060319 -62.833575)
			(xy 164.036647 -62.884072) (xy 164.005874 -62.930585) (xy 163.968657 -62.972122) (xy 163.925789 -63.007797)
			(xy 163.878183 -63.036851) (xy 163.826854 -63.058663) (xy 163.772897 -63.072769) (xy 163.71746 -63.078869)
			(xy 163.661726 -63.076832) (xy 163.606883 -63.066702) (xy 163.554099 -63.048695) (xy 163.504499 -63.023194)
			(xy 163.459141 -62.990743) (xy 163.418992 -62.952034) (xy 163.384906 -62.907891) (xy 163.35761 -62.859256)
			(xy 163.337687 -62.807165) (xy 163.325561 -62.752728) (xy 163.32149 -62.697106) (xy 153.945643 -62.697106)
			(xy 152.405334 -64.237362) (xy 152.397968 -64.244474) (xy 152.390348 -64.26327) (xy 152.390348 -64.648842)
			(xy 154.46578 -64.648842) (xy 154.469851 -64.59322) (xy 154.481977 -64.538783) (xy 154.5019 -64.486692)
			(xy 154.529196 -64.438057) (xy 154.563282 -64.393914) (xy 154.603431 -64.355205) (xy 154.648789 -64.322754)
			(xy 154.698389 -64.297253) (xy 154.751173 -64.279246) (xy 154.806016 -64.269116) (xy 154.86175 -64.267079)
			(xy 154.917187 -64.273179) (xy 154.971144 -64.287285) (xy 155.022473 -64.309097) (xy 155.070079 -64.338151)
			(xy 155.112947 -64.373826) (xy 155.150164 -64.415363) (xy 155.180937 -64.461876) (xy 155.204609 -64.512373)
			(xy 155.220677 -64.56578) (xy 155.228797 -64.620956) (xy 155.229306 -64.648842) (xy 155.228797 -64.676728)
			(xy 155.220677 -64.731904) (xy 155.204609 -64.785311) (xy 155.180937 -64.835808) (xy 155.150164 -64.882321)
			(xy 155.112947 -64.923858) (xy 155.070079 -64.959533) (xy 155.022473 -64.988587) (xy 154.971144 -65.010399)
			(xy 154.917187 -65.024505) (xy 154.86175 -65.030605) (xy 154.806016 -65.028568) (xy 154.751173 -65.018438)
			(xy 154.698389 -65.000431) (xy 154.648789 -64.97493) (xy 154.603431 -64.942479) (xy 154.563282 -64.90377)
			(xy 154.529196 -64.859627) (xy 154.5019 -64.810992) (xy 154.481977 -64.758901) (xy 154.469851 -64.704464)
			(xy 154.46578 -64.648842) (xy 152.390348 -64.648842) (xy 152.390348 -65.913) (xy 153.466292 -65.913)
			(xy 153.466719 -65.887311) (xy 153.473615 -65.836397) (xy 153.487282 -65.786869) (xy 153.507472 -65.739623)
			(xy 153.533821 -65.695515) (xy 153.565851 -65.655342) (xy 153.602983 -65.619832) (xy 153.623518 -65.60439)
			(xy 153.623772 -65.604136) (xy 153.632665 -65.596804) (xy 153.643487 -65.576491) (xy 153.6446 -65.56502)
			(xy 153.64714 -65.48501) (xy 153.647027 -65.473357) (xy 153.637636 -65.452056) (xy 153.629106 -65.444116)
			(xy 153.628852 -65.444116) (xy 153.60778 -65.425882) (xy 153.570644 -65.384336) (xy 153.539942 -65.337833)
			(xy 153.516327 -65.287362) (xy 153.500298 -65.233993) (xy 153.492198 -65.178862) (xy 153.491692 -65.151)
			(xy 153.492178 -65.123749) (xy 153.499934 -65.069801) (xy 153.515289 -65.017506) (xy 153.537931 -64.967929)
			(xy 153.567397 -64.922079) (xy 153.603088 -64.880888) (xy 153.644279 -64.845197) (xy 153.690129 -64.815731)
			(xy 153.739706 -64.793089) (xy 153.792001 -64.777734) (xy 153.845949 -64.769978) (xy 153.900451 -64.769978)
			(xy 153.954399 -64.777734) (xy 154.006694 -64.793089) (xy 154.056271 -64.815731) (xy 154.102121 -64.845197)
			(xy 154.143312 -64.880888) (xy 154.179003 -64.922079) (xy 154.208469 -64.967929) (xy 154.231111 -65.017506)
			(xy 154.246466 -65.069801) (xy 154.254222 -65.123749) (xy 154.254708 -65.151) (xy 154.254281 -65.176689)
			(xy 154.247385 -65.227603) (xy 154.233718 -65.277131) (xy 154.213528 -65.324377) (xy 154.187179 -65.368485)
			(xy 154.155149 -65.408658) (xy 154.118017 -65.444168) (xy 154.097482 -65.45961) (xy 154.097228 -65.459864)
			(xy 154.088335 -65.467196) (xy 154.077513 -65.487509) (xy 154.0764 -65.49898) (xy 154.07386 -65.57899)
			(xy 154.073973 -65.590643) (xy 154.083364 -65.611944) (xy 154.091894 -65.619884) (xy 154.092148 -65.619884)
			(xy 154.11322 -65.638118) (xy 154.150356 -65.679664) (xy 154.181058 -65.726167) (xy 154.204673 -65.776638)
			(xy 154.220702 -65.830007) (xy 154.228802 -65.885138) (xy 154.229308 -65.913) (xy 154.228822 -65.940251)
			(xy 154.221066 -65.994199) (xy 154.205711 -66.046494) (xy 154.183069 -66.096071) (xy 154.153603 -66.141921)
			(xy 154.117912 -66.183112) (xy 154.076721 -66.218803) (xy 154.030871 -66.248269) (xy 153.981294 -66.270911)
			(xy 153.928999 -66.286266) (xy 153.875051 -66.294022) (xy 153.820549 -66.294022) (xy 153.766601 -66.286266)
			(xy 153.714306 -66.270911) (xy 153.664729 -66.248269) (xy 153.618879 -66.218803) (xy 153.577688 -66.183112)
			(xy 153.541997 -66.141921) (xy 153.512531 -66.096071) (xy 153.489889 -66.046494) (xy 153.474534 -65.994199)
			(xy 153.466778 -65.940251) (xy 153.466292 -65.913) (xy 152.390348 -65.913) (xy 152.390348 -67.818)
			(xy 153.207718 -67.818) (xy 153.211789 -67.762378) (xy 153.223915 -67.707941) (xy 153.243838 -67.65585)
			(xy 153.271134 -67.607215) (xy 153.30522 -67.563072) (xy 153.345369 -67.524363) (xy 153.390727 -67.491912)
			(xy 153.440327 -67.466411) (xy 153.493111 -67.448404) (xy 153.547954 -67.438274) (xy 153.603688 -67.436237)
			(xy 153.659125 -67.442337) (xy 153.713082 -67.456443) (xy 153.764411 -67.478255) (xy 153.812017 -67.507309)
			(xy 153.854885 -67.542984) (xy 153.892102 -67.584521) (xy 153.922875 -67.631034) (xy 153.946547 -67.681531)
			(xy 153.962615 -67.734938) (xy 153.970735 -67.790114) (xy 153.971244 -67.818) (xy 156.128718 -67.818)
			(xy 156.132789 -67.762378) (xy 156.144915 -67.707941) (xy 156.164838 -67.65585) (xy 156.192134 -67.607215)
			(xy 156.22622 -67.563072) (xy 156.266369 -67.524363) (xy 156.311727 -67.491912) (xy 156.361327 -67.466411)
			(xy 156.414111 -67.448404) (xy 156.468954 -67.438274) (xy 156.524688 -67.436237) (xy 156.580125 -67.442337)
			(xy 156.634082 -67.456443) (xy 156.685411 -67.478255) (xy 156.733017 -67.507309) (xy 156.775885 -67.542984)
			(xy 156.813102 -67.584521) (xy 156.843875 -67.631034) (xy 156.867547 -67.681531) (xy 156.883615 -67.734938)
			(xy 156.891735 -67.790114) (xy 156.892244 -67.818) (xy 156.891735 -67.845886) (xy 156.883615 -67.901062)
			(xy 156.867547 -67.954469) (xy 156.843875 -68.004966) (xy 156.813102 -68.051479) (xy 156.775885 -68.093016)
			(xy 156.733017 -68.128691) (xy 156.685411 -68.157745) (xy 156.634082 -68.179557) (xy 156.580125 -68.193663)
			(xy 156.524688 -68.199763) (xy 156.468954 -68.197726) (xy 156.414111 -68.187596) (xy 156.361327 -68.169589)
			(xy 156.311727 -68.144088) (xy 156.266369 -68.111637) (xy 156.22622 -68.072928) (xy 156.192134 -68.028785)
			(xy 156.164838 -67.98015) (xy 156.144915 -67.928059) (xy 156.132789 -67.873622) (xy 156.128718 -67.818)
			(xy 153.971244 -67.818) (xy 153.970735 -67.845886) (xy 153.962615 -67.901062) (xy 153.946547 -67.954469)
			(xy 153.922875 -68.004966) (xy 153.892102 -68.051479) (xy 153.854885 -68.093016) (xy 153.812017 -68.128691)
			(xy 153.764411 -68.157745) (xy 153.713082 -68.179557) (xy 153.659125 -68.193663) (xy 153.603688 -68.199763)
			(xy 153.547954 -68.197726) (xy 153.493111 -68.187596) (xy 153.440327 -68.169589) (xy 153.390727 -68.144088)
			(xy 153.345369 -68.111637) (xy 153.30522 -68.072928) (xy 153.271134 -68.028785) (xy 153.243838 -67.98015)
			(xy 153.223915 -67.928059) (xy 153.211789 -67.873622) (xy 153.207718 -67.818) (xy 152.390348 -67.818)
			(xy 152.390348 -70.104) (xy 153.207718 -70.104) (xy 153.211789 -70.048378) (xy 153.223915 -69.993941)
			(xy 153.243838 -69.94185) (xy 153.271134 -69.893215) (xy 153.30522 -69.849072) (xy 153.345369 -69.810363)
			(xy 153.390727 -69.777912) (xy 153.440327 -69.752411) (xy 153.493111 -69.734404) (xy 153.547954 -69.724274)
			(xy 153.603688 -69.722237) (xy 153.659125 -69.728337) (xy 153.713082 -69.742443) (xy 153.764411 -69.764255)
			(xy 153.812017 -69.793309) (xy 153.854885 -69.828984) (xy 153.892102 -69.870521) (xy 153.922875 -69.917034)
			(xy 153.946547 -69.967531) (xy 153.962615 -70.020938) (xy 153.970735 -70.076114) (xy 153.971244 -70.104)
			(xy 156.128718 -70.104) (xy 156.132789 -70.048378) (xy 156.144915 -69.993941) (xy 156.164838 -69.94185)
			(xy 156.192134 -69.893215) (xy 156.22622 -69.849072) (xy 156.266369 -69.810363) (xy 156.311727 -69.777912)
			(xy 156.361327 -69.752411) (xy 156.414111 -69.734404) (xy 156.468954 -69.724274) (xy 156.524688 -69.722237)
			(xy 156.580125 -69.728337) (xy 156.634082 -69.742443) (xy 156.685411 -69.764255) (xy 156.733017 -69.793309)
			(xy 156.775885 -69.828984) (xy 156.813102 -69.870521) (xy 156.843875 -69.917034) (xy 156.867547 -69.967531)
			(xy 156.883615 -70.020938) (xy 156.891735 -70.076114) (xy 156.892244 -70.104) (xy 156.891735 -70.131886)
			(xy 156.883615 -70.187062) (xy 156.867547 -70.240469) (xy 156.843875 -70.290966) (xy 156.813102 -70.337479)
			(xy 156.775885 -70.379016) (xy 156.733017 -70.414691) (xy 156.685411 -70.443745) (xy 156.634082 -70.465557)
			(xy 156.580125 -70.479663) (xy 156.524688 -70.485763) (xy 156.468954 -70.483726) (xy 156.414111 -70.473596)
			(xy 156.361327 -70.455589) (xy 156.311727 -70.430088) (xy 156.266369 -70.397637) (xy 156.22622 -70.358928)
			(xy 156.192134 -70.314785) (xy 156.164838 -70.26615) (xy 156.144915 -70.214059) (xy 156.132789 -70.159622)
			(xy 156.128718 -70.104) (xy 153.971244 -70.104) (xy 153.970735 -70.131886) (xy 153.962615 -70.187062)
			(xy 153.946547 -70.240469) (xy 153.922875 -70.290966) (xy 153.892102 -70.337479) (xy 153.854885 -70.379016)
			(xy 153.812017 -70.414691) (xy 153.764411 -70.443745) (xy 153.713082 -70.465557) (xy 153.659125 -70.479663)
			(xy 153.603688 -70.485763) (xy 153.547954 -70.483726) (xy 153.493111 -70.473596) (xy 153.440327 -70.455589)
			(xy 153.390727 -70.430088) (xy 153.345369 -70.397637) (xy 153.30522 -70.358928) (xy 153.271134 -70.314785)
			(xy 153.243838 -70.26615) (xy 153.223915 -70.214059) (xy 153.211789 -70.159622) (xy 153.207718 -70.104)
			(xy 152.390348 -70.104) (xy 152.390348 -71.374) (xy 158.033718 -71.374) (xy 158.037789 -71.318378)
			(xy 158.049915 -71.263941) (xy 158.069838 -71.21185) (xy 158.097134 -71.163215) (xy 158.13122 -71.119072)
			(xy 158.171369 -71.080363) (xy 158.216727 -71.047912) (xy 158.266327 -71.022411) (xy 158.319111 -71.004404)
			(xy 158.373954 -70.994274) (xy 158.429688 -70.992237) (xy 158.485125 -70.998337) (xy 158.539082 -71.012443)
			(xy 158.590411 -71.034255) (xy 158.638017 -71.063309) (xy 158.680885 -71.098984) (xy 158.718102 -71.140521)
			(xy 158.748875 -71.187034) (xy 158.772547 -71.237531) (xy 158.788615 -71.290938) (xy 158.796735 -71.346114)
			(xy 158.797244 -71.374) (xy 158.796735 -71.401886) (xy 158.788615 -71.457062) (xy 158.772547 -71.510469)
			(xy 158.748875 -71.560966) (xy 158.718102 -71.607479) (xy 158.680885 -71.649016) (xy 158.638017 -71.684691)
			(xy 158.590411 -71.713745) (xy 158.539082 -71.735557) (xy 158.485125 -71.749663) (xy 158.429688 -71.755763)
			(xy 158.373954 -71.753726) (xy 158.319111 -71.743596) (xy 158.266327 -71.725589) (xy 158.216727 -71.700088)
			(xy 158.171369 -71.667637) (xy 158.13122 -71.628928) (xy 158.097134 -71.584785) (xy 158.069838 -71.53615)
			(xy 158.049915 -71.484059) (xy 158.037789 -71.429622) (xy 158.033718 -71.374) (xy 152.390348 -71.374)
			(xy 152.390348 -72.39) (xy 153.207718 -72.39) (xy 153.211789 -72.334378) (xy 153.223915 -72.279941)
			(xy 153.243838 -72.22785) (xy 153.271134 -72.179215) (xy 153.30522 -72.135072) (xy 153.345369 -72.096363)
			(xy 153.390727 -72.063912) (xy 153.440327 -72.038411) (xy 153.493111 -72.020404) (xy 153.547954 -72.010274)
			(xy 153.603688 -72.008237) (xy 153.659125 -72.014337) (xy 153.713082 -72.028443) (xy 153.764411 -72.050255)
			(xy 153.812017 -72.079309) (xy 153.854885 -72.114984) (xy 153.892102 -72.156521) (xy 153.922875 -72.203034)
			(xy 153.946547 -72.253531) (xy 153.962615 -72.306938) (xy 153.970735 -72.362114) (xy 153.971244 -72.39)
			(xy 156.128718 -72.39) (xy 156.132789 -72.334378) (xy 156.144915 -72.279941) (xy 156.164838 -72.22785)
			(xy 156.192134 -72.179215) (xy 156.22622 -72.135072) (xy 156.266369 -72.096363) (xy 156.311727 -72.063912)
			(xy 156.361327 -72.038411) (xy 156.414111 -72.020404) (xy 156.468954 -72.010274) (xy 156.524688 -72.008237)
			(xy 156.580125 -72.014337) (xy 156.634082 -72.028443) (xy 156.685411 -72.050255) (xy 156.733017 -72.079309)
			(xy 156.775885 -72.114984) (xy 156.813102 -72.156521) (xy 156.843875 -72.203034) (xy 156.867547 -72.253531)
			(xy 156.883615 -72.306938) (xy 156.891735 -72.362114) (xy 156.892244 -72.39) (xy 156.891735 -72.417886)
			(xy 156.883615 -72.473062) (xy 156.867547 -72.526469) (xy 156.843875 -72.576966) (xy 156.813102 -72.623479)
			(xy 156.775885 -72.665016) (xy 156.733017 -72.700691) (xy 156.685411 -72.729745) (xy 156.634082 -72.751557)
			(xy 156.580125 -72.765663) (xy 156.524688 -72.771763) (xy 156.468954 -72.769726) (xy 156.414111 -72.759596)
			(xy 156.361327 -72.741589) (xy 156.311727 -72.716088) (xy 156.266369 -72.683637) (xy 156.22622 -72.644928)
			(xy 156.192134 -72.600785) (xy 156.164838 -72.55215) (xy 156.144915 -72.500059) (xy 156.132789 -72.445622)
			(xy 156.128718 -72.39) (xy 153.971244 -72.39) (xy 153.970735 -72.417886) (xy 153.962615 -72.473062)
			(xy 153.946547 -72.526469) (xy 153.922875 -72.576966) (xy 153.892102 -72.623479) (xy 153.854885 -72.665016)
			(xy 153.812017 -72.700691) (xy 153.764411 -72.729745) (xy 153.713082 -72.751557) (xy 153.659125 -72.765663)
			(xy 153.603688 -72.771763) (xy 153.547954 -72.769726) (xy 153.493111 -72.759596) (xy 153.440327 -72.741589)
			(xy 153.390727 -72.716088) (xy 153.345369 -72.683637) (xy 153.30522 -72.644928) (xy 153.271134 -72.600785)
			(xy 153.243838 -72.55215) (xy 153.223915 -72.500059) (xy 153.211789 -72.445622) (xy 153.207718 -72.39)
			(xy 152.390348 -72.39) (xy 152.390348 -74.697082) (xy 152.391618 -74.708512) (xy 152.394412 -74.719688)
			(xy 152.398222 -74.73061) (xy 152.401016 -74.736198) (xy 152.47493 -74.792332) (xy 152.47972 -74.795764)
			(xy 152.490501 -74.800513) (xy 152.496266 -74.80173) (xy 152.507696 -74.803762) (xy 152.51938 -74.800714)
			(xy 152.519888 -74.800714) (xy 152.544966 -74.794124) (xy 152.596325 -74.786982) (xy 152.62225 -74.78649)
			(xy 152.652476 -74.78776) (xy 152.653238 -74.78776) (xy 152.663859 -74.787961) (xy 152.68381 -74.780738)
			(xy 152.691846 -74.77379) (xy 152.754838 -74.713592) (xy 152.762966 -74.69378) (xy 152.762458 -74.682604)
			(xy 152.762204 -74.668126) (xy 152.762666 -74.640872) (xy 152.77042 -74.586919) (xy 152.785774 -74.534619)
			(xy 152.808415 -74.485036) (xy 152.837882 -74.439181) (xy 152.873576 -74.397986) (xy 152.914769 -74.362291)
			(xy 152.960624 -74.332821) (xy 153.010206 -74.310178) (xy 153.062505 -74.294823) (xy 153.116458 -74.287067)
			(xy 153.143712 -74.286618) (xy 153.173011 -74.287153) (xy 153.230922 -74.296108) (xy 153.286783 -74.313807)
			(xy 153.339285 -74.339834) (xy 153.387193 -74.373578) (xy 153.408634 -74.393552) (xy 153.41854 -74.403204)
			(xy 153.444194 -74.409554) (xy 153.54173 -74.382884) (xy 153.550146 -74.38019) (xy 153.564569 -74.370002)
			(xy 153.57465 -74.355504) (xy 153.57729 -74.34707) (xy 153.58504 -74.320509) (xy 153.607147 -74.269788)
			(xy 153.636349 -74.222793) (xy 153.672032 -74.180509) (xy 153.713449 -74.143822) (xy 153.759731 -74.113502)
			(xy 153.809907 -74.090185) (xy 153.862924 -74.07436) (xy 153.917672 -74.066359) (xy 153.945336 -74.065892)
			(xy 153.972586 -74.06638) (xy 154.026529 -74.074141) (xy 154.07882 -74.089499) (xy 154.128393 -74.112142)
			(xy 154.174238 -74.14161) (xy 154.215424 -74.177301) (xy 154.251112 -74.21849) (xy 154.280575 -74.264339)
			(xy 154.303213 -74.313914) (xy 154.318567 -74.366206) (xy 154.326322 -74.42015) (xy 154.326322 -74.47465)
			(xy 154.318567 -74.528594) (xy 154.303213 -74.580886) (xy 154.280575 -74.630461) (xy 154.251112 -74.67631)
			(xy 154.215424 -74.717499) (xy 154.174238 -74.75319) (xy 154.128393 -74.782658) (xy 154.083858 -74.803)
			(xy 156.255718 -74.803) (xy 156.259789 -74.747378) (xy 156.271915 -74.692941) (xy 156.291838 -74.64085)
			(xy 156.319134 -74.592215) (xy 156.35322 -74.548072) (xy 156.393369 -74.509363) (xy 156.438727 -74.476912)
			(xy 156.488327 -74.451411) (xy 156.541111 -74.433404) (xy 156.595954 -74.423274) (xy 156.651688 -74.421237)
			(xy 156.707125 -74.427337) (xy 156.761082 -74.441443) (xy 156.812411 -74.463255) (xy 156.860017 -74.492309)
			(xy 156.902885 -74.527984) (xy 156.940102 -74.569521) (xy 156.970875 -74.616034) (xy 156.994547 -74.666531)
			(xy 157.010615 -74.719938) (xy 157.018735 -74.775114) (xy 157.019244 -74.803) (xy 157.018735 -74.830886)
			(xy 157.010615 -74.886062) (xy 156.994547 -74.939469) (xy 156.970875 -74.989966) (xy 156.940102 -75.036479)
			(xy 156.902885 -75.078016) (xy 156.860017 -75.113691) (xy 156.812411 -75.142745) (xy 156.761082 -75.164557)
			(xy 156.707125 -75.178663) (xy 156.651688 -75.184763) (xy 156.595954 -75.182726) (xy 156.541111 -75.172596)
			(xy 156.488327 -75.154589) (xy 156.438727 -75.129088) (xy 156.393369 -75.096637) (xy 156.35322 -75.057928)
			(xy 156.319134 -75.013785) (xy 156.291838 -74.96515) (xy 156.271915 -74.913059) (xy 156.259789 -74.858622)
			(xy 156.255718 -74.803) (xy 154.083858 -74.803) (xy 154.07882 -74.805301) (xy 154.026529 -74.820659)
			(xy 153.972586 -74.82842) (xy 153.945336 -74.828908) (xy 153.916039 -74.828369) (xy 153.858134 -74.819405)
			(xy 153.802279 -74.801697) (xy 153.749787 -74.775662) (xy 153.701889 -74.74191) (xy 153.680414 -74.721974)
			(xy 153.670508 -74.712322) (xy 153.644854 -74.705972) (xy 153.547318 -74.732642) (xy 153.538898 -74.735331)
			(xy 153.524467 -74.745515) (xy 153.514383 -74.760016) (xy 153.511758 -74.768456) (xy 153.504007 -74.795018)
			(xy 153.481899 -74.845738) (xy 153.452697 -74.892735) (xy 153.417013 -74.935021) (xy 153.375597 -74.97171)
			(xy 153.329316 -75.002033) (xy 153.279141 -75.025353) (xy 153.226124 -75.041183) (xy 153.171377 -75.04919)
			(xy 153.143712 -75.049634) (xy 153.113486 -75.048364) (xy 153.112724 -75.048364) (xy 153.102106 -75.048171)
			(xy 153.082169 -75.055407) (xy 153.074116 -75.062334) (xy 153.011124 -75.122532) (xy 153.002996 -75.142344)
			(xy 153.003504 -75.15352) (xy 153.003758 -75.167998) (xy 153.003295 -75.19525) (xy 152.995538 -75.249198)
			(xy 152.980181 -75.301493) (xy 152.957538 -75.351071) (xy 152.92807 -75.39692) (xy 152.892469 -75.438)
			(xy 155.239718 -75.438) (xy 155.243789 -75.382378) (xy 155.255915 -75.327941) (xy 155.275838 -75.27585)
			(xy 155.303134 -75.227215) (xy 155.33722 -75.183072) (xy 155.377369 -75.144363) (xy 155.422727 -75.111912)
			(xy 155.472327 -75.086411) (xy 155.525111 -75.068404) (xy 155.579954 -75.058274) (xy 155.635688 -75.056237)
			(xy 155.691125 -75.062337) (xy 155.745082 -75.076443) (xy 155.796411 -75.098255) (xy 155.844017 -75.127309)
			(xy 155.886885 -75.162984) (xy 155.924102 -75.204521) (xy 155.954875 -75.251034) (xy 155.978547 -75.301531)
			(xy 155.994615 -75.354938) (xy 156.002735 -75.410114) (xy 156.003244 -75.438) (xy 156.002735 -75.465886)
			(xy 155.994615 -75.521062) (xy 155.978547 -75.574469) (xy 155.954875 -75.624966) (xy 155.924102 -75.671479)
			(xy 155.886885 -75.713016) (xy 155.844017 -75.748691) (xy 155.796411 -75.777745) (xy 155.745082 -75.799557)
			(xy 155.691125 -75.813663) (xy 155.635688 -75.819763) (xy 155.579954 -75.817726) (xy 155.525111 -75.807596)
			(xy 155.472327 -75.789589) (xy 155.422727 -75.764088) (xy 155.377369 -75.731637) (xy 155.33722 -75.692928)
			(xy 155.303134 -75.648785) (xy 155.275838 -75.60015) (xy 155.255915 -75.548059) (xy 155.243789 -75.493622)
			(xy 155.239718 -75.438) (xy 152.892469 -75.438) (xy 152.892375 -75.438109) (xy 152.851182 -75.473798)
			(xy 152.805328 -75.503261) (xy 152.755748 -75.525898) (xy 152.703451 -75.541248) (xy 152.649502 -75.548998)
			(xy 152.62225 -75.549506) (xy 152.596324 -75.549022) (xy 152.544963 -75.541889) (xy 152.519888 -75.535282)
			(xy 152.51938 -75.535282) (xy 152.507696 -75.532234) (xy 152.496266 -75.534266) (xy 152.490513 -75.535521)
			(xy 152.479742 -75.54027) (xy 152.47493 -75.543664) (xy 152.410414 -75.592686) (xy 152.401428 -75.600278)
			(xy 152.390975 -75.621324) (xy 152.390348 -75.633072) (xy 152.390348 -77.47) (xy 154.115768 -77.47)
			(xy 154.119839 -77.414378) (xy 154.131965 -77.359941) (xy 154.151888 -77.30785) (xy 154.179184 -77.259215)
			(xy 154.21327 -77.215072) (xy 154.253419 -77.176363) (xy 154.298777 -77.143912) (xy 154.348377 -77.118411)
			(xy 154.401161 -77.100404) (xy 154.456004 -77.090274) (xy 154.511738 -77.088237) (xy 154.567175 -77.094337)
			(xy 154.621132 -77.108443) (xy 154.672461 -77.130255) (xy 154.720067 -77.159309) (xy 154.762935 -77.194984)
			(xy 154.800152 -77.236521) (xy 154.830925 -77.283034) (xy 154.854597 -77.333531) (xy 154.870665 -77.386938)
			(xy 154.878785 -77.442114) (xy 154.879294 -77.47) (xy 154.878785 -77.497886) (xy 154.870665 -77.553062)
			(xy 154.854597 -77.606469) (xy 154.830925 -77.656966) (xy 154.800152 -77.703479) (xy 154.762935 -77.745016)
			(xy 154.720067 -77.780691) (xy 154.672461 -77.809745) (xy 154.621132 -77.831557) (xy 154.567175 -77.845663)
			(xy 154.511738 -77.851763) (xy 154.456004 -77.849726) (xy 154.401161 -77.839596) (xy 154.348377 -77.821589)
			(xy 154.298777 -77.796088) (xy 154.253419 -77.763637) (xy 154.21327 -77.724928) (xy 154.179184 -77.680785)
			(xy 154.151888 -77.63215) (xy 154.131965 -77.580059) (xy 154.119839 -77.525622) (xy 154.115768 -77.47)
			(xy 152.390348 -77.47) (xy 152.390348 -78.22565) (xy 156.255718 -78.22565) (xy 156.259789 -78.170028)
			(xy 156.271915 -78.115591) (xy 156.291838 -78.0635) (xy 156.319134 -78.014865) (xy 156.35322 -77.970722)
			(xy 156.393369 -77.932013) (xy 156.438727 -77.899562) (xy 156.488327 -77.874061) (xy 156.541111 -77.856054)
			(xy 156.595954 -77.845924) (xy 156.651688 -77.843887) (xy 156.707125 -77.849987) (xy 156.761082 -77.864093)
			(xy 156.812411 -77.885905) (xy 156.860017 -77.914959) (xy 156.902885 -77.950634) (xy 156.940102 -77.992171)
			(xy 156.970875 -78.038684) (xy 156.994547 -78.089181) (xy 157.010615 -78.142588) (xy 157.018735 -78.197764)
			(xy 157.019244 -78.22565) (xy 157.019128 -78.232) (xy 157.652718 -78.232) (xy 157.656789 -78.176378)
			(xy 157.668915 -78.121941) (xy 157.688838 -78.06985) (xy 157.716134 -78.021215) (xy 157.75022 -77.977072)
			(xy 157.790369 -77.938363) (xy 157.835727 -77.905912) (xy 157.885327 -77.880411) (xy 157.938111 -77.862404)
			(xy 157.992954 -77.852274) (xy 158.048688 -77.850237) (xy 158.104125 -77.856337) (xy 158.158082 -77.870443)
			(xy 158.209411 -77.892255) (xy 158.257017 -77.921309) (xy 158.299885 -77.956984) (xy 158.337102 -77.998521)
			(xy 158.367875 -78.045034) (xy 158.391547 -78.095531) (xy 158.407615 -78.148938) (xy 158.415735 -78.204114)
			(xy 158.416244 -78.232) (xy 158.415735 -78.259886) (xy 158.407615 -78.315062) (xy 158.391547 -78.368469)
			(xy 158.367875 -78.418966) (xy 158.337102 -78.465479) (xy 158.299885 -78.507016) (xy 158.257017 -78.542691)
			(xy 158.209411 -78.571745) (xy 158.158082 -78.593557) (xy 158.104125 -78.607663) (xy 158.048688 -78.613763)
			(xy 157.992954 -78.611726) (xy 157.938111 -78.601596) (xy 157.885327 -78.583589) (xy 157.835727 -78.558088)
			(xy 157.790369 -78.525637) (xy 157.75022 -78.486928) (xy 157.716134 -78.442785) (xy 157.688838 -78.39415)
			(xy 157.668915 -78.342059) (xy 157.656789 -78.287622) (xy 157.652718 -78.232) (xy 157.019128 -78.232)
			(xy 157.018735 -78.253536) (xy 157.010615 -78.308712) (xy 156.994547 -78.362119) (xy 156.970875 -78.412616)
			(xy 156.940102 -78.459129) (xy 156.902885 -78.500666) (xy 156.860017 -78.536341) (xy 156.812411 -78.565395)
			(xy 156.761082 -78.587207) (xy 156.707125 -78.601313) (xy 156.651688 -78.607413) (xy 156.595954 -78.605376)
			(xy 156.541111 -78.595246) (xy 156.488327 -78.577239) (xy 156.438727 -78.551738) (xy 156.393369 -78.519287)
			(xy 156.35322 -78.480578) (xy 156.319134 -78.436435) (xy 156.291838 -78.3878) (xy 156.271915 -78.335709)
			(xy 156.259789 -78.281272) (xy 156.255718 -78.22565) (xy 152.390348 -78.22565) (xy 152.390348 -79.61757)
			(xy 152.389911 -79.627633) (xy 152.382173 -79.646214) (xy 152.375362 -79.653638) (xy 151.525986 -80.503014)
			(xy 151.518591 -80.509868) (xy 151.499992 -80.51761) (xy 151.489918 -80.518) (xy 150.405338 -80.518)
			(xy 150.400177 -80.518094) (xy 150.390063 -80.520143) (xy 150.385272 -80.522064) (xy 150.34355 -80.539438)
			(xy 150.257349 -80.566611) (xy 150.168837 -80.584905) (xy 150.078927 -80.594132) (xy 150.033736 -80.594708)
			(xy 149.988545 -80.594127) (xy 149.898633 -80.584911) (xy 149.81012 -80.566621) (xy 149.723918 -80.539447)
			(xy 149.6822 -80.522064) (xy 149.6774 -80.520173) (xy 149.667291 -80.518124) (xy 149.662134 -80.518)
			(xy 149.627082 -80.518) (xy 149.617013 -80.517573) (xy 149.598414 -80.509854) (xy 149.591014 -80.503014)
			(xy 149.517862 -80.429862) (xy 149.51456 -80.427322) (xy 149.476036 -80.398841) (xy 149.404699 -80.334882)
			(xy 149.34064 -80.263635) (xy 149.312122 -80.225138) (xy 149.311614 -80.224376) (xy 149.309074 -80.221074)
			(xy 149.2885 -80.2005) (xy 149.2885 -80.191102) (xy 149.280626 -80.178656) (xy 149.258894 -80.143191)
			(xy 149.221385 -80.068946) (xy 149.190976 -79.991521) (xy 149.167935 -79.911594) (xy 149.152462 -79.829864)
			(xy 149.144694 -79.747045) (xy 149.144228 -79.705454) (xy 149.144228 -79.7052) (xy 149.144813 -79.658804)
			(xy 149.154447 -79.566514) (xy 149.17364 -79.475729) (xy 149.202185 -79.387437) (xy 149.220428 -79.344774)
			(xy 149.224232 -79.334831) (xy 149.224232 -79.313569) (xy 149.220428 -79.303626) (xy 149.202189 -79.260961)
			(xy 149.17365 -79.172668) (xy 149.154453 -79.081884) (xy 149.144808 -78.989596) (xy 149.144228 -78.9432)
			(xy 149.144827 -78.896765) (xy 149.154504 -78.804402) (xy 149.173763 -78.713551) (xy 149.202393 -78.625206)
			(xy 149.220682 -78.58252) (xy 149.222711 -78.577622) (xy 149.224882 -78.567247) (xy 149.225 -78.561946)
			(xy 149.225 -76.094082) (xy 149.225427 -76.084013) (xy 149.233146 -76.065414) (xy 149.239986 -76.058014)
			(xy 150.988014 -74.309986) (xy 150.988522 -74.309478) (xy 150.995112 -74.3021) (xy 151.002579 -74.283801)
			(xy 151.003 -74.273918) (xy 151.003 -68.474082) (xy 151.002573 -68.464013) (xy 150.994854 -68.445414)
			(xy 150.988014 -68.438014) (xy 150.057104 -67.507104) (xy 150.049992 -67.499738) (xy 150.031196 -67.492118)
			(xy 147.35937 -67.492118) (xy 147.349929 -67.492487) (xy 147.332324 -67.499308) (xy 147.31839 -67.512049)
			(xy 147.310024 -67.528975) (xy 147.308824 -67.538346) (xy 147.308824 -67.5386) (xy 147.304674 -67.581018)
			(xy 147.289281 -67.664853) (xy 147.26594 -67.746831) (xy 147.234863 -67.8262) (xy 147.196337 -67.902232)
			(xy 147.150713 -67.97423) (xy 147.098412 -68.041533) (xy 147.039912 -68.103525) (xy 146.97575 -68.159636)
			(xy 146.906515 -68.209352) (xy 146.832841 -68.252216) (xy 146.755405 -68.287837) (xy 146.674916 -68.315886)
			(xy 146.592114 -68.336107) (xy 146.507756 -68.348314) (xy 146.422618 -68.352396) (xy 146.33748 -68.348314)
			(xy 146.253122 -68.336107) (xy 146.17032 -68.315886) (xy 146.089831 -68.287837) (xy 146.012395 -68.252216)
			(xy 145.938721 -68.209352) (xy 145.869486 -68.159636) (xy 145.805324 -68.103525) (xy 145.746824 -68.041533)
			(xy 145.694523 -67.97423) (xy 145.648899 -67.902232) (xy 145.610373 -67.8262) (xy 145.579296 -67.746831)
			(xy 145.555955 -67.664853) (xy 145.540562 -67.581018) (xy 145.536412 -67.5386) (xy 145.536412 -67.538346)
			(xy 145.535119 -67.529009) (xy 145.526739 -67.512144) (xy 145.512835 -67.499442) (xy 145.495282 -67.492619)
			(xy 145.485866 -67.492118) (xy 143.945102 -67.492118) (xy 143.934443 -67.492578) (xy 143.914977 -67.501262)
			(xy 143.90751 -67.508882) (xy 143.856964 -67.564508) (xy 143.850234 -67.57277) (xy 143.843544 -67.592978)
			(xy 143.84401 -67.603624) (xy 143.846034 -67.625411) (xy 143.848194 -67.669119) (xy 143.848328 -67.691)
			(xy 143.847807 -67.734796) (xy 143.839198 -67.821963) (xy 143.822053 -67.90786) (xy 143.79654 -67.991653)
			(xy 143.762905 -68.072529) (xy 143.742664 -68.11137) (xy 143.739616 -68.117212) (xy 143.736568 -68.12915)
			(xy 143.736568 -68.14185) (xy 143.739616 -68.153788) (xy 143.742664 -68.15963) (xy 143.762893 -68.198475)
			(xy 143.796494 -68.27936) (xy 143.82199 -68.363154) (xy 143.839136 -68.449046) (xy 143.847765 -68.536207)
			(xy 143.848328 -68.58) (xy 143.847807 -68.623796) (xy 143.839198 -68.710963) (xy 143.822053 -68.79686)
			(xy 143.79654 -68.880653) (xy 143.762905 -68.961529) (xy 143.742664 -69.00037) (xy 143.739616 -69.006212)
			(xy 143.736568 -69.01815) (xy 143.736568 -69.03085) (xy 143.739616 -69.042788) (xy 143.742664 -69.04863)
			(xy 143.762893 -69.087475) (xy 143.796494 -69.16836) (xy 143.82199 -69.252154) (xy 143.839136 -69.338046)
			(xy 143.847765 -69.425207) (xy 143.848328 -69.469) (xy 143.847807 -69.512796) (xy 143.839198 -69.599963)
			(xy 143.822053 -69.68586) (xy 143.79654 -69.769653) (xy 143.762905 -69.850529) (xy 143.742664 -69.88937)
			(xy 143.739616 -69.895212) (xy 143.736568 -69.90715) (xy 143.736568 -69.91985) (xy 143.739616 -69.931788)
			(xy 143.742664 -69.93763) (xy 143.762893 -69.976475) (xy 143.796494 -70.05736) (xy 143.82199 -70.141154)
			(xy 143.839136 -70.227046) (xy 143.847765 -70.314207) (xy 143.848328 -70.358) (xy 143.847824 -70.400348)
			(xy 143.839773 -70.484662) (xy 143.823744 -70.567828) (xy 143.799883 -70.649095) (xy 143.768404 -70.727725)
			(xy 143.729593 -70.803006) (xy 143.683803 -70.874258) (xy 143.631447 -70.940834) (xy 143.572999 -71.002132)
			(xy 143.508989 -71.057597) (xy 143.439997 -71.106726) (xy 143.366647 -71.149075) (xy 143.289604 -71.184259)
			(xy 143.209565 -71.211961) (xy 143.127256 -71.231929) (xy 143.043421 -71.243982) (xy 142.95882 -71.248013)
			(xy 142.874219 -71.243982) (xy 142.790384 -71.231929) (xy 142.708075 -71.211961) (xy 142.628036 -71.184259)
			(xy 142.550993 -71.149075) (xy 142.477643 -71.106726) (xy 142.408651 -71.057597) (xy 142.344641 -71.002132)
			(xy 142.286193 -70.940834) (xy 142.233837 -70.874258) (xy 142.188047 -70.803006) (xy 142.149236 -70.727725)
			(xy 142.117757 -70.649095) (xy 142.093896 -70.567828) (xy 142.077867 -70.484662) (xy 142.069816 -70.400348)
			(xy 142.069312 -70.358) (xy 142.069833 -70.314204) (xy 142.078442 -70.227037) (xy 142.095585 -70.14114)
			(xy 142.121097 -70.057346) (xy 142.15473 -69.976469) (xy 142.174976 -69.93763) (xy 142.178024 -69.931788)
			(xy 142.181072 -69.91985) (xy 142.181072 -69.90715) (xy 142.178024 -69.895212) (xy 142.174976 -69.88937)
			(xy 142.154746 -69.850526) (xy 142.121144 -69.76964) (xy 142.095646 -69.685847) (xy 142.0785 -69.599954)
			(xy 142.06987 -69.512793) (xy 142.069312 -69.469) (xy 142.069833 -69.425204) (xy 142.078442 -69.338037)
			(xy 142.095585 -69.25214) (xy 142.121097 -69.168346) (xy 142.15473 -69.087469) (xy 142.174976 -69.04863)
			(xy 142.178024 -69.042788) (xy 142.181072 -69.03085) (xy 142.181072 -69.01815) (xy 142.178024 -69.006212)
			(xy 142.174976 -69.00037) (xy 142.154746 -68.961526) (xy 142.121144 -68.88064) (xy 142.095646 -68.796847)
			(xy 142.0785 -68.710954) (xy 142.06987 -68.623793) (xy 142.069312 -68.58) (xy 142.069833 -68.536204)
			(xy 142.078442 -68.449037) (xy 142.095585 -68.36314) (xy 142.121097 -68.279346) (xy 142.15473 -68.198469)
			(xy 142.174976 -68.15963) (xy 142.178024 -68.153788) (xy 142.181072 -68.14185) (xy 142.181072 -68.12915)
			(xy 142.178024 -68.117212) (xy 142.174976 -68.11137) (xy 142.154746 -68.072526) (xy 142.121144 -67.99164)
			(xy 142.095646 -67.907847) (xy 142.0785 -67.821954) (xy 142.06987 -67.734793) (xy 142.069312 -67.691)
			(xy 142.069455 -67.66912) (xy 142.071617 -67.625412) (xy 142.07363 -67.603624) (xy 142.074236 -67.592961)
			(xy 142.067524 -67.572705) (xy 142.060676 -67.564508) (xy 142.01013 -67.508882) (xy 142.002584 -67.501375)
			(xy 141.983165 -67.492714) (xy 141.972538 -67.492118) (xy 140.999972 -67.492118) (xy 140.990531 -67.492486)
			(xy 140.972925 -67.499308) (xy 140.958991 -67.512048) (xy 140.950624 -67.528975) (xy 140.949426 -67.538346)
			(xy 140.949426 -67.5386) (xy 140.945276 -67.581018) (xy 140.929883 -67.664853) (xy 140.906542 -67.746831)
			(xy 140.875465 -67.8262) (xy 140.836939 -67.902232) (xy 140.791315 -67.97423) (xy 140.739014 -68.041533)
			(xy 140.680514 -68.103525) (xy 140.616352 -68.159636) (xy 140.547117 -68.209352) (xy 140.473443 -68.252216)
			(xy 140.396007 -68.287837) (xy 140.315518 -68.315886) (xy 140.232716 -68.336107) (xy 140.148358 -68.348314)
			(xy 140.06322 -68.352396) (xy 139.978082 -68.348314) (xy 139.893724 -68.336107) (xy 139.810922 -68.315886)
			(xy 139.730433 -68.287837) (xy 139.652997 -68.252216) (xy 139.579323 -68.209352) (xy 139.510088 -68.159636)
			(xy 139.445926 -68.103525) (xy 139.387426 -68.041533) (xy 139.335125 -67.97423) (xy 139.289501 -67.902232)
			(xy 139.250975 -67.8262) (xy 139.219898 -67.746831) (xy 139.196557 -67.664853) (xy 139.181164 -67.581018)
			(xy 139.177014 -67.5386) (xy 139.177014 -67.538346) (xy 139.175721 -67.529009) (xy 139.167341 -67.512143)
			(xy 139.153437 -67.499441) (xy 139.135884 -67.492617) (xy 139.126468 -67.492118) (xy 137.950448 -67.492118)
			(xy 137.940382 -67.492551) (xy 137.921793 -67.500281) (xy 137.91438 -67.507104) (xy 137.018776 -68.402708)
			(xy 137.012096 -68.410119) (xy 137.00452 -68.428555) (xy 137.004044 -68.438522) (xy 137.004044 -71.85406)
			(xy 149.046184 -71.85406) (xy 149.046689 -71.811635) (xy 149.054766 -71.72717) (xy 149.070853 -71.643858)
			(xy 149.094802 -71.562458) (xy 149.126397 -71.48371) (xy 149.165349 -71.408329) (xy 149.211305 -71.337001)
			(xy 149.263847 -71.270376) (xy 149.322496 -71.209058) (xy 149.354286 -71.18096) (xy 149.362668 -71.173594)
			(xy 149.371812 -71.153782) (xy 149.371812 -71.054214) (xy 149.362668 -71.034402) (xy 149.354286 -71.027036)
			(xy 149.322511 -70.998921) (xy 149.263862 -70.937604) (xy 149.21132 -70.87098) (xy 149.165363 -70.799655)
			(xy 149.126408 -70.724277) (xy 149.09481 -70.645531) (xy 149.070855 -70.564133) (xy 149.054763 -70.480824)
			(xy 149.046678 -70.396361) (xy 149.046184 -70.353936) (xy 149.046688 -70.311588) (xy 149.054739 -70.227274)
			(xy 149.070768 -70.144108) (xy 149.094629 -70.062841) (xy 149.126108 -69.984211) (xy 149.164919 -69.90893)
			(xy 149.210709 -69.837678) (xy 149.263065 -69.771102) (xy 149.321513 -69.709804) (xy 149.385523 -69.654339)
			(xy 149.454515 -69.60521) (xy 149.527865 -69.562861) (xy 149.604908 -69.527677) (xy 149.684947 -69.499975)
			(xy 149.767256 -69.480007) (xy 149.851091 -69.467954) (xy 149.935692 -69.463924) (xy 150.020293 -69.467954)
			(xy 150.104128 -69.480007) (xy 150.186437 -69.499975) (xy 150.266476 -69.527677) (xy 150.343519 -69.562861)
			(xy 150.416869 -69.60521) (xy 150.485861 -69.654339) (xy 150.549871 -69.709804) (xy 150.608319 -69.771102)
			(xy 150.660675 -69.837678) (xy 150.706465 -69.90893) (xy 150.745276 -69.984211) (xy 150.776755 -70.062841)
			(xy 150.800616 -70.144108) (xy 150.816645 -70.227274) (xy 150.824696 -70.311588) (xy 150.8252 -70.353936)
			(xy 150.824697 -70.396361) (xy 150.81662 -70.480826) (xy 150.800534 -70.564138) (xy 150.776585 -70.645538)
			(xy 150.74499 -70.724287) (xy 150.706037 -70.799668) (xy 150.660081 -70.870996) (xy 150.607539 -70.937621)
			(xy 150.548889 -70.998938) (xy 150.517098 -71.027036) (xy 150.508716 -71.034402) (xy 150.499572 -71.054214)
			(xy 150.499572 -71.153782) (xy 150.508716 -71.173594) (xy 150.517098 -71.18096) (xy 150.548868 -71.209081)
			(xy 150.607517 -71.270396) (xy 150.66006 -71.337019) (xy 150.706018 -71.408344) (xy 150.744973 -71.483722)
			(xy 150.776572 -71.562467) (xy 150.800527 -71.643864) (xy 150.816621 -71.727173) (xy 150.824706 -71.811636)
			(xy 150.8252 -71.85406) (xy 150.824696 -71.896408) (xy 150.816645 -71.980722) (xy 150.800616 -72.063888)
			(xy 150.776755 -72.145155) (xy 150.745276 -72.223785) (xy 150.706465 -72.299066) (xy 150.660675 -72.370318)
			(xy 150.608319 -72.436894) (xy 150.549871 -72.498192) (xy 150.485861 -72.553657) (xy 150.416869 -72.602786)
			(xy 150.343519 -72.645135) (xy 150.266476 -72.680319) (xy 150.186437 -72.708021) (xy 150.104128 -72.727989)
			(xy 150.020293 -72.740042) (xy 149.935692 -72.744073) (xy 149.851091 -72.740042) (xy 149.767256 -72.727989)
			(xy 149.684947 -72.708021) (xy 149.604908 -72.680319) (xy 149.527865 -72.645135) (xy 149.454515 -72.602786)
			(xy 149.385523 -72.553657) (xy 149.321513 -72.498192) (xy 149.263065 -72.436894) (xy 149.210709 -72.370318)
			(xy 149.164919 -72.299066) (xy 149.126108 -72.223785) (xy 149.094629 -72.145155) (xy 149.070768 -72.063888)
			(xy 149.054739 -71.980722) (xy 149.046688 -71.896408) (xy 149.046184 -71.85406) (xy 137.004044 -71.85406)
			(xy 137.004044 -74.360278) (xy 144.227042 -74.360278) (xy 144.227544 -74.317152) (xy 144.235889 -74.231306)
			(xy 144.252509 -74.146671) (xy 144.277246 -74.064044) (xy 144.309869 -73.9842) (xy 144.350071 -73.907891)
			(xy 144.373346 -73.871582) (xy 144.376902 -73.866248) (xy 144.380966 -73.855072) (xy 144.382236 -73.841356)
			(xy 144.379696 -73.827386) (xy 144.376394 -73.820782) (xy 144.35831 -73.783644) (xy 144.328323 -73.70667)
			(xy 144.305596 -73.62725) (xy 144.290326 -73.546065) (xy 144.282643 -73.463814) (xy 144.28216 -73.42251)
			(xy 144.282664 -73.380162) (xy 144.290715 -73.295848) (xy 144.306744 -73.212682) (xy 144.330605 -73.131415)
			(xy 144.362084 -73.052785) (xy 144.400895 -72.977504) (xy 144.446685 -72.906252) (xy 144.499041 -72.839676)
			(xy 144.557489 -72.778378) (xy 144.621499 -72.722913) (xy 144.690491 -72.673784) (xy 144.763841 -72.631435)
			(xy 144.840884 -72.596251) (xy 144.920923 -72.568549) (xy 145.003232 -72.548581) (xy 145.087067 -72.536528)
			(xy 145.171668 -72.532498) (xy 145.256269 -72.536528) (xy 145.340104 -72.548581) (xy 145.422413 -72.568549)
			(xy 145.502452 -72.596251) (xy 145.579495 -72.631435) (xy 145.652845 -72.673784) (xy 145.721837 -72.722913)
			(xy 145.785847 -72.778378) (xy 145.844295 -72.839676) (xy 145.896651 -72.906252) (xy 145.942441 -72.977504)
			(xy 145.981252 -73.052785) (xy 146.012731 -73.131415) (xy 146.036592 -73.212682) (xy 146.052621 -73.295848)
			(xy 146.060672 -73.380162) (xy 146.061176 -73.42251) (xy 146.060665 -73.465635) (xy 146.052321 -73.551481)
			(xy 146.035703 -73.636116) (xy 146.010967 -73.718744) (xy 145.978346 -73.798587) (xy 145.938146 -73.874897)
			(xy 145.914872 -73.911206) (xy 145.911316 -73.91654) (xy 145.907252 -73.927716) (xy 145.905982 -73.941432)
			(xy 145.908522 -73.955402) (xy 145.911824 -73.962006) (xy 145.929905 -73.999145) (xy 145.959893 -74.076119)
			(xy 145.98262 -74.155539) (xy 145.997891 -74.236724) (xy 146.005574 -74.318974) (xy 146.006058 -74.360278)
			(xy 146.005554 -74.402626) (xy 145.997503 -74.48694) (xy 145.981474 -74.570106) (xy 145.957613 -74.651373)
			(xy 145.926134 -74.730003) (xy 145.887323 -74.805284) (xy 145.841533 -74.876536) (xy 145.789177 -74.943112)
			(xy 145.730729 -75.00441) (xy 145.666719 -75.059875) (xy 145.597727 -75.109004) (xy 145.524377 -75.151353)
			(xy 145.447334 -75.186537) (xy 145.367295 -75.214239) (xy 145.284986 -75.234207) (xy 145.201151 -75.24626)
			(xy 145.11655 -75.250291) (xy 145.031949 -75.24626) (xy 144.948114 -75.234207) (xy 144.865805 -75.214239)
			(xy 144.785766 -75.186537) (xy 144.708723 -75.151353) (xy 144.635373 -75.109004) (xy 144.566381 -75.059875)
			(xy 144.502371 -75.00441) (xy 144.443923 -74.943112) (xy 144.391567 -74.876536) (xy 144.345777 -74.805284)
			(xy 144.306966 -74.730003) (xy 144.275487 -74.651373) (xy 144.251626 -74.570106) (xy 144.235597 -74.48694)
			(xy 144.227546 -74.402626) (xy 144.227042 -74.360278) (xy 137.004044 -74.360278) (xy 137.004044 -76.8584)
			(xy 142.64304 -76.8584) (xy 142.64707 -76.773794) (xy 142.659125 -76.689953) (xy 142.679094 -76.607639)
			(xy 142.706798 -76.527595) (xy 142.741985 -76.450547) (xy 142.784337 -76.377193) (xy 142.833469 -76.308197)
			(xy 142.888938 -76.244183) (xy 142.95024 -76.185733) (xy 143.016821 -76.133374) (xy 143.088078 -76.087581)
			(xy 143.163365 -76.048769) (xy 143.242 -76.017289) (xy 143.323272 -75.993427) (xy 143.406444 -75.977398)
			(xy 143.490763 -75.969347) (xy 143.533114 -75.96886) (xy 143.57627 -75.96935) (xy 143.662175 -75.977714)
			(xy 143.746866 -75.994362) (xy 143.829546 -76.019137) (xy 143.909436 -76.051805) (xy 143.985785 -76.092061)
			(xy 144.057875 -76.139524) (xy 144.125027 -76.193749) (xy 144.156176 -76.223622) (xy 144.163288 -76.23048)
			(xy 144.181068 -76.2381) (xy 144.27073 -76.239878) (xy 144.288764 -76.23302) (xy 144.295876 -76.22667)
			(xy 144.326488 -76.199565) (xy 144.391905 -76.150502) (xy 144.461549 -76.107652) (xy 144.534833 -76.071377)
			(xy 144.611137 -76.041982) (xy 144.689818 -76.019717) (xy 144.770211 -76.004769) (xy 144.851637 -75.997264)
			(xy 144.892522 -75.9968) (xy 144.93487 -75.997289) (xy 145.019183 -76.005341) (xy 145.102348 -76.021372)
			(xy 145.183614 -76.045236) (xy 145.262242 -76.076716) (xy 145.337523 -76.115527) (xy 145.408773 -76.161318)
			(xy 145.475349 -76.213675) (xy 145.536645 -76.272123) (xy 145.592109 -76.336133) (xy 145.641237 -76.405125)
			(xy 145.683585 -76.478475) (xy 145.718768 -76.555518) (xy 145.74647 -76.635556) (xy 145.766437 -76.717865)
			(xy 145.778491 -76.8017) (xy 145.782521 -76.8863) (xy 145.778491 -76.9709) (xy 145.766437 -77.054735)
			(xy 145.74647 -77.137044) (xy 145.718768 -77.217082) (xy 145.683585 -77.294125) (xy 145.641237 -77.367475)
			(xy 145.592109 -77.436467) (xy 145.536645 -77.500477) (xy 145.475349 -77.558925) (xy 145.408773 -77.611282)
			(xy 145.337523 -77.657073) (xy 145.262242 -77.695884) (xy 145.183614 -77.727364) (xy 145.102348 -77.751228)
			(xy 145.019183 -77.767259) (xy 144.93487 -77.775311) (xy 144.892522 -77.775816) (xy 144.849367 -77.775309)
			(xy 144.763462 -77.766948) (xy 144.678771 -77.750304) (xy 144.596091 -77.725532) (xy 144.516201 -77.692865)
			(xy 144.439851 -77.652611) (xy 144.367762 -77.60515) (xy 144.300609 -77.550927) (xy 144.26946 -77.521054)
			(xy 144.262348 -77.514196) (xy 144.244568 -77.506576) (xy 144.154906 -77.504798) (xy 144.136872 -77.511656)
			(xy 144.12976 -77.518006) (xy 144.099129 -77.54509) (xy 144.033716 -77.594154) (xy 143.964075 -77.637007)
			(xy 143.890794 -77.673285) (xy 143.814492 -77.702683) (xy 143.735813 -77.724951) (xy 143.655423 -77.739902)
			(xy 143.573999 -77.747411) (xy 143.533114 -77.747876) (xy 143.490763 -77.747453) (xy 143.406444 -77.739402)
			(xy 143.323272 -77.723373) (xy 143.242 -77.699511) (xy 143.163365 -77.668031) (xy 143.088078 -77.629219)
			(xy 143.016821 -77.583426) (xy 142.95024 -77.531067) (xy 142.888938 -77.472617) (xy 142.833469 -77.408603)
			(xy 142.784337 -77.339607) (xy 142.741985 -77.266253) (xy 142.706798 -77.189205) (xy 142.679094 -77.109161)
			(xy 142.659125 -77.026847) (xy 142.64707 -76.943006) (xy 142.64304 -76.8584) (xy 137.004044 -76.8584)
			(xy 137.004044 -79.871062) (xy 137.003608 -79.881126) (xy 136.995872 -79.899709) (xy 136.989058 -79.90713)
			(xy 136.987788 -79.9084) (xy 136.980932 -79.915794) (xy 136.973184 -79.934393) (xy 136.972802 -79.944468)
			(xy 136.972802 -80.55229) (xy 136.973275 -80.562161) (xy 136.980737 -80.580441) (xy 136.98728 -80.58785)
			(xy 136.987534 -80.588104) (xy 137.5791 -81.17967) (xy 137.582656 -81.182972) (xy 137.589669 -81.188376)
			(xy 137.60632 -81.194357) (xy 137.615168 -81.194656) (xy 158.36519 -81.194656) (xy 158.374023 -81.194277)
			(xy 158.390651 -81.188305) (xy 158.397702 -81.182972) (xy 158.39948 -81.181448) (xy 158.960312 -80.620616)
			(xy 158.96082 -80.620108) (xy 158.9674 -80.612726) (xy 158.974841 -80.594427) (xy 158.975298 -80.584548)
			(xy 158.975298 -69.922136) (xy 158.974863 -69.912071) (xy 158.967132 -69.893484) (xy 158.960312 -69.886068)
			(xy 158.938722 -69.864478) (xy 158.935166 -69.86143) (xy 158.929753 -69.857214) (xy 158.917268 -69.851534)
			(xy 158.910528 -69.850254) (xy 158.905194 -69.849746) (xy 158.877584 -69.847911) (xy 158.823283 -69.837271)
			(xy 158.771089 -69.818897) (xy 158.722097 -69.793175) (xy 158.677335 -69.760646) (xy 158.637742 -69.72199)
			(xy 158.604149 -69.678021) (xy 158.577261 -69.629659) (xy 158.557642 -69.577921) (xy 158.545703 -69.523891)
			(xy 158.541695 -69.468702) (xy 158.545702 -69.413514) (xy 158.55764 -69.359484) (xy 158.577259 -69.307745)
			(xy 158.604147 -69.259383) (xy 158.637739 -69.215413) (xy 158.677332 -69.176757) (xy 158.722093 -69.144227)
			(xy 158.771085 -69.118505) (xy 158.823279 -69.100131) (xy 158.877579 -69.089489) (xy 158.905194 -69.087746)
			(xy 158.910528 -69.087238) (xy 158.917269 -69.085957) (xy 158.929758 -69.080287) (xy 158.935166 -69.076062)
			(xy 158.938722 -69.073014) (xy 158.960312 -69.051424) (xy 158.961328 -69.050154) (xy 158.961582 -69.050154)
			(xy 158.967857 -69.042861) (xy 158.974892 -69.02497) (xy 158.975298 -69.015356) (xy 158.975298 -65.148968)
			(xy 158.975727 -65.1389) (xy 158.983449 -65.120304) (xy 158.990284 -65.1129) (xy 160.72358 -63.379604)
			(xy 160.730983 -63.37277) (xy 160.749581 -63.365064) (xy 160.759648 -63.364618) (xy 160.769808 -63.364618)
			(xy 160.78835 -63.372238) (xy 160.789112 -63.373) (xy 175.397922 -63.373) (xy 175.407149 -63.372596)
			(xy 175.424398 -63.366038) (xy 175.438197 -63.353786) (xy 175.44288 -63.345822) (xy 175.48479 -63.26632)
			(xy 175.487818 -63.26003) (xy 175.490664 -63.24637) (xy 175.490378 -63.239396) (xy 175.489616 -63.225426)
			(xy 175.481742 -63.213742) (xy 175.481488 -63.213488) (xy 175.46558 -63.189497) (xy 175.440401 -63.137735)
			(xy 175.423301 -63.082772) (xy 175.414669 -63.025861) (xy 175.414178 -62.99708) (xy 175.414665 -62.969829)
			(xy 175.422424 -62.915883) (xy 175.437781 -62.86359) (xy 175.460423 -62.814014) (xy 175.489889 -62.768165)
			(xy 175.525581 -62.726976) (xy 175.56677 -62.691286) (xy 175.61262 -62.66182) (xy 175.662195 -62.639178)
			(xy 175.714489 -62.623823) (xy 175.768435 -62.616065) (xy 175.795686 -62.615572) (xy 175.822287 -62.616039)
			(xy 175.874972 -62.623439) (xy 175.926119 -62.638083) (xy 175.974737 -62.659687) (xy 176.019884 -62.687834)
			(xy 176.060684 -62.721977) (xy 176.096349 -62.761456) (xy 176.111662 -62.783212) (xy 176.11919 -62.793231)
			(xy 176.141308 -62.804945) (xy 176.153826 -62.805564) (xy 176.237646 -62.805564) (xy 176.250156 -62.804925)
			(xy 176.272266 -62.793211) (xy 176.27981 -62.783212) (xy 176.2951 -62.761434) (xy 176.330752 -62.721932)
			(xy 176.37155 -62.687771) (xy 176.4167 -62.659612) (xy 176.465326 -62.638003) (xy 176.516484 -62.623364)
			(xy 176.56918 -62.615979) (xy 176.595786 -62.615572) (xy 176.625299 -62.616122) (xy 176.683622 -62.625211)
			(xy 176.739849 -62.643173) (xy 176.792639 -62.669581) (xy 176.840732 -62.703804) (xy 176.862232 -62.72403)
			(xy 176.868885 -62.729941) (xy 176.885112 -62.737215) (xy 176.902847 -62.738523) (xy 176.911508 -62.736476)
			(xy 176.996598 -62.7126) (xy 177.002884 -62.710552) (xy 177.014211 -62.703746) (xy 177.01895 -62.699138)
			(xy 177.023776 -62.694058) (xy 177.03038 -62.682628) (xy 177.031904 -62.67577) (xy 177.039207 -62.648616)
			(xy 177.0607 -62.596656) (xy 177.089585 -62.548414) (xy 177.125238 -62.504932) (xy 177.166885 -62.467153)
			(xy 177.213626 -62.435895) (xy 177.264447 -62.411835) (xy 177.31825 -62.395494) (xy 177.373868 -62.387225)
			(xy 177.401982 -62.386718) (xy 177.429234 -62.38718) (xy 177.483183 -62.394934) (xy 177.535479 -62.410288)
			(xy 177.585058 -62.432928) (xy 177.630911 -62.462393) (xy 177.672103 -62.498084) (xy 177.707796 -62.539275)
			(xy 177.737264 -62.585126) (xy 177.759906 -62.634704) (xy 177.775262 -62.686999) (xy 177.783019 -62.740948)
			(xy 177.783019 -62.795452) (xy 177.775262 -62.849401) (xy 177.759906 -62.901696) (xy 177.737264 -62.951274)
			(xy 177.707796 -62.997125) (xy 177.672103 -63.038316) (xy 177.630911 -63.074007) (xy 177.585058 -63.103472)
			(xy 177.535479 -63.126112) (xy 177.483183 -63.141466) (xy 177.429234 -63.14922) (xy 177.401982 -63.149734)
			(xy 177.37247 -63.149181) (xy 177.314149 -63.140088) (xy 177.257925 -63.122122) (xy 177.205138 -63.095712)
			(xy 177.157049 -63.061488) (xy 177.135536 -63.041276) (xy 177.128882 -63.03537) (xy 177.112656 -63.028105)
			(xy 177.094925 -63.026807) (xy 177.08626 -63.02883) (xy 177.00117 -63.052706) (xy 176.994887 -63.054757)
			(xy 176.983565 -63.061569) (xy 176.978818 -63.066168) (xy 176.973992 -63.071248) (xy 176.967388 -63.082678)
			(xy 176.965864 -63.089536) (xy 176.956906 -63.122553) (xy 176.9288 -63.184917) (xy 176.909984 -63.213488)
			(xy 176.90973 -63.213742) (xy 176.909476 -63.213996) (xy 176.905924 -63.219701) (xy 176.901678 -63.232447)
			(xy 176.901094 -63.239142) (xy 176.901094 -63.239396) (xy 176.900817 -63.246371) (xy 176.903641 -63.260037)
			(xy 176.906682 -63.26632) (xy 176.948592 -63.345822) (xy 176.953236 -63.353813) (xy 176.967054 -63.366063)
			(xy 176.984317 -63.372623) (xy 176.99355 -63.373) (xy 182.884318 -63.373) (xy 182.894387 -63.373427)
			(xy 182.912986 -63.381146) (xy 182.920386 -63.387986) (xy 184.160414 -64.628014) (xy 184.167268 -64.635409)
			(xy 184.17501 -64.654008) (xy 184.1754 -64.664082) (xy 184.1754 -67.744848) (xy 184.175612 -67.751659)
			(xy 184.179208 -67.764797) (xy 184.182512 -67.770756) (xy 184.186178 -67.776467) (xy 184.195962 -67.785866)
			(xy 184.201816 -67.789298) (xy 184.279794 -67.83197) (xy 184.287953 -67.836012) (xy 184.30596 -67.838624)
			(xy 184.323746 -67.834782) (xy 184.33161 -67.830192) (xy 184.367376 -67.80795) (xy 184.442343 -67.769551)
			(xy 184.520603 -67.73841) (xy 184.601457 -67.714805) (xy 184.68418 -67.698949) (xy 184.768032 -67.690982)
			(xy 184.810146 -67.690492) (xy 184.810654 -67.690492) (xy 184.857018 -67.691088) (xy 184.949243 -67.700735)
			(xy 185.039964 -67.719928) (xy 185.128193 -67.748459) (xy 185.170826 -67.766692) (xy 185.180768 -67.770498)
			(xy 185.202032 -67.770498) (xy 185.211974 -67.766692) (xy 185.254579 -67.748477) (xy 185.342748 -67.719965)
			(xy 185.433402 -67.700769) (xy 185.52556 -67.691098) (xy 185.571892 -67.690492) (xy 185.5724 -67.690492)
			(xy 185.614748 -67.690996) (xy 185.699062 -67.699047) (xy 185.782228 -67.715076) (xy 185.863495 -67.738937)
			(xy 185.942125 -67.770416) (xy 186.017406 -67.809227) (xy 186.088658 -67.855017) (xy 186.155234 -67.907373)
			(xy 186.216532 -67.965821) (xy 186.271997 -68.029831) (xy 186.321126 -68.098823) (xy 186.363475 -68.172173)
			(xy 186.398659 -68.249216) (xy 186.426361 -68.329255) (xy 186.446329 -68.411564) (xy 186.458382 -68.495399)
			(xy 186.462413 -68.58) (xy 186.458382 -68.664601) (xy 186.446329 -68.748436) (xy 186.426361 -68.830745)
			(xy 186.398659 -68.910784) (xy 186.363475 -68.987827) (xy 186.321126 -69.061177) (xy 186.271997 -69.130169)
			(xy 186.216532 -69.194179) (xy 186.155234 -69.252627) (xy 186.088658 -69.304983) (xy 186.017406 -69.350773)
			(xy 185.942125 -69.389584) (xy 185.863495 -69.421063) (xy 185.782228 -69.444924) (xy 185.699062 -69.460953)
			(xy 185.614748 -69.469004) (xy 185.5724 -69.469508) (xy 185.571892 -69.469508) (xy 185.52556 -69.4689)
			(xy 185.4334 -69.45924) (xy 185.342744 -69.440048) (xy 185.254577 -69.41153) (xy 185.211974 -69.393308)
			(xy 185.202032 -69.389502) (xy 185.180768 -69.389502) (xy 185.170826 -69.393308) (xy 185.128191 -69.411534)
			(xy 185.03996 -69.44006) (xy 184.949241 -69.459255) (xy 184.857018 -69.468914) (xy 184.810654 -69.469508)
			(xy 184.810146 -69.469508) (xy 184.768031 -69.469018) (xy 184.684178 -69.461058) (xy 184.601452 -69.445207)
			(xy 184.520596 -69.421606) (xy 184.442334 -69.390466) (xy 184.367366 -69.352066) (xy 184.33161 -69.329808)
			(xy 184.323751 -69.325201) (xy 184.305961 -69.321342) (xy 184.287947 -69.323966) (xy 184.279794 -69.32803)
			(xy 184.201816 -69.370702) (xy 184.194057 -69.3754) (xy 184.182208 -69.389118) (xy 184.175845 -69.406091)
			(xy 184.1754 -69.415152) (xy 184.1754 -70.336918) (xy 184.174973 -70.346987) (xy 184.167254 -70.365586)
			(xy 184.160414 -70.372986) (xy 183.645048 -70.888352) (xy 183.637428 -70.90537) (xy 183.63692 -70.914768)
			(xy 183.633896 -70.956654) (xy 183.620939 -71.039634) (xy 183.600217 -71.121023) (xy 183.571916 -71.200097)
			(xy 183.536287 -71.27615) (xy 183.493648 -71.348506) (xy 183.444377 -71.41652) (xy 183.388915 -71.479587)
			(xy 183.327754 -71.537145) (xy 183.26144 -71.588682) (xy 183.190563 -71.633738) (xy 183.115755 -71.671911)
			(xy 183.037681 -71.702863) (xy 182.957037 -71.726318) (xy 182.874542 -71.742066) (xy 182.790929 -71.749968)
			(xy 182.748936 -71.750428) (xy 182.70668 -71.749926) (xy 182.622551 -71.741903) (xy 182.539561 -71.725937)
			(xy 182.458461 -71.70217) (xy 182.37998 -71.670817) (xy 182.304827 -71.632162) (xy 182.23368 -71.586552)
			(xy 182.16718 -71.534399) (xy 182.105928 -71.476173) (xy 182.050474 -71.412399) (xy 182.00132 -71.343653)
			(xy 181.958908 -71.270554) (xy 181.923622 -71.193762) (xy 181.909212 -71.154036) (xy 181.90845 -71.152004)
			(xy 181.904351 -71.142952) (xy 181.890568 -71.128667) (xy 181.872388 -71.120696) (xy 181.862476 -71.12)
			(xy 180.640482 -71.12) (xy 180.630413 -71.119573) (xy 180.611814 -71.111854) (xy 180.604414 -71.105014)
			(xy 179.872386 -70.372986) (xy 179.865532 -70.365591) (xy 179.85779 -70.346992) (xy 179.8574 -70.336918)
			(xy 179.8574 -70.146418) (xy 179.85683 -70.134752) (xy 179.8465 -70.113835) (xy 179.837588 -70.106286)
			(xy 179.763928 -70.049898) (xy 179.740814 -70.045326) (xy 179.72913 -70.048374) (xy 179.691347 -70.058144)
			(xy 179.614505 -70.07181) (xy 179.53676 -70.078679) (xy 179.497736 -70.079108) (xy 179.458941 -70.078671)
			(xy 179.381648 -70.071885) (xy 179.305239 -70.058397) (xy 179.230294 -70.03831) (xy 179.157382 -70.011775)
			(xy 179.087056 -69.978994) (xy 179.053236 -69.959982) (xy 179.047394 -69.95668) (xy 179.034694 -69.953124)
			(xy 179.020978 -69.953124) (xy 179.008278 -69.95668) (xy 179.002436 -69.959982) (xy 178.968632 -69.979026)
			(xy 178.898309 -70.011822) (xy 178.825396 -70.038364) (xy 178.750446 -70.05845) (xy 178.674032 -70.071927)
			(xy 178.596733 -70.078693) (xy 178.557936 -70.079108) (xy 178.515586 -70.078622) (xy 178.431268 -70.070573)
			(xy 178.348098 -70.054547) (xy 178.266827 -70.030686) (xy 178.188193 -69.999209) (xy 178.112907 -69.960399)
			(xy 178.041651 -69.914608) (xy 177.97507 -69.862251) (xy 177.913768 -69.803802) (xy 177.8583 -69.739791)
			(xy 177.809168 -69.670796) (xy 177.766817 -69.597444) (xy 177.73163 -69.520398) (xy 177.703926 -69.440356)
			(xy 177.683957 -69.358043) (xy 177.671902 -69.274205) (xy 177.667872 -69.1896) (xy 177.671902 -69.104995)
			(xy 177.683957 -69.021157) (xy 177.703926 -68.938844) (xy 177.73163 -68.858802) (xy 177.766817 -68.781756)
			(xy 177.809168 -68.708404) (xy 177.8583 -68.639409) (xy 177.913768 -68.575398) (xy 177.97507 -68.516949)
			(xy 178.041651 -68.464592) (xy 178.112907 -68.418801) (xy 178.188193 -68.379991) (xy 178.266827 -68.348514)
			(xy 178.348098 -68.324653) (xy 178.431268 -68.308627) (xy 178.515586 -68.300578) (xy 178.557936 -68.300092)
			(xy 178.596731 -68.300528) (xy 178.674025 -68.307311) (xy 178.750435 -68.320797) (xy 178.825382 -68.340882)
			(xy 178.898295 -68.367416) (xy 178.968622 -68.400195) (xy 179.002436 -68.419218) (xy 179.008278 -68.42252)
			(xy 179.020978 -68.426076) (xy 179.034694 -68.426076) (xy 179.047394 -68.42252) (xy 179.053236 -68.419218)
			(xy 179.087045 -68.400184) (xy 179.157367 -68.367386) (xy 179.230279 -68.340842) (xy 179.305227 -68.320754)
			(xy 179.381641 -68.307275) (xy 179.458939 -68.300506) (xy 179.497736 -68.300092) (xy 179.536759 -68.300538)
			(xy 179.614501 -68.307419) (xy 179.691343 -68.321073) (xy 179.72913 -68.330826) (xy 179.740814 -68.333874)
			(xy 179.763928 -68.329302) (xy 179.837588 -68.272914) (xy 179.846447 -68.265327) (xy 179.856748 -68.244429)
			(xy 179.8574 -68.232782) (xy 179.8574 -67.585082) (xy 179.856973 -67.575013) (xy 179.849254 -67.556414)
			(xy 179.842414 -67.549014) (xy 179.51196 -67.21856) (xy 179.505677 -67.212834) (xy 179.490378 -67.205452)
			(xy 179.481988 -67.204082) (xy 179.48148 -67.204082) (xy 179.43909 -67.19914) (xy 179.355446 -67.182171)
			(xy 179.273811 -67.157273) (xy 179.194935 -67.124672) (xy 179.119542 -67.08467) (xy 179.048325 -67.037634)
			(xy 178.981938 -66.983995) (xy 178.920992 -66.924248) (xy 178.866046 -66.858939) (xy 178.8414 -66.824098)
			(xy 178.833874 -66.814204) (xy 178.811906 -66.802627) (xy 178.79949 -66.802) (xy 168.192704 -66.802)
			(xy 168.167558 -66.818256) (xy 168.161462 -66.831972) (xy 168.149777 -66.856713) (xy 168.120372 -66.902854)
			(xy 168.084677 -66.944321) (xy 168.043425 -66.980264) (xy 167.99746 -67.009945) (xy 167.947728 -67.032756)
			(xy 167.895246 -67.048228) (xy 167.841093 -67.056044) (xy 167.786379 -67.056044) (xy 167.732226 -67.048228)
			(xy 167.679744 -67.032756) (xy 167.630012 -67.009945) (xy 167.584047 -66.980264) (xy 167.542795 -66.944321)
			(xy 167.5071 -66.902854) (xy 167.477695 -66.856713) (xy 167.46601 -66.831972) (xy 167.459914 -66.818256)
			(xy 167.434768 -66.802) (xy 167.413432 -66.802) (xy 167.403367 -66.802436) (xy 167.384781 -66.810167)
			(xy 167.377364 -66.816986) (xy 167.328342 -66.866008) (xy 167.323691 -66.871053) (xy 167.316999 -66.883026)
			(xy 167.315134 -66.88963) (xy 167.31488 -66.890138) (xy 167.31488 -66.890392) (xy 167.308353 -66.915885)
			(xy 167.289238 -66.964915) (xy 167.263565 -67.010851) (xy 167.231822 -67.052823) (xy 167.19461 -67.090033)
			(xy 167.152637 -67.121775) (xy 167.1067 -67.147445) (xy 167.057669 -67.166558) (xy 167.032178 -67.173094)
			(xy 167.031924 -67.173094) (xy 167.031416 -67.173348) (xy 167.02479 -67.175159) (xy 167.012803 -67.181857)
			(xy 167.007794 -67.186556) (xy 165.71595 -68.4784) (xy 171.017182 -68.4784) (xy 171.021253 -68.422778)
			(xy 171.033379 -68.368341) (xy 171.053302 -68.31625) (xy 171.080598 -68.267615) (xy 171.114684 -68.223472)
			(xy 171.154833 -68.184763) (xy 171.200191 -68.152312) (xy 171.249791 -68.126811) (xy 171.302575 -68.108804)
			(xy 171.357418 -68.098674) (xy 171.413152 -68.096637) (xy 171.420086 -68.0974) (xy 174.061118 -68.0974)
			(xy 174.065189 -68.041778) (xy 174.077315 -67.987341) (xy 174.097238 -67.93525) (xy 174.124534 -67.886615)
			(xy 174.15862 -67.842472) (xy 174.198769 -67.803763) (xy 174.244127 -67.771312) (xy 174.293727 -67.745811)
			(xy 174.346511 -67.727804) (xy 174.401354 -67.717674) (xy 174.457088 -67.715637) (xy 174.512525 -67.721737)
			(xy 174.566482 -67.735843) (xy 174.617811 -67.757655) (xy 174.665417 -67.786709) (xy 174.708285 -67.822384)
			(xy 174.745502 -67.863921) (xy 174.776275 -67.910434) (xy 174.799947 -67.960931) (xy 174.816015 -68.014338)
			(xy 174.824135 -68.069514) (xy 174.824644 -68.0974) (xy 176.296318 -68.0974) (xy 176.300389 -68.041778)
			(xy 176.312515 -67.987341) (xy 176.332438 -67.93525) (xy 176.359734 -67.886615) (xy 176.39382 -67.842472)
			(xy 176.433969 -67.803763) (xy 176.479327 -67.771312) (xy 176.528927 -67.745811) (xy 176.581711 -67.727804)
			(xy 176.636554 -67.717674) (xy 176.692288 -67.715637) (xy 176.747725 -67.721737) (xy 176.801682 -67.735843)
			(xy 176.853011 -67.757655) (xy 176.900617 -67.786709) (xy 176.943485 -67.822384) (xy 176.980702 -67.863921)
			(xy 177.011475 -67.910434) (xy 177.035147 -67.960931) (xy 177.051215 -68.014338) (xy 177.059335 -68.069514)
			(xy 177.059844 -68.0974) (xy 177.059335 -68.125286) (xy 177.051215 -68.180462) (xy 177.035147 -68.233869)
			(xy 177.011475 -68.284366) (xy 176.980702 -68.330879) (xy 176.943485 -68.372416) (xy 176.900617 -68.408091)
			(xy 176.853011 -68.437145) (xy 176.801682 -68.458957) (xy 176.747725 -68.473063) (xy 176.692288 -68.479163)
			(xy 176.636554 -68.477126) (xy 176.581711 -68.466996) (xy 176.528927 -68.448989) (xy 176.479327 -68.423488)
			(xy 176.433969 -68.391037) (xy 176.39382 -68.352328) (xy 176.359734 -68.308185) (xy 176.332438 -68.25955)
			(xy 176.312515 -68.207459) (xy 176.300389 -68.153022) (xy 176.296318 -68.0974) (xy 174.824644 -68.0974)
			(xy 174.824135 -68.125286) (xy 174.816015 -68.180462) (xy 174.799947 -68.233869) (xy 174.776275 -68.284366)
			(xy 174.745502 -68.330879) (xy 174.708285 -68.372416) (xy 174.665417 -68.408091) (xy 174.617811 -68.437145)
			(xy 174.566482 -68.458957) (xy 174.512525 -68.473063) (xy 174.457088 -68.479163) (xy 174.401354 -68.477126)
			(xy 174.346511 -68.466996) (xy 174.293727 -68.448989) (xy 174.244127 -68.423488) (xy 174.198769 -68.391037)
			(xy 174.15862 -68.352328) (xy 174.124534 -68.308185) (xy 174.097238 -68.25955) (xy 174.077315 -68.207459)
			(xy 174.065189 -68.153022) (xy 174.061118 -68.0974) (xy 171.420086 -68.0974) (xy 171.468589 -68.102737)
			(xy 171.522546 -68.116843) (xy 171.573875 -68.138655) (xy 171.621481 -68.167709) (xy 171.664349 -68.203384)
			(xy 171.701566 -68.244921) (xy 171.732339 -68.291434) (xy 171.756011 -68.341931) (xy 171.772079 -68.395338)
			(xy 171.780199 -68.450514) (xy 171.780708 -68.4784) (xy 171.780199 -68.506286) (xy 171.772079 -68.561462)
			(xy 171.756011 -68.614869) (xy 171.732339 -68.665366) (xy 171.701566 -68.711879) (xy 171.664349 -68.753416)
			(xy 171.621481 -68.789091) (xy 171.573875 -68.818145) (xy 171.522546 -68.839957) (xy 171.468589 -68.854063)
			(xy 171.413152 -68.860163) (xy 171.357418 -68.858126) (xy 171.302575 -68.847996) (xy 171.249791 -68.829989)
			(xy 171.200191 -68.804488) (xy 171.154833 -68.772037) (xy 171.114684 -68.733328) (xy 171.080598 -68.689185)
			(xy 171.053302 -68.64055) (xy 171.033379 -68.588459) (xy 171.021253 -68.534022) (xy 171.017182 -68.4784)
			(xy 165.71595 -68.4784) (xy 165.11143 -69.08292) (xy 165.108128 -69.086476) (xy 165.102727 -69.093489)
			(xy 165.096753 -69.110141) (xy 165.096444 -69.118988) (xy 165.096444 -69.623254) (xy 171.369655 -69.623254)
			(xy 171.369655 -69.568746) (xy 171.377413 -69.514791) (xy 171.392771 -69.462491) (xy 171.415416 -69.412908)
			(xy 171.444888 -69.367053) (xy 171.480585 -69.32586) (xy 171.521782 -69.290166) (xy 171.56764 -69.260699)
			(xy 171.617224 -69.238059) (xy 171.669527 -69.222706) (xy 171.723481 -69.214953) (xy 171.750736 -69.214492)
			(xy 171.777168 -69.21492) (xy 171.829526 -69.222223) (xy 171.880374 -69.236685) (xy 171.928738 -69.258028)
			(xy 171.973693 -69.285844) (xy 171.994322 -69.302376) (xy 172.005342 -69.310878) (xy 172.030752 -69.322202)
			(xy 172.058277 -69.326243) (xy 172.08587 -69.322701) (xy 172.111481 -69.311838) (xy 172.133206 -69.294462)
			(xy 172.149432 -69.271865) (xy 172.154596 -69.258942) (xy 172.165133 -69.231824) (xy 172.193205 -69.180869)
			(xy 172.228691 -69.13477) (xy 172.270767 -69.094596) (xy 172.318457 -69.061278) (xy 172.370654 -69.03559)
			(xy 172.426147 -69.018128) (xy 172.483648 -69.009298) (xy 172.512736 -69.008752) (xy 172.539983 -69.009321)
			(xy 172.593921 -69.01708) (xy 172.646206 -69.032437) (xy 172.695773 -69.055078) (xy 172.741614 -69.084542)
			(xy 172.782796 -69.12023) (xy 172.81848 -69.161415) (xy 172.847939 -69.207259) (xy 172.870575 -69.256828)
			(xy 172.885927 -69.309114) (xy 172.893682 -69.363053) (xy 172.893682 -69.417547) (xy 172.885927 -69.471486)
			(xy 172.870575 -69.523772) (xy 172.847939 -69.573341) (xy 172.81848 -69.619185) (xy 172.782796 -69.66037)
			(xy 172.741614 -69.696058) (xy 172.695773 -69.725522) (xy 172.646206 -69.748163) (xy 172.593921 -69.76352)
			(xy 172.539983 -69.771279) (xy 172.512736 -69.771768) (xy 172.486305 -69.771308) (xy 172.433948 -69.764013)
			(xy 172.383101 -69.74956) (xy 172.334736 -69.728223) (xy 172.28978 -69.700413) (xy 172.26915 -69.683884)
			(xy 172.25817 -69.675323) (xy 172.232748 -69.663992) (xy 172.20521 -69.659951) (xy 172.177605 -69.6635)
			(xy 172.151985 -69.674376) (xy 172.130256 -69.691769) (xy 172.114035 -69.714386) (xy 172.108876 -69.727318)
			(xy 172.098396 -69.754459) (xy 172.070313 -69.805413) (xy 172.034818 -69.85151) (xy 171.992733 -69.891682)
			(xy 171.945035 -69.924997) (xy 171.892832 -69.950681) (xy 171.837333 -69.968138) (xy 171.779826 -69.976965)
			(xy 171.750736 -69.977508) (xy 171.723481 -69.977047) (xy 171.669527 -69.969294) (xy 171.617224 -69.953941)
			(xy 171.56764 -69.931301) (xy 171.521782 -69.901834) (xy 171.480585 -69.86614) (xy 171.444888 -69.824947)
			(xy 171.415416 -69.779092) (xy 171.392771 -69.729509) (xy 171.377413 -69.677209) (xy 171.369655 -69.623254)
			(xy 165.096444 -69.623254) (xy 165.096444 -73.852024) (xy 165.096444 -73.852278) (xy 165.095957 -73.86224)
			(xy 165.088371 -73.880666) (xy 165.081712 -73.888092) (xy 165.066726 -73.903078) (xy 165.059925 -73.910426)
			(xy 165.052217 -73.928889) (xy 165.05174 -73.938892) (xy 165.05174 -74.216006) (xy 165.051314 -74.226074)
			(xy 165.043592 -74.244672) (xy 165.036754 -74.252074) (xy 162.854386 -76.434442) (xy 162.84702 -76.441554)
			(xy 162.8394 -76.46035) (xy 162.8394 -80.750918) (xy 162.839176 -80.757957) (xy 162.835309 -80.771493)
			(xy 162.83178 -80.777588) (xy 162.828224 -80.783684) (xy 162.824414 -80.796892) (xy 162.824414 -82.879184)
			(xy 162.823976 -82.889248) (xy 162.816242 -82.907831) (xy 162.809428 -82.915252) (xy 160.944052 -84.780628)
			(xy 160.936654 -84.787475) (xy 160.918055 -84.795203) (xy 160.907984 -84.795614) (xy 157.508956 -84.795614)
			(xy 157.500992 -84.795886) (xy 157.485843 -84.800807) (xy 157.479238 -84.805266) (xy 157.478984 -84.805266)
			(xy 157.472821 -84.810071) (xy 157.463512 -84.822614) (xy 157.460696 -84.829904) (xy 157.460696 -84.830412)
			(xy 157.451319 -84.856799) (xy 157.425931 -84.906711) (xy 157.393519 -84.952376) (xy 157.354781 -84.992813)
			(xy 157.310548 -85.027153) (xy 157.26177 -85.054658) (xy 157.209496 -85.074738) (xy 157.154848 -85.086962)
			(xy 157.099 -85.091065) (xy 157.043152 -85.086962) (xy 156.988504 -85.074738) (xy 156.93623 -85.054658)
			(xy 156.887452 -85.027153) (xy 156.843219 -84.992813) (xy 156.804481 -84.952376) (xy 156.772069 -84.906711)
			(xy 156.746681 -84.856799) (xy 156.737304 -84.830412) (xy 156.737304 -84.829904) (xy 156.734491 -84.822613)
			(xy 156.725174 -84.810078) (xy 156.719016 -84.805266) (xy 156.718762 -84.805266) (xy 156.712133 -84.800853)
			(xy 156.697 -84.795924) (xy 156.689044 -84.795614) (xy 136.697466 -84.795614) (xy 136.687482 -84.796158)
			(xy 136.66906 -84.803882) (xy 136.661652 -84.8106) (xy 135.344986 -86.127266) (xy 159.68624 -86.127266)
			(xy 159.68624 -86.04257) (xy 159.694291 -85.958256) (xy 159.71032 -85.87509) (xy 159.734181 -85.793823)
			(xy 159.76566 -85.715193) (xy 159.804471 -85.639912) (xy 159.850261 -85.56866) (xy 159.902617 -85.502084)
			(xy 159.961065 -85.440786) (xy 160.025075 -85.385321) (xy 160.094067 -85.336192) (xy 160.167417 -85.293843)
			(xy 160.24446 -85.258659) (xy 160.324499 -85.230957) (xy 160.406808 -85.210989) (xy 160.490643 -85.198936)
			(xy 160.575244 -85.194906) (xy 160.659845 -85.198936) (xy 160.74368 -85.210989) (xy 160.825989 -85.230957)
			(xy 160.906028 -85.258659) (xy 160.983071 -85.293843) (xy 161.056421 -85.336192) (xy 161.125413 -85.385321)
			(xy 161.189423 -85.440786) (xy 161.247871 -85.502084) (xy 161.300227 -85.56866) (xy 161.346017 -85.639912)
			(xy 161.384828 -85.715193) (xy 161.416307 -85.793823) (xy 161.440168 -85.87509) (xy 161.456197 -85.958256)
			(xy 161.464248 -86.04257) (xy 161.464752 -86.084918) (xy 161.464248 -86.127266) (xy 161.456197 -86.21158)
			(xy 161.440168 -86.294746) (xy 161.416307 -86.376013) (xy 161.384828 -86.454643) (xy 161.346017 -86.529924)
			(xy 161.300227 -86.601176) (xy 161.247871 -86.667752) (xy 161.189423 -86.72905) (xy 161.125413 -86.784515)
			(xy 161.056421 -86.833644) (xy 160.983071 -86.875993) (xy 160.906028 -86.911177) (xy 160.825989 -86.938879)
			(xy 160.74368 -86.958847) (xy 160.659845 -86.9709) (xy 160.575244 -86.974931) (xy 160.490643 -86.9709)
			(xy 160.406808 -86.958847) (xy 160.324499 -86.938879) (xy 160.24446 -86.911177) (xy 160.167417 -86.875993)
			(xy 160.094067 -86.833644) (xy 160.025075 -86.784515) (xy 159.961065 -86.72905) (xy 159.902617 -86.667752)
			(xy 159.850261 -86.601176) (xy 159.804471 -86.529924) (xy 159.76566 -86.454643) (xy 159.734181 -86.376013)
			(xy 159.71032 -86.294746) (xy 159.694291 -86.21158) (xy 159.68624 -86.127266) (xy 135.344986 -86.127266)
			(xy 134.28853 -87.183722) (xy 134.281131 -87.190566) (xy 134.262532 -87.198287) (xy 134.252462 -87.198708)
			(xy 126.739396 -87.198708) (xy 126.729326 -87.198285) (xy 126.710722 -87.19057) (xy 126.703328 -87.183722)
			(xy 124.330206 -84.8106) (xy 124.322808 -84.803753) (xy 124.30421 -84.796016) (xy 124.294138 -84.795614)
			(xy 115.995704 -84.795614) (xy 115.985634 -84.796037) (xy 115.96703 -84.803752) (xy 115.959636 -84.8106)
			(xy 115.42649 -85.343746) (xy 115.419124 -85.350858) (xy 115.411504 -85.369654) (xy 115.411504 -89.488518)
			(xy 115.411964 -89.498395) (xy 115.419408 -89.516693) (xy 115.425982 -89.524078) (xy 115.426236 -89.524332)
			(xy 116.082318 -90.180414) (xy 116.082826 -90.180922) (xy 116.090204 -90.187512) (xy 116.108504 -90.194977)
			(xy 116.118386 -90.1954) (xy 163.300918 -90.1954) (xy 163.310795 -90.19494) (xy 163.329094 -90.187497)
			(xy 163.336478 -90.180922) (xy 163.336732 -90.180668) (xy 165.466014 -88.051386) (xy 165.466522 -88.050878)
			(xy 165.473112 -88.0435) (xy 165.480579 -88.025201) (xy 165.481 -88.015318) (xy 165.481 -75.205082)
			(xy 165.481427 -75.195013) (xy 165.489146 -75.176414) (xy 165.495986 -75.169014) (xy 165.847014 -74.817986)
			(xy 165.847522 -74.817478) (xy 165.854112 -74.8101) (xy 165.861579 -74.791801) (xy 165.862 -74.781918)
			(xy 165.862 -71.420482) (xy 165.862427 -71.410413) (xy 165.870146 -71.391814) (xy 165.876986 -71.384414)
			(xy 167.142414 -70.118986) (xy 167.149809 -70.112132) (xy 167.168408 -70.10439) (xy 167.178482 -70.104)
			(xy 172.470318 -70.104) (xy 172.477357 -70.104224) (xy 172.490893 -70.108091) (xy 172.496988 -70.11162)
			(xy 172.503084 -70.115176) (xy 172.516292 -70.118986) (xy 172.586904 -70.118986) (xy 172.596974 -70.119409)
			(xy 172.615579 -70.127123) (xy 172.622972 -70.133972) (xy 173.101 -70.612) (xy 174.061118 -70.612)
			(xy 174.065189 -70.556378) (xy 174.077315 -70.501941) (xy 174.097238 -70.44985) (xy 174.124534 -70.401215)
			(xy 174.15862 -70.357072) (xy 174.198769 -70.318363) (xy 174.244127 -70.285912) (xy 174.293727 -70.260411)
			(xy 174.346511 -70.242404) (xy 174.401354 -70.232274) (xy 174.457088 -70.230237) (xy 174.512525 -70.236337)
			(xy 174.566482 -70.250443) (xy 174.617811 -70.272255) (xy 174.665417 -70.301309) (xy 174.708285 -70.336984)
			(xy 174.745502 -70.378521) (xy 174.776275 -70.425034) (xy 174.799947 -70.475531) (xy 174.816015 -70.528938)
			(xy 174.824135 -70.584114) (xy 174.824644 -70.612) (xy 176.296318 -70.612) (xy 176.300389 -70.556378)
			(xy 176.312515 -70.501941) (xy 176.332438 -70.44985) (xy 176.359734 -70.401215) (xy 176.39382 -70.357072)
			(xy 176.433969 -70.318363) (xy 176.479327 -70.285912) (xy 176.528927 -70.260411) (xy 176.581711 -70.242404)
			(xy 176.636554 -70.232274) (xy 176.692288 -70.230237) (xy 176.747725 -70.236337) (xy 176.801682 -70.250443)
			(xy 176.853011 -70.272255) (xy 176.900617 -70.301309) (xy 176.943485 -70.336984) (xy 176.980702 -70.378521)
			(xy 177.011475 -70.425034) (xy 177.035147 -70.475531) (xy 177.051215 -70.528938) (xy 177.059335 -70.584114)
			(xy 177.059844 -70.612) (xy 177.059335 -70.639886) (xy 177.051215 -70.695062) (xy 177.035147 -70.748469)
			(xy 177.011475 -70.798966) (xy 176.980702 -70.845479) (xy 176.943485 -70.887016) (xy 176.900617 -70.922691)
			(xy 176.853011 -70.951745) (xy 176.801682 -70.973557) (xy 176.747725 -70.987663) (xy 176.692288 -70.993763)
			(xy 176.636554 -70.991726) (xy 176.581711 -70.981596) (xy 176.528927 -70.963589) (xy 176.479327 -70.938088)
			(xy 176.433969 -70.905637) (xy 176.39382 -70.866928) (xy 176.359734 -70.822785) (xy 176.332438 -70.77415)
			(xy 176.312515 -70.722059) (xy 176.300389 -70.667622) (xy 176.296318 -70.612) (xy 174.824644 -70.612)
			(xy 174.824135 -70.639886) (xy 174.816015 -70.695062) (xy 174.799947 -70.748469) (xy 174.776275 -70.798966)
			(xy 174.745502 -70.845479) (xy 174.708285 -70.887016) (xy 174.665417 -70.922691) (xy 174.617811 -70.951745)
			(xy 174.566482 -70.973557) (xy 174.512525 -70.987663) (xy 174.457088 -70.993763) (xy 174.401354 -70.991726)
			(xy 174.346511 -70.981596) (xy 174.293727 -70.963589) (xy 174.244127 -70.938088) (xy 174.198769 -70.905637)
			(xy 174.15862 -70.866928) (xy 174.124534 -70.822785) (xy 174.097238 -70.77415) (xy 174.077315 -70.722059)
			(xy 174.065189 -70.667622) (xy 174.061118 -70.612) (xy 173.101 -70.612) (xy 174.498 -72.009) (xy 177.667872 -72.009)
			(xy 177.671902 -71.924395) (xy 177.683957 -71.840557) (xy 177.703926 -71.758244) (xy 177.73163 -71.678202)
			(xy 177.766817 -71.601156) (xy 177.809168 -71.527804) (xy 177.8583 -71.458809) (xy 177.913768 -71.394798)
			(xy 177.97507 -71.336349) (xy 178.041651 -71.283992) (xy 178.112907 -71.238201) (xy 178.188193 -71.199391)
			(xy 178.266827 -71.167914) (xy 178.348098 -71.144053) (xy 178.431268 -71.128027) (xy 178.515586 -71.119978)
			(xy 178.557936 -71.119492) (xy 178.596733 -71.119907) (xy 178.674032 -71.126673) (xy 178.750446 -71.14015)
			(xy 178.825396 -71.160236) (xy 178.898309 -71.186778) (xy 178.968632 -71.219574) (xy 179.002436 -71.238618)
			(xy 179.008278 -71.24192) (xy 179.020978 -71.245476) (xy 179.034694 -71.245476) (xy 179.047394 -71.24192)
			(xy 179.053236 -71.238618) (xy 179.087056 -71.219606) (xy 179.157382 -71.186825) (xy 179.230294 -71.16029)
			(xy 179.305239 -71.140203) (xy 179.381648 -71.126715) (xy 179.458941 -71.119929) (xy 179.497736 -71.119492)
			(xy 179.540083 -71.119997) (xy 179.624394 -71.128051) (xy 179.707558 -71.144083) (xy 179.788821 -71.167947)
			(xy 179.867448 -71.199427) (xy 179.942727 -71.238239) (xy 180.013976 -71.28403) (xy 180.080549 -71.336386)
			(xy 180.141844 -71.394834) (xy 180.197307 -71.458843) (xy 180.246433 -71.527834) (xy 180.28878 -71.601182)
			(xy 180.323962 -71.678224) (xy 180.351663 -71.758261) (xy 180.37163 -71.840568) (xy 180.383683 -71.924401)
			(xy 180.387713 -72.009) (xy 180.383683 -72.093599) (xy 180.37163 -72.177432) (xy 180.351663 -72.259739)
			(xy 180.323962 -72.339776) (xy 180.28878 -72.416818) (xy 180.246433 -72.490166) (xy 180.197307 -72.559157)
			(xy 180.141844 -72.623166) (xy 180.080549 -72.681614) (xy 180.013976 -72.73397) (xy 179.942727 -72.779761)
			(xy 179.867448 -72.818573) (xy 179.788821 -72.850053) (xy 179.707558 -72.873917) (xy 179.624394 -72.889949)
			(xy 179.540083 -72.898003) (xy 179.497736 -72.898508) (xy 179.458939 -72.898094) (xy 179.381641 -72.891325)
			(xy 179.305227 -72.877846) (xy 179.230279 -72.857758) (xy 179.157367 -72.831214) (xy 179.087045 -72.798416)
			(xy 179.053236 -72.779382) (xy 179.047394 -72.77608) (xy 179.034694 -72.772524) (xy 179.020978 -72.772524)
			(xy 179.008278 -72.77608) (xy 179.002436 -72.779382) (xy 178.968622 -72.798405) (xy 178.898295 -72.831184)
			(xy 178.825382 -72.857718) (xy 178.750435 -72.877803) (xy 178.674025 -72.891289) (xy 178.596731 -72.898072)
			(xy 178.557936 -72.898508) (xy 178.515586 -72.898022) (xy 178.431268 -72.889973) (xy 178.348098 -72.873947)
			(xy 178.266827 -72.850086) (xy 178.188193 -72.818609) (xy 178.112907 -72.779799) (xy 178.041651 -72.734008)
			(xy 177.97507 -72.681651) (xy 177.913768 -72.623202) (xy 177.8583 -72.559191) (xy 177.809168 -72.490196)
			(xy 177.766817 -72.416844) (xy 177.73163 -72.339798) (xy 177.703926 -72.259756) (xy 177.683957 -72.177443)
			(xy 177.671902 -72.093605) (xy 177.667872 -72.009) (xy 174.498 -72.009) (xy 175.6156 -73.1266) (xy 176.321718 -73.1266)
			(xy 176.325789 -73.070978) (xy 176.337915 -73.016541) (xy 176.357838 -72.96445) (xy 176.385134 -72.915815)
			(xy 176.41922 -72.871672) (xy 176.459369 -72.832963) (xy 176.504727 -72.800512) (xy 176.554327 -72.775011)
			(xy 176.607111 -72.757004) (xy 176.661954 -72.746874) (xy 176.717688 -72.744837) (xy 176.773125 -72.750937)
			(xy 176.827082 -72.765043) (xy 176.878411 -72.786855) (xy 176.926017 -72.815909) (xy 176.968885 -72.851584)
			(xy 177.006102 -72.893121) (xy 177.036875 -72.939634) (xy 177.060547 -72.990131) (xy 177.076615 -73.043538)
			(xy 177.084735 -73.098714) (xy 177.085244 -73.1266) (xy 177.084735 -73.154486) (xy 177.076615 -73.209662)
			(xy 177.060547 -73.263069) (xy 177.036875 -73.313566) (xy 177.006102 -73.360079) (xy 176.968885 -73.401616)
			(xy 176.926017 -73.437291) (xy 176.878411 -73.466345) (xy 176.827082 -73.488157) (xy 176.773125 -73.502263)
			(xy 176.717688 -73.508363) (xy 176.661954 -73.506326) (xy 176.607111 -73.496196) (xy 176.554327 -73.478189)
			(xy 176.504727 -73.452688) (xy 176.459369 -73.420237) (xy 176.41922 -73.381528) (xy 176.385134 -73.337385)
			(xy 176.357838 -73.28875) (xy 176.337915 -73.236659) (xy 176.325789 -73.182222) (xy 176.321718 -73.1266)
			(xy 175.6156 -73.1266) (xy 176.388014 -73.899014) (xy 176.388522 -73.899522) (xy 176.3959 -73.906112)
			(xy 176.414199 -73.913579) (xy 176.424082 -73.914) (xy 183.314594 -73.914) (xy 183.323885 -73.913581)
			(xy 183.341248 -73.906959) (xy 183.355134 -73.89461) (xy 183.359806 -73.886568) (xy 183.379678 -73.849214)
			(xy 183.425493 -73.778076) (xy 183.477857 -73.71161) (xy 183.536296 -73.650417) (xy 183.600282 -73.59505)
			(xy 183.669237 -73.546009) (xy 183.742537 -73.503739) (xy 183.81952 -73.46862) (xy 183.89949 -73.440971)
			(xy 183.981725 -73.421041) (xy 184.065481 -73.409011) (xy 184.15 -73.404989) (xy 184.234519 -73.409011)
			(xy 184.318275 -73.421041) (xy 184.40051 -73.440971) (xy 184.48048 -73.46862) (xy 184.557463 -73.503739)
			(xy 184.630763 -73.546009) (xy 184.699718 -73.59505) (xy 184.763704 -73.650417) (xy 184.822143 -73.71161)
			(xy 184.874507 -73.778076) (xy 184.920322 -73.849214) (xy 184.940194 -73.886568) (xy 184.944822 -73.89465)
			(xy 184.958702 -73.907043) (xy 184.976101 -73.91364) (xy 184.985406 -73.914) (xy 186.668918 -73.914)
			(xy 186.678987 -73.914427) (xy 186.697586 -73.922146) (xy 186.704986 -73.928986) (xy 188.326014 -75.550014)
			(xy 188.332868 -75.557409) (xy 188.34061 -75.576008) (xy 188.341 -75.586082) (xy 188.341 -82.147918)
			(xy 188.340573 -82.157987) (xy 188.332854 -82.176586) (xy 188.326014 -82.183986) (xy 185.180986 -85.329014)
			(xy 185.17362 -85.336126) (xy 185.166 -85.354922) (xy 185.166 -94.085918) (xy 185.16646 -94.095795)
			(xy 185.173903 -94.114094) (xy 185.180478 -94.121478) (xy 185.180732 -94.121732) (xy 185.986674 -94.927674)
			(xy 185.987182 -94.928182) (xy 185.994566 -94.934757) (xy 186.012865 -94.942192) (xy 186.022742 -94.94266)
			(xy 208.149698 -94.94266)
		)
		(stroke
			(width 0)
			(type solid)
		)
		(fill yes)
		(layer "In7.Cu")
		(net "GND")
	)
	(gr_poly
		(pts
			(xy 284.466792 -82.6008) (xy 284.476138 -82.600334) (xy 284.493567 -82.593565) (xy 284.507434 -82.581023)
			(xy 284.512004 -82.57286) (xy 284.55239 -82.493612) (xy 284.555295 -82.487293) (xy 284.557873 -82.473631)
			(xy 284.55747 -82.466688) (xy 284.55747 -82.466434) (xy 284.556732 -82.459627) (xy 284.552093 -82.446752)
			(xy 284.548326 -82.441034) (xy 284.548072 -82.44078) (xy 284.547818 -82.440526) (xy 284.524492 -82.407838)
			(xy 284.483154 -82.338985) (xy 284.448182 -82.266691) (xy 284.419859 -82.191541) (xy 284.398416 -82.114148)
			(xy 284.384026 -82.035139) (xy 284.376806 -81.955155) (xy 284.376368 -81.915) (xy 284.376979 -81.86888)
			(xy 284.386561 -81.77714) (xy 284.40556 -81.686877) (xy 284.433772 -81.599058) (xy 284.451806 -81.556606)
			(xy 284.453076 -81.553558) (xy 284.454854 -81.547716) (xy 284.456632 -81.54162) (xy 284.457394 -81.52892)
			(xy 284.454092 -81.51368) (xy 284.45206 -81.5086) (xy 284.451806 -81.507838) (xy 284.451044 -81.505806)
			(xy 284.433567 -81.46401) (xy 284.406222 -81.377636) (xy 284.387805 -81.288928) (xy 284.378507 -81.198807)
			(xy 284.377892 -81.153508) (xy 284.377892 -81.153) (xy 284.378396 -81.110652) (xy 284.386447 -81.026338)
			(xy 284.402476 -80.943172) (xy 284.426337 -80.861905) (xy 284.457816 -80.783275) (xy 284.496627 -80.707994)
			(xy 284.542417 -80.636742) (xy 284.594773 -80.570166) (xy 284.653221 -80.508868) (xy 284.717231 -80.453403)
			(xy 284.786223 -80.404274) (xy 284.859573 -80.361925) (xy 284.936616 -80.326741) (xy 285.016655 -80.299039)
			(xy 285.098964 -80.279071) (xy 285.182799 -80.267018) (xy 285.2674 -80.262988) (xy 285.352001 -80.267018)
			(xy 285.435836 -80.279071) (xy 285.518145 -80.299039) (xy 285.598184 -80.326741) (xy 285.675227 -80.361925)
			(xy 285.725586 -80.391) (xy 297.102788 -80.391) (xy 297.106818 -80.306399) (xy 297.118871 -80.222564)
			(xy 297.138839 -80.140255) (xy 297.166541 -80.060216) (xy 297.201725 -79.983173) (xy 297.244074 -79.909823)
			(xy 297.293203 -79.840831) (xy 297.348668 -79.776821) (xy 297.409966 -79.718373) (xy 297.476542 -79.666017)
			(xy 297.547794 -79.620227) (xy 297.623075 -79.581416) (xy 297.701705 -79.549937) (xy 297.782972 -79.526076)
			(xy 297.866138 -79.510047) (xy 297.950452 -79.501996) (xy 297.9928 -79.501492) (xy 298.039196 -79.502075)
			(xy 298.131484 -79.51172) (xy 298.222268 -79.530916) (xy 298.310561 -79.559454) (xy 298.353226 -79.577692)
			(xy 298.363166 -79.581512) (xy 298.384434 -79.581512) (xy 298.394374 -79.577692) (xy 298.437036 -79.559447)
			(xy 298.525329 -79.530903) (xy 298.616114 -79.51171) (xy 298.708404 -79.502077) (xy 298.7548 -79.501492)
			(xy 298.797148 -79.501996) (xy 298.881462 -79.510047) (xy 298.964628 -79.526076) (xy 299.045895 -79.549937)
			(xy 299.124525 -79.581416) (xy 299.199806 -79.620227) (xy 299.271058 -79.666017) (xy 299.337634 -79.718373)
			(xy 299.398932 -79.776821) (xy 299.451134 -79.837065) (xy 303.180439 -79.837065) (xy 303.183074 -79.753262)
			(xy 303.193584 -79.670078) (xy 303.211875 -79.588253) (xy 303.237785 -79.508512) (xy 303.271084 -79.431563)
			(xy 303.311477 -79.358089) (xy 303.358605 -79.288742) (xy 303.41205 -79.224139) (xy 303.471337 -79.164851)
			(xy 303.535941 -79.111406) (xy 303.605287 -79.064278) (xy 303.678761 -79.023885) (xy 303.75571 -78.990585)
			(xy 303.835451 -78.964675) (xy 303.917276 -78.946384) (xy 304.00046 -78.935874) (xy 304.084263 -78.933239)
			(xy 304.167943 -78.938502) (xy 304.250756 -78.951617) (xy 304.331967 -78.972466) (xy 304.410856 -79.000866)
			(xy 304.486722 -79.036563) (xy 304.558892 -79.079242) (xy 304.626726 -79.128523) (xy 304.689621 -79.183968)
			(xy 304.747019 -79.245087) (xy 304.79841 -79.311335) (xy 304.843339 -79.382126) (xy 304.881407 -79.456831)
			(xy 304.912276 -79.534787) (xy 304.935671 -79.615302) (xy 304.951386 -79.697661) (xy 304.95928 -79.781134)
			(xy 304.959766 -79.823056) (xy 304.959235 -79.865875) (xy 304.95097 -79.951114) (xy 304.943256 -79.993236)
			(xy 304.941224 -80.004666) (xy 304.946812 -80.026764) (xy 305.012598 -80.104996) (xy 305.033426 -80.114648)
			(xy 305.04511 -80.114394) (xy 305.063398 -80.11414) (xy 305.105323 -80.114573) (xy 305.188801 -80.122464)
			(xy 305.271166 -80.138176) (xy 305.351686 -80.161569) (xy 305.429648 -80.192435) (xy 305.504359 -80.230502)
			(xy 305.575156 -80.27543) (xy 305.641411 -80.326822) (xy 305.702536 -80.38422) (xy 305.757988 -80.447117)
			(xy 305.807274 -80.514952) (xy 305.849958 -80.587125) (xy 305.885661 -80.662994) (xy 305.914065 -80.741886)
			(xy 305.934919 -80.823101) (xy 305.948038 -80.905919) (xy 305.953304 -80.989603) (xy 305.950672 -81.073412)
			(xy 305.940165 -81.156601) (xy 305.921875 -81.238432) (xy 305.895966 -81.318178) (xy 305.862667 -81.395133)
			(xy 305.822274 -81.468612) (xy 305.775145 -81.537964) (xy 305.721699 -81.602573) (xy 305.66241 -81.661865)
			(xy 305.597804 -81.715315) (xy 305.528455 -81.762448) (xy 305.454978 -81.802845) (xy 305.378025 -81.836148)
			(xy 305.29828 -81.862062) (xy 305.21645 -81.880356) (xy 305.133262 -81.890868) (xy 305.049453 -81.893505)
			(xy 304.965768 -81.888243) (xy 304.88295 -81.87513) (xy 304.801734 -81.85428) (xy 304.72284 -81.82588)
			(xy 304.646969 -81.790182) (xy 304.574794 -81.747502) (xy 304.506956 -81.698219) (xy 304.444056 -81.642771)
			(xy 304.386654 -81.581649) (xy 304.335259 -81.515397) (xy 304.290327 -81.444603) (xy 304.252256 -81.369894)
			(xy 304.221385 -81.291934) (xy 304.197987 -81.211414) (xy 304.182271 -81.12905) (xy 304.174376 -81.045573)
			(xy 304.17389 -81.003648) (xy 304.174406 -80.960828) (xy 304.182681 -80.875589) (xy 304.1904 -80.833468)
			(xy 304.192432 -80.822038) (xy 304.186844 -80.79994) (xy 304.121058 -80.721708) (xy 304.10023 -80.712056)
			(xy 304.088546 -80.71231) (xy 304.070258 -80.712564) (xy 304.028336 -80.712081) (xy 303.944863 -80.704186)
			(xy 303.862504 -80.688472) (xy 303.781989 -80.665076) (xy 303.704033 -80.634208) (xy 303.629328 -80.59614)
			(xy 303.558537 -80.551211) (xy 303.492288 -80.49982) (xy 303.43117 -80.442422) (xy 303.375724 -80.379527)
			(xy 303.326443 -80.311694) (xy 303.283764 -80.239524) (xy 303.248067 -80.163658) (xy 303.219667 -80.084769)
			(xy 303.198817 -80.003558) (xy 303.185702 -79.920745) (xy 303.180439 -79.837065) (xy 299.451134 -79.837065)
			(xy 299.454397 -79.840831) (xy 299.503526 -79.909823) (xy 299.545875 -79.983173) (xy 299.581059 -80.060216)
			(xy 299.608761 -80.140255) (xy 299.628729 -80.222564) (xy 299.640782 -80.306399) (xy 299.644813 -80.391)
			(xy 299.640782 -80.475601) (xy 299.628729 -80.559436) (xy 299.608761 -80.641745) (xy 299.581059 -80.721784)
			(xy 299.545875 -80.798827) (xy 299.503526 -80.872177) (xy 299.454397 -80.941169) (xy 299.398932 -81.005179)
			(xy 299.337634 -81.063627) (xy 299.271058 -81.115983) (xy 299.199806 -81.161773) (xy 299.124525 -81.200584)
			(xy 299.045895 -81.232063) (xy 298.964628 -81.255924) (xy 298.881462 -81.271953) (xy 298.797148 -81.280004)
			(xy 298.7548 -81.280508) (xy 298.708404 -81.279925) (xy 298.616116 -81.27028) (xy 298.525332 -81.251084)
			(xy 298.437039 -81.222546) (xy 298.394374 -81.204308) (xy 298.384434 -81.200488) (xy 298.363166 -81.200488)
			(xy 298.353226 -81.204308) (xy 298.310564 -81.222553) (xy 298.222271 -81.251097) (xy 298.131486 -81.27029)
			(xy 298.039196 -81.279923) (xy 297.9928 -81.280508) (xy 297.950452 -81.280004) (xy 297.866138 -81.271953)
			(xy 297.782972 -81.255924) (xy 297.701705 -81.232063) (xy 297.623075 -81.200584) (xy 297.547794 -81.161773)
			(xy 297.476542 -81.115983) (xy 297.409966 -81.063627) (xy 297.348668 -81.005179) (xy 297.293203 -80.941169)
			(xy 297.244074 -80.872177) (xy 297.201725 -80.798827) (xy 297.166541 -80.721784) (xy 297.138839 -80.641745)
			(xy 297.118871 -80.559436) (xy 297.106818 -80.475601) (xy 297.102788 -80.391) (xy 285.725586 -80.391)
			(xy 285.748577 -80.404274) (xy 285.817569 -80.453403) (xy 285.881579 -80.508868) (xy 285.940027 -80.570166)
			(xy 285.992383 -80.636742) (xy 286.038173 -80.707994) (xy 286.076984 -80.783275) (xy 286.108463 -80.861905)
			(xy 286.132324 -80.943172) (xy 286.148353 -81.026338) (xy 286.156404 -81.110652) (xy 286.156908 -81.153)
			(xy 286.156908 -81.153508) (xy 286.156298 -81.198979) (xy 286.146937 -81.289439) (xy 286.128385 -81.37847)
			(xy 286.100837 -81.46514) (xy 286.083248 -81.507076) (xy 286.082994 -81.507838) (xy 286.080962 -81.512918)
			(xy 286.078676 -81.52384) (xy 286.07802 -81.527743) (xy 286.077759 -81.535652) (xy 286.078168 -81.539588)
			(xy 286.07893 -81.547462) (xy 286.081978 -81.554574) (xy 286.100242 -81.597234) (xy 286.128834 -81.685522)
			(xy 286.148088 -81.776305) (xy 286.157793 -81.868599) (xy 286.158432 -81.915) (xy 286.157992 -81.954601)
			(xy 286.15094 -82.033488) (xy 286.136909 -82.111437) (xy 286.116011 -82.187831) (xy 286.088411 -82.262068)
			(xy 286.054326 -82.33356) (xy 286.014027 -82.401743) (xy 285.9913 -82.434176) (xy 285.986728 -82.44078)
			(xy 285.98114 -82.458052) (xy 285.98114 -82.45856) (xy 285.977838 -82.468212) (xy 285.979362 -82.488278)
			(xy 286.022796 -82.573114) (xy 286.026248 -82.579282) (xy 286.035918 -82.589584) (xy 286.041846 -82.593434)
			(xy 286.0421 -82.593434) (xy 286.048048 -82.596791) (xy 286.061183 -82.600516) (xy 286.068008 -82.6008)
			(xy 307.247798 -82.6008) (xy 307.25618 -82.600038) (xy 307.263787 -82.598528) (xy 307.277628 -82.591549)
			(xy 307.283358 -82.586322) (xy 310.369966 -79.499714) (xy 310.376803 -79.492313) (xy 310.384511 -79.473714)
			(xy 310.384952 -79.463646) (xy 310.384952 -68.424552) (xy 310.377332 -68.405756) (xy 310.369966 -68.398644)
			(xy 309.449216 -67.477894) (xy 309.441813 -67.471062) (xy 309.423214 -67.463359) (xy 309.413148 -67.462908)
			(xy 308.385464 -67.462908) (xy 308.356254 -67.490594) (xy 308.355238 -67.510914) (xy 308.352445 -67.552982)
			(xy 308.339901 -67.636359) (xy 308.319524 -67.718174) (xy 308.291497 -67.797695) (xy 308.256071 -67.874207)
			(xy 308.213564 -67.947023) (xy 308.164358 -68.015491) (xy 308.108895 -68.078995) (xy 308.047671 -68.136966)
			(xy 307.981236 -68.188884) (xy 307.910187 -68.234283) (xy 307.83516 -68.272756) (xy 307.756831 -68.303956)
			(xy 307.6759 -68.327605) (xy 307.593094 -68.343489) (xy 307.509158 -68.351467) (xy 307.424842 -68.351467)
			(xy 307.340906 -68.343489) (xy 307.2581 -68.327605) (xy 307.177169 -68.303956) (xy 307.09884 -68.272756)
			(xy 307.023813 -68.234283) (xy 306.952764 -68.188884) (xy 306.886329 -68.136966) (xy 306.825105 -68.078995)
			(xy 306.769642 -68.015491) (xy 306.720436 -67.947023) (xy 306.677929 -67.874207) (xy 306.642503 -67.797695)
			(xy 306.614476 -67.718174) (xy 306.594099 -67.636359) (xy 306.581555 -67.552982) (xy 306.578762 -67.510914)
			(xy 306.577746 -67.490594) (xy 306.548536 -67.462908) (xy 305.55438 -67.462908) (xy 305.54354 -67.463404)
			(xy 305.523795 -67.472353) (xy 305.51628 -67.48018) (xy 305.465988 -67.537584) (xy 305.459853 -67.545335)
			(xy 305.453465 -67.56402) (xy 305.453542 -67.573906) (xy 305.453796 -67.578732) (xy 305.453796 -67.58051)
			(xy 305.457083 -67.608015) (xy 305.460643 -67.663301) (xy 305.460908 -67.691) (xy 305.460382 -67.734762)
			(xy 305.451783 -67.821864) (xy 305.434679 -67.907701) (xy 305.409234 -67.991446) (xy 305.375695 -68.072289)
			(xy 305.355498 -68.111116) (xy 305.355244 -68.11137) (xy 305.35499 -68.111878) (xy 305.349768 -68.12312)
			(xy 305.349768 -68.14788) (xy 305.35499 -68.159122) (xy 305.355244 -68.15963) (xy 305.355498 -68.159884)
			(xy 305.375707 -68.198706) (xy 305.409266 -68.279544) (xy 305.434717 -68.363289) (xy 305.451812 -68.44913)
			(xy 305.460386 -68.536236) (xy 305.460908 -68.58) (xy 305.460382 -68.623762) (xy 305.451783 -68.710864)
			(xy 305.434679 -68.796701) (xy 305.409234 -68.880446) (xy 305.375695 -68.961289) (xy 305.355498 -69.000116)
			(xy 305.355244 -69.00037) (xy 305.35499 -69.000878) (xy 305.349768 -69.01212) (xy 305.349768 -69.03688)
			(xy 305.35499 -69.048122) (xy 305.355244 -69.04863) (xy 305.355498 -69.048884) (xy 305.375707 -69.087706)
			(xy 305.409266 -69.168544) (xy 305.434717 -69.252289) (xy 305.451812 -69.33813) (xy 305.460386 -69.425236)
			(xy 305.460908 -69.469) (xy 305.460382 -69.512762) (xy 305.451783 -69.599864) (xy 305.434679 -69.685701)
			(xy 305.409234 -69.769446) (xy 305.375695 -69.850289) (xy 305.355498 -69.889116) (xy 305.355244 -69.88937)
			(xy 305.35499 -69.889878) (xy 305.349768 -69.90112) (xy 305.349768 -69.92588) (xy 305.35499 -69.937122)
			(xy 305.355244 -69.93763) (xy 305.355498 -69.937884) (xy 305.375707 -69.976706) (xy 305.409266 -70.057544)
			(xy 305.434717 -70.141289) (xy 305.451812 -70.22713) (xy 305.460386 -70.314236) (xy 305.460908 -70.358)
			(xy 305.460404 -70.400348) (xy 305.452353 -70.484662) (xy 305.436324 -70.567828) (xy 305.412463 -70.649095)
			(xy 305.380984 -70.727725) (xy 305.342173 -70.803006) (xy 305.296383 -70.874258) (xy 305.244027 -70.940834)
			(xy 305.185579 -71.002132) (xy 305.121569 -71.057597) (xy 305.052577 -71.106726) (xy 304.979227 -71.149075)
			(xy 304.902184 -71.184259) (xy 304.822145 -71.211961) (xy 304.739836 -71.231929) (xy 304.656001 -71.243982)
			(xy 304.5714 -71.248013) (xy 304.486799 -71.243982) (xy 304.402964 -71.231929) (xy 304.320655 -71.211961)
			(xy 304.240616 -71.184259) (xy 304.163573 -71.149075) (xy 304.090223 -71.106726) (xy 304.021231 -71.057597)
			(xy 303.957221 -71.002132) (xy 303.898773 -70.940834) (xy 303.846417 -70.874258) (xy 303.800627 -70.803006)
			(xy 303.761816 -70.727725) (xy 303.730337 -70.649095) (xy 303.706476 -70.567828) (xy 303.690447 -70.484662)
			(xy 303.682396 -70.400348) (xy 303.681892 -70.358) (xy 303.682418 -70.314238) (xy 303.691017 -70.227136)
			(xy 303.708121 -70.141299) (xy 303.733566 -70.057554) (xy 303.767105 -69.976711) (xy 303.787302 -69.937884)
			(xy 303.787556 -69.93763) (xy 303.78781 -69.937122) (xy 303.793032 -69.92588) (xy 303.793032 -69.90112)
			(xy 303.78781 -69.889878) (xy 303.787556 -69.88937) (xy 303.787302 -69.889116) (xy 303.767093 -69.850294)
			(xy 303.733534 -69.769456) (xy 303.708083 -69.685711) (xy 303.690988 -69.59987) (xy 303.682414 -69.512764)
			(xy 303.681892 -69.469) (xy 303.682418 -69.425238) (xy 303.691017 -69.338136) (xy 303.708121 -69.252299)
			(xy 303.733566 -69.168554) (xy 303.767105 -69.087711) (xy 303.787302 -69.048884) (xy 303.787556 -69.04863)
			(xy 303.78781 -69.048122) (xy 303.793032 -69.03688) (xy 303.793032 -69.01212) (xy 303.78781 -69.000878)
			(xy 303.787556 -69.00037) (xy 303.787302 -69.000116) (xy 303.767093 -68.961294) (xy 303.733534 -68.880456)
			(xy 303.708083 -68.796711) (xy 303.690988 -68.71087) (xy 303.682414 -68.623764) (xy 303.681892 -68.58)
			(xy 303.682418 -68.536238) (xy 303.691017 -68.449136) (xy 303.708121 -68.363299) (xy 303.733566 -68.279554)
			(xy 303.767105 -68.198711) (xy 303.787302 -68.159884) (xy 303.787556 -68.15963) (xy 303.78781 -68.159122)
			(xy 303.793032 -68.14788) (xy 303.793032 -68.12312) (xy 303.78781 -68.111878) (xy 303.787556 -68.11137)
			(xy 303.787302 -68.111116) (xy 303.767093 -68.072294) (xy 303.733534 -67.991456) (xy 303.708083 -67.907711)
			(xy 303.690988 -67.82187) (xy 303.682414 -67.734764) (xy 303.681892 -67.691) (xy 303.681892 -67.690746)
			(xy 303.682264 -67.654706) (xy 303.688115 -67.582862) (xy 303.693576 -67.547236) (xy 303.694846 -67.539108)
			(xy 303.693576 -67.530472) (xy 303.692187 -67.523636) (xy 303.686268 -67.511012) (xy 303.681892 -67.50558)
			(xy 303.631854 -67.44716) (xy 303.624277 -67.439149) (xy 303.60426 -67.429954) (xy 303.593246 -67.42938)
			(xy 302.615854 -67.42938) (xy 302.606008 -67.429844) (xy 302.587772 -67.437277) (xy 302.573678 -67.451031)
			(xy 302.565801 -67.469079) (xy 302.565054 -67.47891) (xy 302.565054 -67.479418) (xy 302.563788 -67.521243)
			(xy 302.554363 -67.604393) (xy 302.537169 -67.686291) (xy 302.512359 -67.766211) (xy 302.480151 -67.843447)
			(xy 302.440831 -67.917317) (xy 302.394747 -67.987167) (xy 302.342304 -68.052379) (xy 302.283969 -68.112377)
			(xy 302.220255 -68.16663) (xy 302.151728 -68.214659) (xy 302.078992 -68.256039) (xy 302.00269 -68.290403)
			(xy 301.923499 -68.317449) (xy 301.842116 -68.336936) (xy 301.759264 -68.348693) (xy 301.675673 -68.352616)
			(xy 301.592083 -68.348669) (xy 301.509234 -68.336889) (xy 301.427857 -68.317378) (xy 301.348673 -68.29031)
			(xy 301.272382 -68.255924) (xy 301.199658 -68.214523) (xy 301.131144 -68.166475) (xy 301.067446 -68.112204)
			(xy 301.009127 -68.052189) (xy 300.956704 -67.986962) (xy 300.910639 -67.917099) (xy 300.87134 -67.843218)
			(xy 300.839154 -67.765972) (xy 300.814367 -67.686045) (xy 300.797197 -67.604142) (xy 300.787795 -67.520989)
			(xy 300.786546 -67.479164) (xy 300.786038 -67.458336) (xy 300.756574 -67.42938) (xy 298.374054 -67.42938)
			(xy 298.363988 -67.428948) (xy 298.345397 -67.42122) (xy 298.337986 -67.414394) (xy 296.504614 -65.581022)
			(xy 296.497778 -65.57362) (xy 296.49007 -65.555022) (xy 296.489628 -65.544954) (xy 296.489628 -62.660784)
			(xy 296.482008 -62.641988) (xy 296.474642 -62.634876) (xy 293.087552 -59.247786) (xy 293.080155 -59.240938)
			(xy 293.061556 -59.233207) (xy 293.051484 -59.2328) (xy 282.164282 -59.2328) (xy 282.154213 -59.232373)
			(xy 282.135614 -59.224654) (xy 282.128214 -59.217814) (xy 274.830286 -51.919886) (xy 274.822891 -51.913032)
			(xy 274.804292 -51.90529) (xy 274.794218 -51.9049) (xy 266.571222 -51.9049) (xy 266.552426 -51.91252)
			(xy 266.545314 -51.919886) (xy 265.038586 -53.426614) (xy 265.031732 -53.434009) (xy 265.02399 -53.452608)
			(xy 265.0236 -53.462682) (xy 265.0236 -57.912) (xy 268.756388 -57.912) (xy 268.760418 -57.827399)
			(xy 268.772471 -57.743564) (xy 268.792439 -57.661255) (xy 268.820141 -57.581216) (xy 268.855325 -57.504173)
			(xy 268.897674 -57.430823) (xy 268.946803 -57.361831) (xy 269.002268 -57.297821) (xy 269.063566 -57.239373)
			(xy 269.130142 -57.187017) (xy 269.201394 -57.141227) (xy 269.276675 -57.102416) (xy 269.355305 -57.070937)
			(xy 269.436572 -57.047076) (xy 269.519738 -57.031047) (xy 269.604052 -57.022996) (xy 269.6464 -57.022492)
			(xy 269.692796 -57.023075) (xy 269.785084 -57.03272) (xy 269.875868 -57.051916) (xy 269.964161 -57.080454)
			(xy 270.006826 -57.098692) (xy 270.016766 -57.102512) (xy 270.038034 -57.102512) (xy 270.047974 -57.098692)
			(xy 270.090636 -57.080447) (xy 270.178929 -57.051903) (xy 270.269714 -57.03271) (xy 270.362004 -57.023077)
			(xy 270.4084 -57.022492) (xy 270.451745 -57.023013) (xy 270.538023 -57.031459) (xy 270.62307 -57.048259)
			(xy 270.706078 -57.073255) (xy 270.786261 -57.10621) (xy 270.862856 -57.146811) (xy 270.935137 -57.194672)
			(xy 271.002417 -57.24934) (xy 271.064059 -57.310294) (xy 271.092168 -57.343294) (xy 271.099534 -57.35193)
			(xy 271.119854 -57.361582) (xy 271.220946 -57.361582) (xy 271.241266 -57.35193) (xy 271.248632 -57.343294)
			(xy 271.276731 -57.310288) (xy 271.338386 -57.249349) (xy 271.405674 -57.194695) (xy 271.477959 -57.146844)
			(xy 271.554554 -57.106248) (xy 271.634734 -57.073295) (xy 271.717739 -57.048295) (xy 271.802782 -57.031485)
			(xy 271.889056 -57.023026) (xy 271.9324 -57.022492) (xy 271.978796 -57.023075) (xy 272.071084 -57.03272)
			(xy 272.161868 -57.051916) (xy 272.250161 -57.080454) (xy 272.292826 -57.098692) (xy 272.302766 -57.102512)
			(xy 272.324034 -57.102512) (xy 272.333974 -57.098692) (xy 272.376636 -57.080447) (xy 272.464929 -57.051903)
			(xy 272.555714 -57.03271) (xy 272.648004 -57.023077) (xy 272.6944 -57.022492) (xy 272.736748 -57.022996)
			(xy 272.821062 -57.031047) (xy 272.904228 -57.047076) (xy 272.985495 -57.070937) (xy 273.064125 -57.102416)
			(xy 273.139406 -57.141227) (xy 273.210658 -57.187017) (xy 273.277234 -57.239373) (xy 273.338532 -57.297821)
			(xy 273.393997 -57.361831) (xy 273.443126 -57.430823) (xy 273.485475 -57.504173) (xy 273.520659 -57.581216)
			(xy 273.548361 -57.661255) (xy 273.568329 -57.743564) (xy 273.580382 -57.827399) (xy 273.584413 -57.912)
			(xy 273.580382 -57.996601) (xy 273.568329 -58.080436) (xy 273.548361 -58.162745) (xy 273.520659 -58.242784)
			(xy 273.485475 -58.319827) (xy 273.443126 -58.393177) (xy 273.393997 -58.462169) (xy 273.338532 -58.526179)
			(xy 273.277234 -58.584627) (xy 273.210658 -58.636983) (xy 273.139406 -58.682773) (xy 273.064125 -58.721584)
			(xy 272.985495 -58.753063) (xy 272.904228 -58.776924) (xy 272.821062 -58.792953) (xy 272.736748 -58.801004)
			(xy 272.6944 -58.801508) (xy 272.648004 -58.800925) (xy 272.555716 -58.79128) (xy 272.464932 -58.772084)
			(xy 272.376639 -58.743546) (xy 272.333974 -58.725308) (xy 272.324034 -58.721488) (xy 272.302766 -58.721488)
			(xy 272.292826 -58.725308) (xy 272.250164 -58.743553) (xy 272.161871 -58.772097) (xy 272.071086 -58.79129)
			(xy 271.978796 -58.800923) (xy 271.9324 -58.801508) (xy 271.889055 -58.800987) (xy 271.802777 -58.792541)
			(xy 271.71773 -58.775741) (xy 271.634722 -58.750745) (xy 271.554539 -58.71779) (xy 271.477944 -58.677189)
			(xy 271.405663 -58.629328) (xy 271.338383 -58.57466) (xy 271.276741 -58.513706) (xy 271.248632 -58.480706)
			(xy 271.241266 -58.47207) (xy 271.220946 -58.462418) (xy 271.119854 -58.462418) (xy 271.099534 -58.47207)
			(xy 271.092168 -58.480706) (xy 271.064069 -58.513712) (xy 271.002414 -58.574651) (xy 270.935126 -58.629305)
			(xy 270.862841 -58.677156) (xy 270.786246 -58.717752) (xy 270.706066 -58.750705) (xy 270.623061 -58.775705)
			(xy 270.538018 -58.792515) (xy 270.451744 -58.800974) (xy 270.4084 -58.801508) (xy 270.362004 -58.800925)
			(xy 270.269716 -58.79128) (xy 270.178932 -58.772084) (xy 270.090639 -58.743546) (xy 270.047974 -58.725308)
			(xy 270.038034 -58.721488) (xy 270.016766 -58.721488) (xy 270.006826 -58.725308) (xy 269.964164 -58.743553)
			(xy 269.875871 -58.772097) (xy 269.785086 -58.79129) (xy 269.692796 -58.800923) (xy 269.6464 -58.801508)
			(xy 269.604052 -58.801004) (xy 269.519738 -58.792953) (xy 269.436572 -58.776924) (xy 269.355305 -58.753063)
			(xy 269.276675 -58.721584) (xy 269.201394 -58.682773) (xy 269.130142 -58.636983) (xy 269.063566 -58.584627)
			(xy 269.002268 -58.526179) (xy 268.946803 -58.462169) (xy 268.897674 -58.393177) (xy 268.855325 -58.319827)
			(xy 268.820141 -58.242784) (xy 268.792439 -58.162745) (xy 268.772471 -58.080436) (xy 268.760418 -57.996601)
			(xy 268.756388 -57.912) (xy 265.0236 -57.912) (xy 265.0236 -61.722) (xy 271.531332 -61.722) (xy 271.535403 -61.666378)
			(xy 271.547529 -61.611941) (xy 271.567452 -61.55985) (xy 271.594748 -61.511215) (xy 271.628834 -61.467072)
			(xy 271.668983 -61.428363) (xy 271.714341 -61.395912) (xy 271.763941 -61.370411) (xy 271.816725 -61.352404)
			(xy 271.871568 -61.342274) (xy 271.927302 -61.340237) (xy 271.982739 -61.346337) (xy 272.036696 -61.360443)
			(xy 272.088025 -61.382255) (xy 272.135631 -61.411309) (xy 272.178499 -61.446984) (xy 272.215716 -61.488521)
			(xy 272.246489 -61.535034) (xy 272.270161 -61.585531) (xy 272.286229 -61.638938) (xy 272.294349 -61.694114)
			(xy 272.294858 -61.722) (xy 272.294349 -61.749886) (xy 272.286229 -61.805062) (xy 272.27301 -61.849)
			(xy 279.043382 -61.849) (xy 279.047453 -61.793378) (xy 279.059579 -61.738941) (xy 279.079502 -61.68685)
			(xy 279.106798 -61.638215) (xy 279.140884 -61.594072) (xy 279.181033 -61.555363) (xy 279.226391 -61.522912)
			(xy 279.275991 -61.497411) (xy 279.328775 -61.479404) (xy 279.383618 -61.469274) (xy 279.439352 -61.467237)
			(xy 279.494789 -61.473337) (xy 279.548746 -61.487443) (xy 279.600075 -61.509255) (xy 279.647681 -61.538309)
			(xy 279.690549 -61.573984) (xy 279.727766 -61.615521) (xy 279.758539 -61.662034) (xy 279.782211 -61.712531)
			(xy 279.798279 -61.765938) (xy 279.806399 -61.821114) (xy 279.806908 -61.849) (xy 279.806399 -61.876886)
			(xy 279.798279 -61.932062) (xy 279.78506 -61.976) (xy 289.203382 -61.976) (xy 289.207453 -61.920378)
			(xy 289.219579 -61.865941) (xy 289.239502 -61.81385) (xy 289.266798 -61.765215) (xy 289.300884 -61.721072)
			(xy 289.341033 -61.682363) (xy 289.386391 -61.649912) (xy 289.435991 -61.624411) (xy 289.488775 -61.606404)
			(xy 289.543618 -61.596274) (xy 289.599352 -61.594237) (xy 289.654789 -61.600337) (xy 289.708746 -61.614443)
			(xy 289.760075 -61.636255) (xy 289.807681 -61.665309) (xy 289.850549 -61.700984) (xy 289.887766 -61.742521)
			(xy 289.918539 -61.789034) (xy 289.942211 -61.839531) (xy 289.958279 -61.892938) (xy 289.966399 -61.948114)
			(xy 289.966908 -61.976) (xy 289.966792 -61.98235) (xy 290.600382 -61.98235) (xy 290.604453 -61.926728)
			(xy 290.616579 -61.872291) (xy 290.636502 -61.8202) (xy 290.663798 -61.771565) (xy 290.697884 -61.727422)
			(xy 290.738033 -61.688713) (xy 290.783391 -61.656262) (xy 290.832991 -61.630761) (xy 290.885775 -61.612754)
			(xy 290.940618 -61.602624) (xy 290.996352 -61.600587) (xy 291.051789 -61.606687) (xy 291.105746 -61.620793)
			(xy 291.157075 -61.642605) (xy 291.204681 -61.671659) (xy 291.247549 -61.707334) (xy 291.284766 -61.748871)
			(xy 291.315539 -61.795384) (xy 291.339211 -61.845881) (xy 291.355279 -61.899288) (xy 291.363399 -61.954464)
			(xy 291.363908 -61.98235) (xy 291.363399 -62.010236) (xy 291.355279 -62.065412) (xy 291.339211 -62.118819)
			(xy 291.315539 -62.169316) (xy 291.284766 -62.215829) (xy 291.247549 -62.257366) (xy 291.204681 -62.293041)
			(xy 291.157075 -62.322095) (xy 291.105746 -62.343907) (xy 291.051789 -62.358013) (xy 290.996352 -62.364113)
			(xy 290.940618 -62.362076) (xy 290.885775 -62.351946) (xy 290.832991 -62.333939) (xy 290.783391 -62.308438)
			(xy 290.738033 -62.275987) (xy 290.697884 -62.237278) (xy 290.663798 -62.193135) (xy 290.636502 -62.1445)
			(xy 290.616579 -62.092409) (xy 290.604453 -62.037972) (xy 290.600382 -61.98235) (xy 289.966792 -61.98235)
			(xy 289.966399 -62.003886) (xy 289.958279 -62.059062) (xy 289.942211 -62.112469) (xy 289.918539 -62.162966)
			(xy 289.887766 -62.209479) (xy 289.850549 -62.251016) (xy 289.807681 -62.286691) (xy 289.760075 -62.315745)
			(xy 289.708746 -62.337557) (xy 289.654789 -62.351663) (xy 289.599352 -62.357763) (xy 289.543618 -62.355726)
			(xy 289.488775 -62.345596) (xy 289.435991 -62.327589) (xy 289.386391 -62.302088) (xy 289.341033 -62.269637)
			(xy 289.300884 -62.230928) (xy 289.266798 -62.186785) (xy 289.239502 -62.13815) (xy 289.219579 -62.086059)
			(xy 289.207453 -62.031622) (xy 289.203382 -61.976) (xy 279.78506 -61.976) (xy 279.782211 -61.985469)
			(xy 279.758539 -62.035966) (xy 279.727766 -62.082479) (xy 279.690549 -62.124016) (xy 279.647681 -62.159691)
			(xy 279.600075 -62.188745) (xy 279.548746 -62.210557) (xy 279.494789 -62.224663) (xy 279.439352 -62.230763)
			(xy 279.383618 -62.228726) (xy 279.328775 -62.218596) (xy 279.275991 -62.200589) (xy 279.226391 -62.175088)
			(xy 279.181033 -62.142637) (xy 279.140884 -62.103928) (xy 279.106798 -62.059785) (xy 279.079502 -62.01115)
			(xy 279.059579 -61.959059) (xy 279.047453 -61.904622) (xy 279.043382 -61.849) (xy 272.27301 -61.849)
			(xy 272.270161 -61.858469) (xy 272.246489 -61.908966) (xy 272.215716 -61.955479) (xy 272.178499 -61.997016)
			(xy 272.135631 -62.032691) (xy 272.088025 -62.061745) (xy 272.036696 -62.083557) (xy 271.982739 -62.097663)
			(xy 271.927302 -62.103763) (xy 271.871568 -62.101726) (xy 271.816725 -62.091596) (xy 271.763941 -62.073589)
			(xy 271.714341 -62.048088) (xy 271.668983 -62.015637) (xy 271.628834 -61.976928) (xy 271.594748 -61.932785)
			(xy 271.567452 -61.88415) (xy 271.547529 -61.832059) (xy 271.535403 -61.777622) (xy 271.531332 -61.722)
			(xy 265.0236 -61.722) (xy 265.0236 -62.865) (xy 279.043382 -62.865) (xy 279.047453 -62.809378) (xy 279.059579 -62.754941)
			(xy 279.079502 -62.70285) (xy 279.106798 -62.654215) (xy 279.140884 -62.610072) (xy 279.181033 -62.571363)
			(xy 279.226391 -62.538912) (xy 279.275991 -62.513411) (xy 279.328775 -62.495404) (xy 279.383618 -62.485274)
			(xy 279.439352 -62.483237) (xy 279.494789 -62.489337) (xy 279.548746 -62.503443) (xy 279.600075 -62.525255)
			(xy 279.647681 -62.554309) (xy 279.690549 -62.589984) (xy 279.727766 -62.631521) (xy 279.758539 -62.678034)
			(xy 279.782211 -62.728531) (xy 279.78506 -62.738) (xy 292.740332 -62.738) (xy 292.744403 -62.682378)
			(xy 292.756529 -62.627941) (xy 292.776452 -62.57585) (xy 292.803748 -62.527215) (xy 292.837834 -62.483072)
			(xy 292.877983 -62.444363) (xy 292.923341 -62.411912) (xy 292.972941 -62.386411) (xy 293.025725 -62.368404)
			(xy 293.080568 -62.358274) (xy 293.136302 -62.356237) (xy 293.191739 -62.362337) (xy 293.245696 -62.376443)
			(xy 293.297025 -62.398255) (xy 293.344631 -62.427309) (xy 293.387499 -62.462984) (xy 293.424716 -62.504521)
			(xy 293.455489 -62.551034) (xy 293.479161 -62.601531) (xy 293.495229 -62.654938) (xy 293.503349 -62.710114)
			(xy 293.503858 -62.738) (xy 293.503349 -62.765886) (xy 293.495229 -62.821062) (xy 293.479161 -62.874469)
			(xy 293.455489 -62.924966) (xy 293.424716 -62.971479) (xy 293.387499 -63.013016) (xy 293.344631 -63.048691)
			(xy 293.297025 -63.077745) (xy 293.245696 -63.099557) (xy 293.191739 -63.113663) (xy 293.136302 -63.119763)
			(xy 293.080568 -63.117726) (xy 293.025725 -63.107596) (xy 292.972941 -63.089589) (xy 292.923341 -63.064088)
			(xy 292.877983 -63.031637) (xy 292.837834 -62.992928) (xy 292.803748 -62.948785) (xy 292.776452 -62.90015)
			(xy 292.756529 -62.848059) (xy 292.744403 -62.793622) (xy 292.740332 -62.738) (xy 279.78506 -62.738)
			(xy 279.798279 -62.781938) (xy 279.806399 -62.837114) (xy 279.806908 -62.865) (xy 279.806399 -62.892886)
			(xy 279.798279 -62.948062) (xy 279.782211 -63.001469) (xy 279.758539 -63.051966) (xy 279.727766 -63.098479)
			(xy 279.690549 -63.140016) (xy 279.647681 -63.175691) (xy 279.600075 -63.204745) (xy 279.548746 -63.226557)
			(xy 279.494789 -63.240663) (xy 279.439352 -63.246763) (xy 279.383618 -63.244726) (xy 279.328775 -63.234596)
			(xy 279.275991 -63.216589) (xy 279.226391 -63.191088) (xy 279.181033 -63.158637) (xy 279.140884 -63.119928)
			(xy 279.106798 -63.075785) (xy 279.079502 -63.02715) (xy 279.059579 -62.975059) (xy 279.047453 -62.920622)
			(xy 279.043382 -62.865) (xy 265.0236 -62.865) (xy 265.0236 -64.042036) (xy 294.509442 -64.042036)
			(xy 294.513513 -63.986414) (xy 294.525639 -63.931977) (xy 294.545562 -63.879886) (xy 294.572858 -63.831251)
			(xy 294.606944 -63.787108) (xy 294.647093 -63.748399) (xy 294.692451 -63.715948) (xy 294.742051 -63.690447)
			(xy 294.794835 -63.67244) (xy 294.849678 -63.66231) (xy 294.905412 -63.660273) (xy 294.960849 -63.666373)
			(xy 295.014806 -63.680479) (xy 295.066135 -63.702291) (xy 295.113741 -63.731345) (xy 295.156609 -63.76702)
			(xy 295.193826 -63.808557) (xy 295.224599 -63.85507) (xy 295.248271 -63.905567) (xy 295.264339 -63.958974)
			(xy 295.272459 -64.01415) (xy 295.272968 -64.042036) (xy 295.272459 -64.069922) (xy 295.264339 -64.125098)
			(xy 295.248271 -64.178505) (xy 295.224599 -64.229002) (xy 295.193826 -64.275515) (xy 295.156609 -64.317052)
			(xy 295.113741 -64.352727) (xy 295.066135 -64.381781) (xy 295.014806 -64.403593) (xy 294.960849 -64.417699)
			(xy 294.905412 -64.423799) (xy 294.849678 -64.421762) (xy 294.794835 -64.411632) (xy 294.742051 -64.393625)
			(xy 294.692451 -64.368124) (xy 294.647093 -64.335673) (xy 294.606944 -64.296964) (xy 294.572858 -64.252821)
			(xy 294.545562 -64.204186) (xy 294.525639 -64.152095) (xy 294.513513 -64.097658) (xy 294.509442 -64.042036)
			(xy 265.0236 -64.042036) (xy 265.0236 -65.141094) (xy 272.523202 -65.141094) (xy 272.527273 -65.085472)
			(xy 272.539399 -65.031035) (xy 272.559322 -64.978944) (xy 272.586618 -64.930309) (xy 272.620704 -64.886166)
			(xy 272.660853 -64.847457) (xy 272.706211 -64.815006) (xy 272.755811 -64.789505) (xy 272.808595 -64.771498)
			(xy 272.863438 -64.761368) (xy 272.919172 -64.759331) (xy 272.974609 -64.765431) (xy 272.992086 -64.77)
			(xy 291.616382 -64.77) (xy 291.620453 -64.714378) (xy 291.632579 -64.659941) (xy 291.652502 -64.60785)
			(xy 291.679798 -64.559215) (xy 291.713884 -64.515072) (xy 291.754033 -64.476363) (xy 291.799391 -64.443912)
			(xy 291.848991 -64.418411) (xy 291.901775 -64.400404) (xy 291.956618 -64.390274) (xy 292.012352 -64.388237)
			(xy 292.067789 -64.394337) (xy 292.121746 -64.408443) (xy 292.173075 -64.430255) (xy 292.220681 -64.459309)
			(xy 292.263549 -64.494984) (xy 292.300766 -64.536521) (xy 292.331539 -64.583034) (xy 292.355211 -64.633531)
			(xy 292.371279 -64.686938) (xy 292.379399 -64.742114) (xy 292.379908 -64.77) (xy 292.379399 -64.797886)
			(xy 292.371878 -64.848994) (xy 295.087546 -64.848994) (xy 295.091617 -64.793372) (xy 295.103743 -64.738935)
			(xy 295.123666 -64.686844) (xy 295.150962 -64.638209) (xy 295.185048 -64.594066) (xy 295.225197 -64.555357)
			(xy 295.270555 -64.522906) (xy 295.320155 -64.497405) (xy 295.372939 -64.479398) (xy 295.427782 -64.469268)
			(xy 295.483516 -64.467231) (xy 295.538953 -64.473331) (xy 295.59291 -64.487437) (xy 295.644239 -64.509249)
			(xy 295.691845 -64.538303) (xy 295.734713 -64.573978) (xy 295.77193 -64.615515) (xy 295.802703 -64.662028)
			(xy 295.826375 -64.712525) (xy 295.842443 -64.765932) (xy 295.850563 -64.821108) (xy 295.851072 -64.848994)
			(xy 295.850563 -64.87688) (xy 295.842443 -64.932056) (xy 295.826375 -64.985463) (xy 295.802703 -65.03596)
			(xy 295.77193 -65.082473) (xy 295.734713 -65.12401) (xy 295.691845 -65.159685) (xy 295.644239 -65.188739)
			(xy 295.59291 -65.210551) (xy 295.538953 -65.224657) (xy 295.483516 -65.230757) (xy 295.427782 -65.22872)
			(xy 295.372939 -65.21859) (xy 295.320155 -65.200583) (xy 295.270555 -65.175082) (xy 295.225197 -65.142631)
			(xy 295.185048 -65.103922) (xy 295.150962 -65.059779) (xy 295.123666 -65.011144) (xy 295.103743 -64.959053)
			(xy 295.091617 -64.904616) (xy 295.087546 -64.848994) (xy 292.371878 -64.848994) (xy 292.371279 -64.853062)
			(xy 292.355211 -64.906469) (xy 292.331539 -64.956966) (xy 292.300766 -65.003479) (xy 292.263549 -65.045016)
			(xy 292.220681 -65.080691) (xy 292.173075 -65.109745) (xy 292.121746 -65.131557) (xy 292.067789 -65.145663)
			(xy 292.012352 -65.151763) (xy 291.956618 -65.149726) (xy 291.901775 -65.139596) (xy 291.848991 -65.121589)
			(xy 291.799391 -65.096088) (xy 291.754033 -65.063637) (xy 291.713884 -65.024928) (xy 291.679798 -64.980785)
			(xy 291.652502 -64.93215) (xy 291.632579 -64.880059) (xy 291.620453 -64.825622) (xy 291.616382 -64.77)
			(xy 272.992086 -64.77) (xy 273.028566 -64.779537) (xy 273.079895 -64.801349) (xy 273.127501 -64.830403)
			(xy 273.170369 -64.866078) (xy 273.207586 -64.907615) (xy 273.238359 -64.954128) (xy 273.262031 -65.004625)
			(xy 273.278099 -65.058032) (xy 273.286219 -65.113208) (xy 273.286728 -65.141094) (xy 273.286219 -65.16898)
			(xy 273.278099 -65.224156) (xy 273.262031 -65.277563) (xy 273.238359 -65.32806) (xy 273.207586 -65.374573)
			(xy 273.180324 -65.405) (xy 290.600382 -65.405) (xy 290.604453 -65.349378) (xy 290.616579 -65.294941)
			(xy 290.636502 -65.24285) (xy 290.663798 -65.194215) (xy 290.697884 -65.150072) (xy 290.738033 -65.111363)
			(xy 290.783391 -65.078912) (xy 290.832991 -65.053411) (xy 290.885775 -65.035404) (xy 290.940618 -65.025274)
			(xy 290.996352 -65.023237) (xy 291.051789 -65.029337) (xy 291.105746 -65.043443) (xy 291.157075 -65.065255)
			(xy 291.204681 -65.094309) (xy 291.247549 -65.129984) (xy 291.284766 -65.171521) (xy 291.315539 -65.218034)
			(xy 291.339211 -65.268531) (xy 291.355279 -65.321938) (xy 291.363399 -65.377114) (xy 291.363908 -65.405)
			(xy 291.363399 -65.432886) (xy 291.355279 -65.488062) (xy 291.339211 -65.541469) (xy 291.315539 -65.591966)
			(xy 291.284766 -65.638479) (xy 291.247549 -65.680016) (xy 291.204681 -65.715691) (xy 291.157075 -65.744745)
			(xy 291.119764 -65.7606) (xy 293.292782 -65.7606) (xy 293.296853 -65.704978) (xy 293.308979 -65.650541)
			(xy 293.328902 -65.59845) (xy 293.356198 -65.549815) (xy 293.390284 -65.505672) (xy 293.430433 -65.466963)
			(xy 293.475791 -65.434512) (xy 293.525391 -65.409011) (xy 293.578175 -65.391004) (xy 293.633018 -65.380874)
			(xy 293.688752 -65.378837) (xy 293.744189 -65.384937) (xy 293.798146 -65.399043) (xy 293.849475 -65.420855)
			(xy 293.897081 -65.449909) (xy 293.939949 -65.485584) (xy 293.977166 -65.527121) (xy 294.007939 -65.573634)
			(xy 294.031611 -65.624131) (xy 294.047679 -65.677538) (xy 294.055799 -65.732714) (xy 294.056308 -65.7606)
			(xy 294.055799 -65.788486) (xy 294.047679 -65.843662) (xy 294.031611 -65.897069) (xy 294.007939 -65.947566)
			(xy 293.977166 -65.994079) (xy 293.939949 -66.035616) (xy 293.897081 -66.071291) (xy 293.849475 -66.100345)
			(xy 293.798146 -66.122157) (xy 293.744189 -66.136263) (xy 293.688752 -66.142363) (xy 293.633018 -66.140326)
			(xy 293.578175 -66.130196) (xy 293.525391 -66.112189) (xy 293.475791 -66.086688) (xy 293.430433 -66.054237)
			(xy 293.390284 -66.015528) (xy 293.356198 -65.971385) (xy 293.328902 -65.92275) (xy 293.308979 -65.870659)
			(xy 293.296853 -65.816222) (xy 293.292782 -65.7606) (xy 291.119764 -65.7606) (xy 291.105746 -65.766557)
			(xy 291.051789 -65.780663) (xy 290.996352 -65.786763) (xy 290.940618 -65.784726) (xy 290.885775 -65.774596)
			(xy 290.832991 -65.756589) (xy 290.783391 -65.731088) (xy 290.738033 -65.698637) (xy 290.697884 -65.659928)
			(xy 290.663798 -65.615785) (xy 290.636502 -65.56715) (xy 290.616579 -65.515059) (xy 290.604453 -65.460622)
			(xy 290.600382 -65.405) (xy 273.180324 -65.405) (xy 273.170369 -65.41611) (xy 273.127501 -65.451785)
			(xy 273.079895 -65.480839) (xy 273.028566 -65.502651) (xy 272.974609 -65.516757) (xy 272.919172 -65.522857)
			(xy 272.863438 -65.52082) (xy 272.808595 -65.51069) (xy 272.755811 -65.492683) (xy 272.706211 -65.467182)
			(xy 272.660853 -65.434731) (xy 272.620704 -65.396022) (xy 272.586618 -65.351879) (xy 272.559322 -65.303244)
			(xy 272.539399 -65.251153) (xy 272.527273 -65.196716) (xy 272.523202 -65.141094) (xy 265.0236 -65.141094)
			(xy 265.0236 -67.0814) (xy 270.534382 -67.0814) (xy 270.538453 -67.025778) (xy 270.550579 -66.971341)
			(xy 270.570502 -66.91925) (xy 270.597798 -66.870615) (xy 270.631884 -66.826472) (xy 270.672033 -66.787763)
			(xy 270.717391 -66.755312) (xy 270.766991 -66.729811) (xy 270.819775 -66.711804) (xy 270.874618 -66.701674)
			(xy 270.930352 -66.699637) (xy 270.985789 -66.705737) (xy 271.039746 -66.719843) (xy 271.091075 -66.741655)
			(xy 271.138681 -66.770709) (xy 271.181549 -66.806384) (xy 271.218766 -66.847921) (xy 271.249539 -66.894434)
			(xy 271.273211 -66.944931) (xy 271.289279 -66.998338) (xy 271.297399 -67.053514) (xy 271.297908 -67.0814)
			(xy 272.794982 -67.0814) (xy 272.799053 -67.025778) (xy 272.811179 -66.971341) (xy 272.831102 -66.91925)
			(xy 272.858398 -66.870615) (xy 272.892484 -66.826472) (xy 272.932633 -66.787763) (xy 272.977991 -66.755312)
			(xy 273.027591 -66.729811) (xy 273.080375 -66.711804) (xy 273.135218 -66.701674) (xy 273.190952 -66.699637)
			(xy 273.246389 -66.705737) (xy 273.300346 -66.719843) (xy 273.351675 -66.741655) (xy 273.399281 -66.770709)
			(xy 273.442149 -66.806384) (xy 273.479366 -66.847921) (xy 273.510139 -66.894434) (xy 273.526343 -66.929)
			(xy 277.011382 -66.929) (xy 277.015453 -66.873378) (xy 277.027579 -66.818941) (xy 277.047502 -66.76685)
			(xy 277.074798 -66.718215) (xy 277.108884 -66.674072) (xy 277.149033 -66.635363) (xy 277.194391 -66.602912)
			(xy 277.243991 -66.577411) (xy 277.296775 -66.559404) (xy 277.351618 -66.549274) (xy 277.407352 -66.547237)
			(xy 277.462789 -66.553337) (xy 277.516746 -66.567443) (xy 277.568075 -66.589255) (xy 277.615681 -66.618309)
			(xy 277.658549 -66.653984) (xy 277.695766 -66.695521) (xy 277.726539 -66.742034) (xy 277.750211 -66.792531)
			(xy 277.766279 -66.845938) (xy 277.774399 -66.901114) (xy 277.774908 -66.929) (xy 279.144982 -66.929)
			(xy 279.149053 -66.873378) (xy 279.161179 -66.818941) (xy 279.181102 -66.76685) (xy 279.208398 -66.718215)
			(xy 279.242484 -66.674072) (xy 279.282633 -66.635363) (xy 279.327991 -66.602912) (xy 279.377591 -66.577411)
			(xy 279.430375 -66.559404) (xy 279.485218 -66.549274) (xy 279.540952 -66.547237) (xy 279.596389 -66.553337)
			(xy 279.650346 -66.567443) (xy 279.701675 -66.589255) (xy 279.749281 -66.618309) (xy 279.792149 -66.653984)
			(xy 279.829366 -66.695521) (xy 279.860139 -66.742034) (xy 279.883811 -66.792531) (xy 279.899879 -66.845938)
			(xy 279.907999 -66.901114) (xy 279.908508 -66.929) (xy 279.907999 -66.956886) (xy 279.899879 -67.012062)
			(xy 279.883811 -67.065469) (xy 279.860139 -67.115966) (xy 279.829366 -67.162479) (xy 279.792149 -67.204016)
			(xy 279.749281 -67.239691) (xy 279.701675 -67.268745) (xy 279.650346 -67.290557) (xy 279.596389 -67.304663)
			(xy 279.540952 -67.310763) (xy 279.485218 -67.308726) (xy 279.430375 -67.298596) (xy 279.377591 -67.280589)
			(xy 279.327991 -67.255088) (xy 279.282633 -67.222637) (xy 279.242484 -67.183928) (xy 279.208398 -67.139785)
			(xy 279.181102 -67.09115) (xy 279.161179 -67.039059) (xy 279.149053 -66.984622) (xy 279.144982 -66.929)
			(xy 277.774908 -66.929) (xy 277.774399 -66.956886) (xy 277.766279 -67.012062) (xy 277.750211 -67.065469)
			(xy 277.726539 -67.115966) (xy 277.695766 -67.162479) (xy 277.658549 -67.204016) (xy 277.615681 -67.239691)
			(xy 277.568075 -67.268745) (xy 277.516746 -67.290557) (xy 277.462789 -67.304663) (xy 277.407352 -67.310763)
			(xy 277.351618 -67.308726) (xy 277.296775 -67.298596) (xy 277.243991 -67.280589) (xy 277.194391 -67.255088)
			(xy 277.149033 -67.222637) (xy 277.108884 -67.183928) (xy 277.074798 -67.139785) (xy 277.047502 -67.09115)
			(xy 277.027579 -67.039059) (xy 277.015453 -66.984622) (xy 277.011382 -66.929) (xy 273.526343 -66.929)
			(xy 273.533811 -66.944931) (xy 273.549879 -66.998338) (xy 273.557999 -67.053514) (xy 273.558508 -67.0814)
			(xy 273.557999 -67.109286) (xy 273.549879 -67.164462) (xy 273.533811 -67.217869) (xy 273.510139 -67.268366)
			(xy 273.479366 -67.314879) (xy 273.442149 -67.356416) (xy 273.399281 -67.392091) (xy 273.351675 -67.421145)
			(xy 273.310008 -67.438851) (xy 286.588178 -67.438851) (xy 286.588178 -67.384349) (xy 286.595934 -67.330401)
			(xy 286.611289 -67.278106) (xy 286.633931 -67.228529) (xy 286.663397 -67.182679) (xy 286.699088 -67.141488)
			(xy 286.740279 -67.105797) (xy 286.786129 -67.076331) (xy 286.835706 -67.053689) (xy 286.888001 -67.038334)
			(xy 286.941949 -67.030578) (xy 286.996451 -67.030578) (xy 287.050399 -67.038334) (xy 287.102694 -67.053689)
			(xy 287.152271 -67.076331) (xy 287.198121 -67.105797) (xy 287.239312 -67.141488) (xy 287.275003 -67.182679)
			(xy 287.304469 -67.228529) (xy 287.327111 -67.278106) (xy 287.342466 -67.330401) (xy 287.350222 -67.384349)
			(xy 287.350708 -67.4116) (xy 287.350637 -67.422674) (xy 287.349365 -67.444786) (xy 287.348168 -67.455796)
			(xy 287.347035 -67.469116) (xy 287.350956 -67.49555) (xy 287.36161 -67.520058) (xy 287.378265 -67.540957)
			(xy 287.399777 -67.556811) (xy 287.42467 -67.566533) (xy 287.451234 -67.569453) (xy 287.4645 -67.56781)
			(xy 287.478764 -67.565779) (xy 287.507497 -67.563615) (xy 287.521904 -67.563492) (xy 287.549155 -67.563982)
			(xy 287.603102 -67.571739) (xy 287.655396 -67.587094) (xy 287.704972 -67.609736) (xy 287.750822 -67.639202)
			(xy 287.792011 -67.674894) (xy 287.827702 -67.716084) (xy 287.857167 -67.761934) (xy 287.879808 -67.81151)
			(xy 287.881713 -67.818) (xy 290.727382 -67.818) (xy 290.731453 -67.762378) (xy 290.743579 -67.707941)
			(xy 290.763502 -67.65585) (xy 290.790798 -67.607215) (xy 290.824884 -67.563072) (xy 290.865033 -67.524363)
			(xy 290.910391 -67.491912) (xy 290.959991 -67.466411) (xy 291.012775 -67.448404) (xy 291.067618 -67.438274)
			(xy 291.123352 -67.436237) (xy 291.178789 -67.442337) (xy 291.232746 -67.456443) (xy 291.284075 -67.478255)
			(xy 291.331681 -67.507309) (xy 291.374549 -67.542984) (xy 291.411766 -67.584521) (xy 291.442539 -67.631034)
			(xy 291.466211 -67.681531) (xy 291.482279 -67.734938) (xy 291.490399 -67.790114) (xy 291.490908 -67.818)
			(xy 293.648382 -67.818) (xy 293.652453 -67.762378) (xy 293.664579 -67.707941) (xy 293.684502 -67.65585)
			(xy 293.711798 -67.607215) (xy 293.745884 -67.563072) (xy 293.786033 -67.524363) (xy 293.831391 -67.491912)
			(xy 293.880991 -67.466411) (xy 293.933775 -67.448404) (xy 293.988618 -67.438274) (xy 294.044352 -67.436237)
			(xy 294.099789 -67.442337) (xy 294.153746 -67.456443) (xy 294.205075 -67.478255) (xy 294.252681 -67.507309)
			(xy 294.295549 -67.542984) (xy 294.332766 -67.584521) (xy 294.363539 -67.631034) (xy 294.387211 -67.681531)
			(xy 294.403279 -67.734938) (xy 294.411399 -67.790114) (xy 294.411908 -67.818) (xy 294.411399 -67.845886)
			(xy 294.403279 -67.901062) (xy 294.387211 -67.954469) (xy 294.363539 -68.004966) (xy 294.332766 -68.051479)
			(xy 294.295549 -68.093016) (xy 294.252681 -68.128691) (xy 294.205075 -68.157745) (xy 294.153746 -68.179557)
			(xy 294.099789 -68.193663) (xy 294.044352 -68.199763) (xy 293.988618 -68.197726) (xy 293.933775 -68.187596)
			(xy 293.880991 -68.169589) (xy 293.831391 -68.144088) (xy 293.786033 -68.111637) (xy 293.745884 -68.072928)
			(xy 293.711798 -68.028785) (xy 293.684502 -67.98015) (xy 293.664579 -67.928059) (xy 293.652453 -67.873622)
			(xy 293.648382 -67.818) (xy 291.490908 -67.818) (xy 291.490399 -67.845886) (xy 291.482279 -67.901062)
			(xy 291.466211 -67.954469) (xy 291.442539 -68.004966) (xy 291.411766 -68.051479) (xy 291.374549 -68.093016)
			(xy 291.331681 -68.128691) (xy 291.284075 -68.157745) (xy 291.232746 -68.179557) (xy 291.178789 -68.193663)
			(xy 291.123352 -68.199763) (xy 291.067618 -68.197726) (xy 291.012775 -68.187596) (xy 290.959991 -68.169589)
			(xy 290.910391 -68.144088) (xy 290.865033 -68.111637) (xy 290.824884 -68.072928) (xy 290.790798 -68.028785)
			(xy 290.763502 -67.98015) (xy 290.743579 -67.928059) (xy 290.731453 -67.873622) (xy 290.727382 -67.818)
			(xy 287.881713 -67.818) (xy 287.895162 -67.863805) (xy 287.902918 -67.917752) (xy 287.902918 -67.972254)
			(xy 287.895161 -68.026201) (xy 287.879806 -68.078495) (xy 287.857165 -68.128071) (xy 287.827699 -68.173921)
			(xy 287.792007 -68.21511) (xy 287.750817 -68.250801) (xy 287.704967 -68.280267) (xy 287.655391 -68.302907)
			(xy 287.603097 -68.318262) (xy 287.54915 -68.326018) (xy 287.494648 -68.326018) (xy 287.440701 -68.318262)
			(xy 287.388407 -68.302906) (xy 287.33883 -68.280265) (xy 287.29298 -68.250799) (xy 287.251791 -68.215108)
			(xy 287.2161 -68.173919) (xy 287.186634 -68.128069) (xy 287.163993 -68.078492) (xy 287.148638 -68.026198)
			(xy 287.140882 -67.972251) (xy 287.140396 -67.945) (xy 287.140467 -67.933926) (xy 287.141739 -67.911814)
			(xy 287.142936 -67.900804) (xy 287.144064 -67.887484) (xy 287.140143 -67.86105) (xy 287.12949 -67.836543)
			(xy 287.112836 -67.815645) (xy 287.091324 -67.79979) (xy 287.066433 -67.790069) (xy 287.03987 -67.787148)
			(xy 287.026604 -67.78879) (xy 287.01234 -67.79082) (xy 286.983607 -67.792985) (xy 286.9692 -67.793108)
			(xy 286.941949 -67.792622) (xy 286.888001 -67.784866) (xy 286.835706 -67.769511) (xy 286.786129 -67.746869)
			(xy 286.740279 -67.717403) (xy 286.699088 -67.681712) (xy 286.663397 -67.640521) (xy 286.633931 -67.594671)
			(xy 286.611289 -67.545094) (xy 286.595934 -67.492799) (xy 286.588178 -67.438851) (xy 273.310008 -67.438851)
			(xy 273.300346 -67.442957) (xy 273.246389 -67.457063) (xy 273.190952 -67.463163) (xy 273.135218 -67.461126)
			(xy 273.080375 -67.450996) (xy 273.027591 -67.432989) (xy 272.977991 -67.407488) (xy 272.932633 -67.375037)
			(xy 272.892484 -67.336328) (xy 272.858398 -67.292185) (xy 272.831102 -67.24355) (xy 272.811179 -67.191459)
			(xy 272.799053 -67.137022) (xy 272.794982 -67.0814) (xy 271.297908 -67.0814) (xy 271.297399 -67.109286)
			(xy 271.289279 -67.164462) (xy 271.273211 -67.217869) (xy 271.249539 -67.268366) (xy 271.218766 -67.314879)
			(xy 271.181549 -67.356416) (xy 271.138681 -67.392091) (xy 271.091075 -67.421145) (xy 271.039746 -67.442957)
			(xy 270.985789 -67.457063) (xy 270.930352 -67.463163) (xy 270.874618 -67.461126) (xy 270.819775 -67.450996)
			(xy 270.766991 -67.432989) (xy 270.717391 -67.407488) (xy 270.672033 -67.375037) (xy 270.631884 -67.336328)
			(xy 270.597798 -67.292185) (xy 270.570502 -67.24355) (xy 270.550579 -67.191459) (xy 270.538453 -67.137022)
			(xy 270.534382 -67.0814) (xy 265.0236 -67.0814) (xy 265.0236 -68.199) (xy 267.232388 -68.199) (xy 267.236418 -68.114399)
			(xy 267.248471 -68.030564) (xy 267.268439 -67.948255) (xy 267.296141 -67.868216) (xy 267.331325 -67.791173)
			(xy 267.373674 -67.717823) (xy 267.422803 -67.648831) (xy 267.478268 -67.584821) (xy 267.539566 -67.526373)
			(xy 267.606142 -67.474017) (xy 267.677394 -67.428227) (xy 267.752675 -67.389416) (xy 267.831305 -67.357937)
			(xy 267.912572 -67.334076) (xy 267.995738 -67.318047) (xy 268.080052 -67.309996) (xy 268.1224 -67.309492)
			(xy 268.161197 -67.309924) (xy 268.238495 -67.316687) (xy 268.314909 -67.330161) (xy 268.389859 -67.350244)
			(xy 268.462772 -67.376783) (xy 268.533096 -67.409575) (xy 268.5669 -67.428618) (xy 268.574795 -67.432715)
			(xy 268.5923 -67.43579) (xy 268.609805 -67.432715) (xy 268.6177 -67.428618) (xy 268.651506 -67.40958)
			(xy 268.721835 -67.376803) (xy 268.79475 -67.350272) (xy 268.869698 -67.330189) (xy 268.946109 -67.316707)
			(xy 269.023404 -67.309927) (xy 269.0622 -67.309492) (xy 269.104548 -67.309996) (xy 269.188862 -67.318047)
			(xy 269.272028 -67.334076) (xy 269.353295 -67.357937) (xy 269.431925 -67.389416) (xy 269.507206 -67.428227)
			(xy 269.578458 -67.474017) (xy 269.645034 -67.526373) (xy 269.706332 -67.584821) (xy 269.761797 -67.648831)
			(xy 269.810926 -67.717823) (xy 269.853275 -67.791173) (xy 269.888459 -67.868216) (xy 269.916161 -67.948255)
			(xy 269.936129 -68.030564) (xy 269.948182 -68.114399) (xy 269.952213 -68.199) (xy 269.948182 -68.283601)
			(xy 269.936129 -68.367436) (xy 269.916161 -68.449745) (xy 269.888459 -68.529784) (xy 269.853275 -68.606827)
			(xy 269.810926 -68.680177) (xy 269.761797 -68.749169) (xy 269.706332 -68.813179) (xy 269.645034 -68.871627)
			(xy 269.578458 -68.923983) (xy 269.507206 -68.969773) (xy 269.431925 -69.008584) (xy 269.353295 -69.040063)
			(xy 269.272028 -69.063924) (xy 269.188862 -69.079953) (xy 269.104548 -69.088004) (xy 269.0622 -69.088508)
			(xy 269.023403 -69.088076) (xy 268.946105 -69.081313) (xy 268.869691 -69.067839) (xy 268.794741 -69.047756)
			(xy 268.721828 -69.021217) (xy 268.651504 -68.988425) (xy 268.6177 -68.969382) (xy 268.609805 -68.965285)
			(xy 268.5923 -68.96221) (xy 268.574795 -68.965285) (xy 268.5669 -68.969382) (xy 268.533094 -68.98842)
			(xy 268.462765 -69.021197) (xy 268.38985 -69.047728) (xy 268.314902 -69.067811) (xy 268.238491 -69.081293)
			(xy 268.161196 -69.088073) (xy 268.1224 -69.088508) (xy 268.080052 -69.088004) (xy 267.995738 -69.079953)
			(xy 267.912572 -69.063924) (xy 267.831305 -69.040063) (xy 267.752675 -69.008584) (xy 267.677394 -68.969773)
			(xy 267.606142 -68.923983) (xy 267.539566 -68.871627) (xy 267.478268 -68.813179) (xy 267.422803 -68.749169)
			(xy 267.373674 -68.680177) (xy 267.331325 -68.606827) (xy 267.296141 -68.529784) (xy 267.268439 -68.449745)
			(xy 267.248471 -68.367436) (xy 267.236418 -68.283601) (xy 267.232388 -68.199) (xy 265.0236 -68.199)
			(xy 265.0236 -68.381118) (xy 265.024027 -68.391187) (xy 265.031746 -68.409786) (xy 265.038586 -68.417186)
			(xy 265.103102 -68.481702) (xy 265.107614 -68.485995) (xy 265.11828 -68.492417) (xy 265.124184 -68.494402)
			(xy 265.124438 -68.494402) (xy 265.165609 -68.507143) (xy 265.245482 -68.539526) (xy 265.32185 -68.57948)
			(xy 265.393997 -68.626631) (xy 265.461248 -68.680537) (xy 265.522971 -68.740693) (xy 265.551158 -68.773294)
			(xy 265.558016 -68.781422) (xy 265.585702 -68.795138) (xy 265.590982 -68.797509) (xy 265.602268 -68.800065)
			(xy 265.608054 -68.800218) (xy 266.43457 -68.800218) (xy 266.444634 -68.800654) (xy 266.463218 -68.808389)
			(xy 266.470638 -68.815204) (xy 267.23594 -69.580506) (xy 267.242792 -69.587902) (xy 267.246163 -69.596)
			(xy 270.559782 -69.596) (xy 270.563853 -69.540378) (xy 270.575979 -69.485941) (xy 270.595902 -69.43385)
			(xy 270.623198 -69.385215) (xy 270.657284 -69.341072) (xy 270.697433 -69.302363) (xy 270.742791 -69.269912)
			(xy 270.792391 -69.244411) (xy 270.845175 -69.226404) (xy 270.900018 -69.216274) (xy 270.955752 -69.214237)
			(xy 271.011189 -69.220337) (xy 271.065146 -69.234443) (xy 271.116475 -69.256255) (xy 271.164081 -69.285309)
			(xy 271.206949 -69.320984) (xy 271.244166 -69.362521) (xy 271.274939 -69.409034) (xy 271.298611 -69.459531)
			(xy 271.314679 -69.512938) (xy 271.322799 -69.568114) (xy 271.323308 -69.596) (xy 272.794982 -69.596)
			(xy 272.799053 -69.540378) (xy 272.811179 -69.485941) (xy 272.831102 -69.43385) (xy 272.858398 -69.385215)
			(xy 272.892484 -69.341072) (xy 272.932633 -69.302363) (xy 272.977991 -69.269912) (xy 273.027591 -69.244411)
			(xy 273.080375 -69.226404) (xy 273.135218 -69.216274) (xy 273.190952 -69.214237) (xy 273.246389 -69.220337)
			(xy 273.300346 -69.234443) (xy 273.351675 -69.256255) (xy 273.399281 -69.285309) (xy 273.440789 -69.319852)
			(xy 274.726334 -69.319852) (xy 274.734091 -69.265898) (xy 274.749447 -69.213596) (xy 274.772091 -69.164012)
			(xy 274.80156 -69.118156) (xy 274.837256 -69.07696) (xy 274.878451 -69.041264) (xy 274.924307 -69.011794)
			(xy 274.97389 -68.98915) (xy 275.026191 -68.973792) (xy 275.080145 -68.966035) (xy 275.1074 -68.965572)
			(xy 275.138309 -68.966154) (xy 275.19932 -68.976112) (xy 275.228812 -68.985384) (xy 275.242628 -68.989524)
			(xy 275.271434 -68.990713) (xy 275.299424 -68.983803) (xy 275.324368 -68.969347) (xy 275.344278 -68.948496)
			(xy 275.357567 -68.922911) (xy 275.363177 -68.894632) (xy 275.362416 -68.880228) (xy 275.360892 -68.8467)
			(xy 275.361378 -68.819449) (xy 275.369134 -68.765501) (xy 275.384489 -68.713206) (xy 275.407131 -68.663629)
			(xy 275.436597 -68.617779) (xy 275.472288 -68.576588) (xy 275.513479 -68.540897) (xy 275.559329 -68.511431)
			(xy 275.608906 -68.488789) (xy 275.661201 -68.473434) (xy 275.715149 -68.465678) (xy 275.769651 -68.465678)
			(xy 275.823599 -68.473434) (xy 275.875894 -68.488789) (xy 275.925471 -68.511431) (xy 275.971321 -68.540897)
			(xy 276.012512 -68.576588) (xy 276.048203 -68.617779) (xy 276.077669 -68.663629) (xy 276.100311 -68.713206)
			(xy 276.115666 -68.765501) (xy 276.123422 -68.819449) (xy 276.123422 -68.873951) (xy 276.115666 -68.927899)
			(xy 276.105947 -68.961) (xy 279.398982 -68.961) (xy 279.403053 -68.905378) (xy 279.415179 -68.850941)
			(xy 279.435102 -68.79885) (xy 279.462398 -68.750215) (xy 279.496484 -68.706072) (xy 279.536633 -68.667363)
			(xy 279.581991 -68.634912) (xy 279.631591 -68.609411) (xy 279.684375 -68.591404) (xy 279.739218 -68.581274)
			(xy 279.794952 -68.579237) (xy 279.850389 -68.585337) (xy 279.904346 -68.599443) (xy 279.955675 -68.621255)
			(xy 280.003281 -68.650309) (xy 280.046149 -68.685984) (xy 280.083366 -68.727521) (xy 280.114139 -68.774034)
			(xy 280.137811 -68.824531) (xy 280.153879 -68.877938) (xy 280.161999 -68.933114) (xy 280.16216 -68.94195)
			(xy 285.266382 -68.94195) (xy 285.270453 -68.886328) (xy 285.282579 -68.831891) (xy 285.302502 -68.7798)
			(xy 285.329798 -68.731165) (xy 285.363884 -68.687022) (xy 285.404033 -68.648313) (xy 285.449391 -68.615862)
			(xy 285.498991 -68.590361) (xy 285.551775 -68.572354) (xy 285.606618 -68.562224) (xy 285.662352 -68.560187)
			(xy 285.717789 -68.566287) (xy 285.771746 -68.580393) (xy 285.823075 -68.602205) (xy 285.870681 -68.631259)
			(xy 285.913549 -68.666934) (xy 285.950766 -68.708471) (xy 285.981539 -68.754984) (xy 286.005211 -68.805481)
			(xy 286.021279 -68.858888) (xy 286.029399 -68.914064) (xy 286.029908 -68.94195) (xy 286.029399 -68.969836)
			(xy 286.021279 -69.025012) (xy 286.005211 -69.078419) (xy 285.981539 -69.128916) (xy 285.950766 -69.175429)
			(xy 285.913549 -69.216966) (xy 285.870681 -69.252641) (xy 285.823075 -69.281695) (xy 285.771746 -69.303507)
			(xy 285.717789 -69.317613) (xy 285.662352 -69.323713) (xy 285.606618 -69.321676) (xy 285.551775 -69.311546)
			(xy 285.498991 -69.293539) (xy 285.449391 -69.268038) (xy 285.404033 -69.235587) (xy 285.363884 -69.196878)
			(xy 285.329798 -69.152735) (xy 285.302502 -69.1041) (xy 285.282579 -69.052009) (xy 285.270453 -68.997572)
			(xy 285.266382 -68.94195) (xy 280.16216 -68.94195) (xy 280.162508 -68.961) (xy 280.161999 -68.988886)
			(xy 280.153879 -69.044062) (xy 280.137811 -69.097469) (xy 280.114139 -69.147966) (xy 280.083366 -69.194479)
			(xy 280.046149 -69.236016) (xy 280.003281 -69.271691) (xy 279.955675 -69.300745) (xy 279.904346 -69.322557)
			(xy 279.850389 -69.336663) (xy 279.794952 -69.342763) (xy 279.739218 -69.340726) (xy 279.684375 -69.330596)
			(xy 279.631591 -69.312589) (xy 279.581991 -69.287088) (xy 279.536633 -69.254637) (xy 279.496484 -69.215928)
			(xy 279.462398 -69.171785) (xy 279.435102 -69.12315) (xy 279.415179 -69.071059) (xy 279.403053 -69.016622)
			(xy 279.398982 -68.961) (xy 276.105947 -68.961) (xy 276.100311 -68.980194) (xy 276.077669 -69.029771)
			(xy 276.048203 -69.075621) (xy 276.012512 -69.116812) (xy 275.971321 -69.152503) (xy 275.925471 -69.181969)
			(xy 275.875894 -69.204611) (xy 275.823599 -69.219966) (xy 275.769651 -69.227722) (xy 275.7424 -69.228208)
			(xy 275.711491 -69.227622) (xy 275.65048 -69.217666) (xy 275.620988 -69.208396) (xy 275.607167 -69.204277)
			(xy 275.578365 -69.203089) (xy 275.550379 -69.209997) (xy 275.525438 -69.22445) (xy 275.505529 -69.245297)
			(xy 275.492239 -69.270876) (xy 275.486626 -69.29915) (xy 275.487384 -69.313552) (xy 275.488908 -69.34708)
			(xy 275.488467 -69.374335) (xy 275.480712 -69.428289) (xy 275.465357 -69.480591) (xy 275.442716 -69.530176)
			(xy 275.413248 -69.576033) (xy 275.377554 -69.61723) (xy 275.33636 -69.652928) (xy 275.290505 -69.6824)
			(xy 275.240923 -69.705046) (xy 275.188622 -69.720405) (xy 275.134668 -69.728164) (xy 275.080159 -69.728166)
			(xy 275.026204 -69.72041) (xy 274.973902 -69.705055) (xy 274.924318 -69.682413) (xy 274.878461 -69.652944)
			(xy 274.837265 -69.617249) (xy 274.801568 -69.576055) (xy 274.772097 -69.530199) (xy 274.749452 -69.480616)
			(xy 274.734094 -69.428316) (xy 274.726335 -69.374361) (xy 274.726334 -69.319852) (xy 273.440789 -69.319852)
			(xy 273.442149 -69.320984) (xy 273.479366 -69.362521) (xy 273.510139 -69.409034) (xy 273.533811 -69.459531)
			(xy 273.549879 -69.512938) (xy 273.557999 -69.568114) (xy 273.558508 -69.596) (xy 273.557999 -69.623886)
			(xy 273.549879 -69.679062) (xy 273.533811 -69.732469) (xy 273.510139 -69.782966) (xy 273.479366 -69.829479)
			(xy 273.465531 -69.84492) (xy 275.990048 -69.84492) (xy 275.994119 -69.789298) (xy 276.006245 -69.734861)
			(xy 276.026168 -69.68277) (xy 276.053464 -69.634135) (xy 276.08755 -69.589992) (xy 276.127699 -69.551283)
			(xy 276.173057 -69.518832) (xy 276.222657 -69.493331) (xy 276.275441 -69.475324) (xy 276.330284 -69.465194)
			(xy 276.386018 -69.463157) (xy 276.441455 -69.469257) (xy 276.495412 -69.483363) (xy 276.546741 -69.505175)
			(xy 276.594347 -69.534229) (xy 276.637215 -69.569904) (xy 276.674432 -69.611441) (xy 276.705205 -69.657954)
			(xy 276.728877 -69.708451) (xy 276.733254 -69.723) (xy 287.174684 -69.723) (xy 287.178755 -69.667378)
			(xy 287.190881 -69.612941) (xy 287.210804 -69.56085) (xy 287.2381 -69.512215) (xy 287.272186 -69.468072)
			(xy 287.312335 -69.429363) (xy 287.357693 -69.396912) (xy 287.407293 -69.371411) (xy 287.460077 -69.353404)
			(xy 287.51492 -69.343274) (xy 287.570654 -69.341237) (xy 287.626091 -69.347337) (xy 287.680048 -69.361443)
			(xy 287.731377 -69.383255) (xy 287.778983 -69.412309) (xy 287.821851 -69.447984) (xy 287.859068 -69.489521)
			(xy 287.889841 -69.536034) (xy 287.913513 -69.586531) (xy 287.929581 -69.639938) (xy 287.937701 -69.695114)
			(xy 287.93821 -69.723) (xy 287.937701 -69.750886) (xy 287.929581 -69.806062) (xy 287.913513 -69.859469)
			(xy 287.889841 -69.909966) (xy 287.859068 -69.956479) (xy 287.821851 -69.998016) (xy 287.778983 -70.033691)
			(xy 287.731377 -70.062745) (xy 287.680048 -70.084557) (xy 287.626091 -70.098663) (xy 287.577588 -70.104)
			(xy 290.727382 -70.104) (xy 290.731453 -70.048378) (xy 290.743579 -69.993941) (xy 290.763502 -69.94185)
			(xy 290.790798 -69.893215) (xy 290.824884 -69.849072) (xy 290.865033 -69.810363) (xy 290.910391 -69.777912)
			(xy 290.959991 -69.752411) (xy 291.012775 -69.734404) (xy 291.067618 -69.724274) (xy 291.123352 -69.722237)
			(xy 291.178789 -69.728337) (xy 291.232746 -69.742443) (xy 291.284075 -69.764255) (xy 291.331681 -69.793309)
			(xy 291.374549 -69.828984) (xy 291.411766 -69.870521) (xy 291.442539 -69.917034) (xy 291.466211 -69.967531)
			(xy 291.482279 -70.020938) (xy 291.490399 -70.076114) (xy 291.490908 -70.104) (xy 293.648382 -70.104)
			(xy 293.652453 -70.048378) (xy 293.664579 -69.993941) (xy 293.684502 -69.94185) (xy 293.711798 -69.893215)
			(xy 293.745884 -69.849072) (xy 293.786033 -69.810363) (xy 293.831391 -69.777912) (xy 293.880991 -69.752411)
			(xy 293.933775 -69.734404) (xy 293.988618 -69.724274) (xy 294.044352 -69.722237) (xy 294.099789 -69.728337)
			(xy 294.153746 -69.742443) (xy 294.205075 -69.764255) (xy 294.252681 -69.793309) (xy 294.295549 -69.828984)
			(xy 294.318021 -69.854064) (xy 296.794936 -69.854064) (xy 296.795426 -69.811638) (xy 296.803503 -69.727172)
			(xy 296.81959 -69.64386) (xy 296.843541 -69.562459) (xy 296.875137 -69.48371) (xy 296.914092 -69.408329)
			(xy 296.96005 -69.337002) (xy 297.012594 -69.270377) (xy 297.071246 -69.209061) (xy 297.103038 -69.180964)
			(xy 297.111674 -69.173598) (xy 297.120564 -69.153786) (xy 297.120564 -69.054218) (xy 297.111674 -69.034406)
			(xy 297.103038 -69.02704) (xy 297.071255 -68.998934) (xy 297.012608 -68.937615) (xy 296.960068 -68.870989)
			(xy 296.914112 -68.799662) (xy 296.875158 -68.724283) (xy 296.843561 -68.645536) (xy 296.819607 -68.564138)
			(xy 296.803515 -68.480828) (xy 296.79543 -68.396365) (xy 296.794936 -68.35394) (xy 296.79544 -68.311592)
			(xy 296.803491 -68.227278) (xy 296.81952 -68.144112) (xy 296.843381 -68.062845) (xy 296.87486 -67.984215)
			(xy 296.913671 -67.908934) (xy 296.959461 -67.837682) (xy 297.011817 -67.771106) (xy 297.070265 -67.709808)
			(xy 297.134275 -67.654343) (xy 297.203267 -67.605214) (xy 297.276617 -67.562865) (xy 297.35366 -67.527681)
			(xy 297.433699 -67.499979) (xy 297.516008 -67.480011) (xy 297.599843 -67.467958) (xy 297.684444 -67.463928)
			(xy 297.769045 -67.467958) (xy 297.85288 -67.480011) (xy 297.935189 -67.499979) (xy 298.015228 -67.527681)
			(xy 298.092271 -67.562865) (xy 298.165621 -67.605214) (xy 298.234613 -67.654343) (xy 298.298623 -67.709808)
			(xy 298.357071 -67.771106) (xy 298.409427 -67.837682) (xy 298.455217 -67.908934) (xy 298.494028 -67.984215)
			(xy 298.525507 -68.062845) (xy 298.549368 -68.144112) (xy 298.565397 -68.227278) (xy 298.573448 -68.311592)
			(xy 298.573952 -68.35394) (xy 298.573469 -68.396366) (xy 298.565391 -68.480832) (xy 298.549303 -68.564145)
			(xy 298.525352 -68.645546) (xy 298.493755 -68.724295) (xy 298.4548 -68.799676) (xy 298.408841 -68.871003)
			(xy 298.356295 -68.937627) (xy 298.297642 -68.998943) (xy 298.26585 -69.02704) (xy 298.257214 -69.034406)
			(xy 298.248324 -69.054218) (xy 298.248324 -69.153786) (xy 298.257214 -69.173598) (xy 298.26585 -69.180964)
			(xy 298.297633 -69.20907) (xy 298.35628 -69.270389) (xy 298.40882 -69.337015) (xy 298.454776 -69.408341)
			(xy 298.49373 -69.483721) (xy 298.525328 -69.562468) (xy 298.549281 -69.643866) (xy 298.565374 -69.727176)
			(xy 298.573458 -69.811639) (xy 298.573952 -69.854064) (xy 298.573448 -69.896412) (xy 298.565397 -69.980726)
			(xy 298.549368 -70.063892) (xy 298.525507 -70.145159) (xy 298.494028 -70.223789) (xy 298.455217 -70.29907)
			(xy 298.409427 -70.370322) (xy 298.357071 -70.436898) (xy 298.298623 -70.498196) (xy 298.234613 -70.553661)
			(xy 298.165621 -70.60279) (xy 298.092271 -70.645139) (xy 298.015228 -70.680323) (xy 297.935189 -70.708025)
			(xy 297.85288 -70.727993) (xy 297.769045 -70.740046) (xy 297.684444 -70.744077) (xy 297.599843 -70.740046)
			(xy 297.516008 -70.727993) (xy 297.433699 -70.708025) (xy 297.35366 -70.680323) (xy 297.276617 -70.645139)
			(xy 297.203267 -70.60279) (xy 297.134275 -70.553661) (xy 297.070265 -70.498196) (xy 297.011817 -70.436898)
			(xy 296.959461 -70.370322) (xy 296.913671 -70.29907) (xy 296.87486 -70.223789) (xy 296.843381 -70.145159)
			(xy 296.81952 -70.063892) (xy 296.803491 -69.980726) (xy 296.79544 -69.896412) (xy 296.794936 -69.854064)
			(xy 294.318021 -69.854064) (xy 294.332766 -69.870521) (xy 294.363539 -69.917034) (xy 294.387211 -69.967531)
			(xy 294.403279 -70.020938) (xy 294.411399 -70.076114) (xy 294.411908 -70.104) (xy 294.411399 -70.131886)
			(xy 294.403279 -70.187062) (xy 294.387211 -70.240469) (xy 294.363539 -70.290966) (xy 294.332766 -70.337479)
			(xy 294.295549 -70.379016) (xy 294.252681 -70.414691) (xy 294.205075 -70.443745) (xy 294.153746 -70.465557)
			(xy 294.099789 -70.479663) (xy 294.044352 -70.485763) (xy 293.988618 -70.483726) (xy 293.933775 -70.473596)
			(xy 293.880991 -70.455589) (xy 293.831391 -70.430088) (xy 293.786033 -70.397637) (xy 293.745884 -70.358928)
			(xy 293.711798 -70.314785) (xy 293.684502 -70.26615) (xy 293.664579 -70.214059) (xy 293.652453 -70.159622)
			(xy 293.648382 -70.104) (xy 291.490908 -70.104) (xy 291.490399 -70.131886) (xy 291.482279 -70.187062)
			(xy 291.466211 -70.240469) (xy 291.442539 -70.290966) (xy 291.411766 -70.337479) (xy 291.374549 -70.379016)
			(xy 291.331681 -70.414691) (xy 291.284075 -70.443745) (xy 291.232746 -70.465557) (xy 291.178789 -70.479663)
			(xy 291.123352 -70.485763) (xy 291.067618 -70.483726) (xy 291.012775 -70.473596) (xy 290.959991 -70.455589)
			(xy 290.910391 -70.430088) (xy 290.865033 -70.397637) (xy 290.824884 -70.358928) (xy 290.790798 -70.314785)
			(xy 290.763502 -70.26615) (xy 290.743579 -70.214059) (xy 290.731453 -70.159622) (xy 290.727382 -70.104)
			(xy 287.577588 -70.104) (xy 287.570654 -70.104763) (xy 287.51492 -70.102726) (xy 287.460077 -70.092596)
			(xy 287.407293 -70.074589) (xy 287.357693 -70.049088) (xy 287.312335 -70.016637) (xy 287.272186 -69.977928)
			(xy 287.2381 -69.933785) (xy 287.210804 -69.88515) (xy 287.190881 -69.833059) (xy 287.178755 -69.778622)
			(xy 287.174684 -69.723) (xy 276.733254 -69.723) (xy 276.744945 -69.761858) (xy 276.753065 -69.817034)
			(xy 276.753574 -69.84492) (xy 276.753065 -69.872806) (xy 276.744945 -69.927982) (xy 276.728877 -69.981389)
			(xy 276.705205 -70.031886) (xy 276.674432 -70.078399) (xy 276.637215 -70.119936) (xy 276.594347 -70.155611)
			(xy 276.546741 -70.184665) (xy 276.495412 -70.206477) (xy 276.441455 -70.220583) (xy 276.386018 -70.226683)
			(xy 276.330284 -70.224646) (xy 276.275441 -70.214516) (xy 276.222657 -70.196509) (xy 276.173057 -70.171008)
			(xy 276.127699 -70.138557) (xy 276.08755 -70.099848) (xy 276.053464 -70.055705) (xy 276.026168 -70.00707)
			(xy 276.006245 -69.954979) (xy 275.994119 -69.900542) (xy 275.990048 -69.84492) (xy 273.465531 -69.84492)
			(xy 273.442149 -69.871016) (xy 273.399281 -69.906691) (xy 273.351675 -69.935745) (xy 273.300346 -69.957557)
			(xy 273.246389 -69.971663) (xy 273.190952 -69.977763) (xy 273.135218 -69.975726) (xy 273.080375 -69.965596)
			(xy 273.027591 -69.947589) (xy 272.977991 -69.922088) (xy 272.932633 -69.889637) (xy 272.892484 -69.850928)
			(xy 272.858398 -69.806785) (xy 272.831102 -69.75815) (xy 272.811179 -69.706059) (xy 272.799053 -69.651622)
			(xy 272.794982 -69.596) (xy 271.323308 -69.596) (xy 271.322799 -69.623886) (xy 271.314679 -69.679062)
			(xy 271.298611 -69.732469) (xy 271.274939 -69.782966) (xy 271.244166 -69.829479) (xy 271.206949 -69.871016)
			(xy 271.164081 -69.906691) (xy 271.116475 -69.935745) (xy 271.065146 -69.957557) (xy 271.011189 -69.971663)
			(xy 270.955752 -69.977763) (xy 270.900018 -69.975726) (xy 270.845175 -69.965596) (xy 270.792391 -69.947589)
			(xy 270.742791 -69.922088) (xy 270.697433 -69.889637) (xy 270.657284 -69.850928) (xy 270.623198 -69.806785)
			(xy 270.595902 -69.75815) (xy 270.575979 -69.706059) (xy 270.563853 -69.651622) (xy 270.559782 -69.596)
			(xy 267.246163 -69.596) (xy 267.250534 -69.606501) (xy 267.250926 -69.616574) (xy 267.250926 -70.394322)
			(xy 267.251424 -70.404759) (xy 267.25975 -70.423898) (xy 267.275041 -70.438104) (xy 267.284708 -70.442074)
			(xy 267.390372 -70.479666) (xy 267.421106 -70.47103) (xy 267.431266 -70.45833) (xy 267.459378 -70.424504)
			(xy 267.521246 -70.361981) (xy 267.588981 -70.305866) (xy 267.661921 -70.256708) (xy 267.739355 -70.214986)
			(xy 267.820528 -70.181107) (xy 267.904647 -70.155401) (xy 267.990892 -70.13812) (xy 268.078421 -70.129433)
			(xy 268.1224 -70.128892) (xy 268.161174 -70.129339) (xy 268.238424 -70.136137) (xy 268.314789 -70.149631)
			(xy 268.389691 -70.169717) (xy 268.462562 -70.196243) (xy 268.532849 -70.229008) (xy 268.566646 -70.248018)
			(xy 268.5669 -70.248018) (xy 268.567408 -70.248272) (xy 268.57516 -70.252231) (xy 268.5923 -70.255191)
			(xy 268.60944 -70.252231) (xy 268.617192 -70.248272) (xy 268.6177 -70.248018) (xy 268.617954 -70.248018)
			(xy 268.651745 -70.228994) (xy 268.722026 -70.196213) (xy 268.794897 -70.169678) (xy 268.869801 -70.149591)
			(xy 268.946171 -70.136106) (xy 269.023425 -70.129325) (xy 269.0622 -70.128892) (xy 269.104548 -70.129396)
			(xy 269.188862 -70.137447) (xy 269.272028 -70.153476) (xy 269.353295 -70.177337) (xy 269.431925 -70.208816)
			(xy 269.507206 -70.247627) (xy 269.578458 -70.293417) (xy 269.645034 -70.345773) (xy 269.706332 -70.404221)
			(xy 269.761797 -70.468231) (xy 269.810926 -70.537223) (xy 269.853275 -70.610573) (xy 269.888459 -70.687616)
			(xy 269.916161 -70.767655) (xy 269.934912 -70.844948) (xy 274.726418 -70.844948) (xy 274.726418 -70.790452)
			(xy 274.734174 -70.73651) (xy 274.749527 -70.68422) (xy 274.772166 -70.634648) (xy 274.801629 -70.588803)
			(xy 274.837317 -70.547617) (xy 274.878503 -70.511929) (xy 274.924348 -70.482466) (xy 274.97392 -70.459827)
			(xy 275.02621 -70.444474) (xy 275.080152 -70.436718) (xy 275.1074 -70.436232) (xy 275.133832 -70.436671)
			(xy 275.186189 -70.443971) (xy 275.237037 -70.458429) (xy 275.285402 -70.47977) (xy 275.330357 -70.507584)
			(xy 275.350986 -70.524116) (xy 275.361935 -70.53272) (xy 275.387366 -70.544047) (xy 275.414912 -70.548083)
			(xy 275.442523 -70.544527) (xy 275.468148 -70.533644) (xy 275.489879 -70.516243) (xy 275.506101 -70.493618)
			(xy 275.51126 -70.480682) (xy 275.521794 -70.453563) (xy 275.549871 -70.402612) (xy 275.585359 -70.356516)
			(xy 275.627436 -70.316343) (xy 275.675125 -70.283027) (xy 275.727321 -70.257338) (xy 275.782813 -70.239875)
			(xy 275.840313 -70.23104) (xy 275.8694 -70.230492) (xy 275.896651 -70.230978) (xy 275.950599 -70.238734)
			(xy 276.002894 -70.254089) (xy 276.052471 -70.276731) (xy 276.098321 -70.306197) (xy 276.139512 -70.341888)
			(xy 276.175203 -70.383079) (xy 276.204669 -70.428929) (xy 276.227311 -70.478506) (xy 276.242666 -70.530801)
			(xy 276.250422 -70.584749) (xy 276.250422 -70.639251) (xy 276.242666 -70.693199) (xy 276.227311 -70.745494)
			(xy 276.204669 -70.795071) (xy 276.175203 -70.840921) (xy 276.163817 -70.854062) (xy 288.161982 -70.854062)
			(xy 288.166053 -70.79844) (xy 288.178179 -70.744003) (xy 288.198102 -70.691912) (xy 288.225398 -70.643277)
			(xy 288.259484 -70.599134) (xy 288.299633 -70.560425) (xy 288.344991 -70.527974) (xy 288.394591 -70.502473)
			(xy 288.447375 -70.484466) (xy 288.502218 -70.474336) (xy 288.557952 -70.472299) (xy 288.613389 -70.478399)
			(xy 288.667346 -70.492505) (xy 288.718675 -70.514317) (xy 288.766281 -70.543371) (xy 288.809149 -70.579046)
			(xy 288.846366 -70.620583) (xy 288.877139 -70.667096) (xy 288.900811 -70.717593) (xy 288.916879 -70.771)
			(xy 288.924999 -70.826176) (xy 288.925508 -70.854062) (xy 288.924999 -70.881948) (xy 288.916879 -70.937124)
			(xy 288.900811 -70.990531) (xy 288.877139 -71.041028) (xy 288.846366 -71.087541) (xy 288.809149 -71.129078)
			(xy 288.766281 -71.164753) (xy 288.718675 -71.193807) (xy 288.667346 -71.215619) (xy 288.613389 -71.229725)
			(xy 288.557952 -71.235825) (xy 288.502218 -71.233788) (xy 288.447375 -71.223658) (xy 288.394591 -71.205651)
			(xy 288.344991 -71.18015) (xy 288.299633 -71.147699) (xy 288.259484 -71.10899) (xy 288.225398 -71.064847)
			(xy 288.198102 -71.016212) (xy 288.178179 -70.964121) (xy 288.166053 -70.909684) (xy 288.161982 -70.854062)
			(xy 276.163817 -70.854062) (xy 276.139512 -70.882112) (xy 276.098321 -70.917803) (xy 276.052471 -70.947269)
			(xy 276.002894 -70.969911) (xy 275.950599 -70.985266) (xy 275.896651 -70.993022) (xy 275.8694 -70.993508)
			(xy 275.842969 -70.99306) (xy 275.790612 -70.985761) (xy 275.739764 -70.971304) (xy 275.691399 -70.949966)
			(xy 275.646444 -70.922154) (xy 275.625814 -70.905624) (xy 275.614849 -70.897046) (xy 275.589423 -70.885728)
			(xy 275.561884 -70.881696) (xy 275.53428 -70.88525) (xy 275.508661 -70.896126) (xy 275.486931 -70.913516)
			(xy 275.470704 -70.936128) (xy 275.46554 -70.949058) (xy 275.454973 -70.976164) (xy 275.426904 -71.027116)
			(xy 275.391422 -71.073215) (xy 275.349351 -71.11339) (xy 275.301665 -71.146709) (xy 275.249473 -71.172399)
			(xy 275.193984 -71.189865) (xy 275.136486 -71.1987) (xy 275.1074 -71.199248) (xy 275.080152 -71.198682)
			(xy 275.02621 -71.190926) (xy 274.97392 -71.175573) (xy 274.924348 -71.152934) (xy 274.878503 -71.123471)
			(xy 274.837317 -71.087783) (xy 274.801629 -71.046597) (xy 274.772166 -71.000752) (xy 274.749527 -70.95118)
			(xy 274.734174 -70.89889) (xy 274.726418 -70.844948) (xy 269.934912 -70.844948) (xy 269.936129 -70.849964)
			(xy 269.948182 -70.933799) (xy 269.952213 -71.0184) (xy 269.948182 -71.103001) (xy 269.936129 -71.186836)
			(xy 269.916161 -71.269145) (xy 269.888459 -71.349184) (xy 269.853275 -71.426227) (xy 269.810926 -71.499577)
			(xy 269.761797 -71.568569) (xy 269.706332 -71.632579) (xy 269.645034 -71.691027) (xy 269.578458 -71.743383)
			(xy 269.507206 -71.789173) (xy 269.431925 -71.827984) (xy 269.353295 -71.859463) (xy 269.272028 -71.883324)
			(xy 269.188862 -71.899353) (xy 269.104548 -71.907404) (xy 269.0622 -71.907908) (xy 269.023426 -71.907461)
			(xy 268.946176 -71.900663) (xy 268.869811 -71.887169) (xy 268.794909 -71.867083) (xy 268.722038 -71.840557)
			(xy 268.651751 -71.807792) (xy 268.617954 -71.788782) (xy 268.6177 -71.788782) (xy 268.617192 -71.788528)
			(xy 268.60944 -71.784569) (xy 268.5923 -71.781609) (xy 268.57516 -71.784569) (xy 268.567408 -71.788528)
			(xy 268.5669 -71.788782) (xy 268.566646 -71.788782) (xy 268.532855 -71.807806) (xy 268.462574 -71.840587)
			(xy 268.389703 -71.867122) (xy 268.314799 -71.887209) (xy 268.238429 -71.900694) (xy 268.161175 -71.907475)
			(xy 268.1224 -71.907908) (xy 268.078572 -71.907382) (xy 267.991341 -71.898757) (xy 267.905382 -71.881593)
			(xy 267.821528 -71.856054) (xy 267.740594 -71.82239) (xy 267.663365 -71.780925) (xy 267.59059 -71.732064)
			(xy 267.522975 -71.67628) (xy 267.461177 -71.614114) (xy 267.433044 -71.580502) (xy 267.43152 -71.578724)
			(xy 267.424557 -71.570735) (xy 267.405859 -71.560816) (xy 267.384744 -71.559332) (xy 267.374624 -71.562468)
			(xy 267.284708 -71.594726) (xy 267.269468 -71.60006) (xy 267.250926 -71.626222) (xy 267.250926 -72.1106)
			(xy 270.559782 -72.1106) (xy 270.563853 -72.054978) (xy 270.575979 -72.000541) (xy 270.595902 -71.94845)
			(xy 270.623198 -71.899815) (xy 270.657284 -71.855672) (xy 270.697433 -71.816963) (xy 270.742791 -71.784512)
			(xy 270.792391 -71.759011) (xy 270.845175 -71.741004) (xy 270.900018 -71.730874) (xy 270.955752 -71.728837)
			(xy 271.011189 -71.734937) (xy 271.065146 -71.749043) (xy 271.116475 -71.770855) (xy 271.164081 -71.799909)
			(xy 271.206949 -71.835584) (xy 271.244166 -71.877121) (xy 271.274939 -71.923634) (xy 271.298611 -71.974131)
			(xy 271.314679 -72.027538) (xy 271.322799 -72.082714) (xy 271.323308 -72.1106) (xy 272.794982 -72.1106)
			(xy 272.799053 -72.054978) (xy 272.811179 -72.000541) (xy 272.831102 -71.94845) (xy 272.858398 -71.899815)
			(xy 272.892484 -71.855672) (xy 272.932633 -71.816963) (xy 272.977991 -71.784512) (xy 273.027591 -71.759011)
			(xy 273.080375 -71.741004) (xy 273.135218 -71.730874) (xy 273.190952 -71.728837) (xy 273.246389 -71.734937)
			(xy 273.300346 -71.749043) (xy 273.314364 -71.755) (xy 275.741382 -71.755) (xy 275.745453 -71.699378)
			(xy 275.757579 -71.644941) (xy 275.777502 -71.59285) (xy 275.804798 -71.544215) (xy 275.838884 -71.500072)
			(xy 275.879033 -71.461363) (xy 275.924391 -71.428912) (xy 275.973991 -71.403411) (xy 276.026775 -71.385404)
			(xy 276.081618 -71.375274) (xy 276.137352 -71.373237) (xy 276.192789 -71.379337) (xy 276.246746 -71.393443)
			(xy 276.298075 -71.415255) (xy 276.345681 -71.444309) (xy 276.388549 -71.479984) (xy 276.425766 -71.521521)
			(xy 276.456539 -71.568034) (xy 276.480211 -71.618531) (xy 276.496279 -71.671938) (xy 276.504399 -71.727114)
			(xy 276.504908 -71.755) (xy 276.504399 -71.782886) (xy 276.496279 -71.838062) (xy 276.48306 -71.882)
			(xy 284.504382 -71.882) (xy 284.508453 -71.826378) (xy 284.520579 -71.771941) (xy 284.540502 -71.71985)
			(xy 284.567798 -71.671215) (xy 284.601884 -71.627072) (xy 284.642033 -71.588363) (xy 284.687391 -71.555912)
			(xy 284.736991 -71.530411) (xy 284.789775 -71.512404) (xy 284.844618 -71.502274) (xy 284.900352 -71.500237)
			(xy 284.955789 -71.506337) (xy 285.009746 -71.520443) (xy 285.061075 -71.542255) (xy 285.108681 -71.571309)
			(xy 285.151549 -71.606984) (xy 285.188766 -71.648521) (xy 285.219539 -71.695034) (xy 285.243211 -71.745531)
			(xy 285.259279 -71.798938) (xy 285.267399 -71.854114) (xy 285.267908 -71.882) (xy 285.267399 -71.909886)
			(xy 285.259279 -71.965062) (xy 285.243211 -72.018469) (xy 285.219539 -72.068966) (xy 285.188766 -72.115479)
			(xy 285.151549 -72.157016) (xy 285.108681 -72.192691) (xy 285.061075 -72.221745) (xy 285.009746 -72.243557)
			(xy 284.955789 -72.257663) (xy 284.900352 -72.263763) (xy 284.844618 -72.261726) (xy 284.789775 -72.251596)
			(xy 284.736991 -72.233589) (xy 284.687391 -72.208088) (xy 284.642033 -72.175637) (xy 284.601884 -72.136928)
			(xy 284.567798 -72.092785) (xy 284.540502 -72.04415) (xy 284.520579 -71.992059) (xy 284.508453 -71.937622)
			(xy 284.504382 -71.882) (xy 276.48306 -71.882) (xy 276.480211 -71.891469) (xy 276.456539 -71.941966)
			(xy 276.425766 -71.988479) (xy 276.388549 -72.030016) (xy 276.345681 -72.065691) (xy 276.298075 -72.094745)
			(xy 276.246746 -72.116557) (xy 276.192789 -72.130663) (xy 276.137352 -72.136763) (xy 276.081618 -72.134726)
			(xy 276.026775 -72.124596) (xy 275.973991 -72.106589) (xy 275.924391 -72.081088) (xy 275.879033 -72.048637)
			(xy 275.838884 -72.009928) (xy 275.804798 -71.965785) (xy 275.777502 -71.91715) (xy 275.757579 -71.865059)
			(xy 275.745453 -71.810622) (xy 275.741382 -71.755) (xy 273.314364 -71.755) (xy 273.351675 -71.770855)
			(xy 273.399281 -71.799909) (xy 273.442149 -71.835584) (xy 273.479366 -71.877121) (xy 273.510139 -71.923634)
			(xy 273.533811 -71.974131) (xy 273.549879 -72.027538) (xy 273.557999 -72.082714) (xy 273.558508 -72.1106)
			(xy 273.557999 -72.138486) (xy 273.549879 -72.193662) (xy 273.533811 -72.247069) (xy 273.510139 -72.297566)
			(xy 273.479366 -72.344079) (xy 273.442149 -72.385616) (xy 273.436881 -72.39) (xy 281.837382 -72.39)
			(xy 281.841453 -72.334378) (xy 281.853579 -72.279941) (xy 281.873502 -72.22785) (xy 281.900798 -72.179215)
			(xy 281.934884 -72.135072) (xy 281.975033 -72.096363) (xy 282.020391 -72.063912) (xy 282.069991 -72.038411)
			(xy 282.122775 -72.020404) (xy 282.177618 -72.010274) (xy 282.233352 -72.008237) (xy 282.288789 -72.014337)
			(xy 282.342746 -72.028443) (xy 282.394075 -72.050255) (xy 282.441681 -72.079309) (xy 282.484549 -72.114984)
			(xy 282.521766 -72.156521) (xy 282.552539 -72.203034) (xy 282.576211 -72.253531) (xy 282.592279 -72.306938)
			(xy 282.600399 -72.362114) (xy 282.600908 -72.39) (xy 290.727382 -72.39) (xy 290.731453 -72.334378)
			(xy 290.743579 -72.279941) (xy 290.763502 -72.22785) (xy 290.790798 -72.179215) (xy 290.824884 -72.135072)
			(xy 290.865033 -72.096363) (xy 290.910391 -72.063912) (xy 290.959991 -72.038411) (xy 291.012775 -72.020404)
			(xy 291.067618 -72.010274) (xy 291.123352 -72.008237) (xy 291.178789 -72.014337) (xy 291.232746 -72.028443)
			(xy 291.284075 -72.050255) (xy 291.331681 -72.079309) (xy 291.374549 -72.114984) (xy 291.411766 -72.156521)
			(xy 291.442539 -72.203034) (xy 291.466211 -72.253531) (xy 291.482279 -72.306938) (xy 291.490399 -72.362114)
			(xy 291.490908 -72.39) (xy 293.648382 -72.39) (xy 293.652453 -72.334378) (xy 293.664579 -72.279941)
			(xy 293.684502 -72.22785) (xy 293.711798 -72.179215) (xy 293.745884 -72.135072) (xy 293.786033 -72.096363)
			(xy 293.831391 -72.063912) (xy 293.880991 -72.038411) (xy 293.933775 -72.020404) (xy 293.988618 -72.010274)
			(xy 294.044352 -72.008237) (xy 294.099789 -72.014337) (xy 294.153746 -72.028443) (xy 294.205075 -72.050255)
			(xy 294.252681 -72.079309) (xy 294.295549 -72.114984) (xy 294.332766 -72.156521) (xy 294.363539 -72.203034)
			(xy 294.387211 -72.253531) (xy 294.403279 -72.306938) (xy 294.411399 -72.362114) (xy 294.411908 -72.39)
			(xy 294.411399 -72.417886) (xy 294.403279 -72.473062) (xy 294.387211 -72.526469) (xy 294.363539 -72.576966)
			(xy 294.332766 -72.623479) (xy 294.295549 -72.665016) (xy 294.252681 -72.700691) (xy 294.205075 -72.729745)
			(xy 294.153746 -72.751557) (xy 294.099789 -72.765663) (xy 294.044352 -72.771763) (xy 293.988618 -72.769726)
			(xy 293.933775 -72.759596) (xy 293.880991 -72.741589) (xy 293.831391 -72.716088) (xy 293.786033 -72.683637)
			(xy 293.745884 -72.644928) (xy 293.711798 -72.600785) (xy 293.684502 -72.55215) (xy 293.664579 -72.500059)
			(xy 293.652453 -72.445622) (xy 293.648382 -72.39) (xy 291.490908 -72.39) (xy 291.490399 -72.417886)
			(xy 291.482279 -72.473062) (xy 291.466211 -72.526469) (xy 291.442539 -72.576966) (xy 291.411766 -72.623479)
			(xy 291.374549 -72.665016) (xy 291.331681 -72.700691) (xy 291.284075 -72.729745) (xy 291.232746 -72.751557)
			(xy 291.178789 -72.765663) (xy 291.123352 -72.771763) (xy 291.067618 -72.769726) (xy 291.012775 -72.759596)
			(xy 290.959991 -72.741589) (xy 290.910391 -72.716088) (xy 290.865033 -72.683637) (xy 290.824884 -72.644928)
			(xy 290.790798 -72.600785) (xy 290.763502 -72.55215) (xy 290.743579 -72.500059) (xy 290.731453 -72.445622)
			(xy 290.727382 -72.39) (xy 282.600908 -72.39) (xy 282.600399 -72.417886) (xy 282.592279 -72.473062)
			(xy 282.576211 -72.526469) (xy 282.552539 -72.576966) (xy 282.521766 -72.623479) (xy 282.484549 -72.665016)
			(xy 282.441681 -72.700691) (xy 282.394075 -72.729745) (xy 282.342746 -72.751557) (xy 282.288789 -72.765663)
			(xy 282.233352 -72.771763) (xy 282.177618 -72.769726) (xy 282.122775 -72.759596) (xy 282.069991 -72.741589)
			(xy 282.020391 -72.716088) (xy 281.975033 -72.683637) (xy 281.934884 -72.644928) (xy 281.900798 -72.600785)
			(xy 281.873502 -72.55215) (xy 281.853579 -72.500059) (xy 281.841453 -72.445622) (xy 281.837382 -72.39)
			(xy 273.436881 -72.39) (xy 273.399281 -72.421291) (xy 273.351675 -72.450345) (xy 273.300346 -72.472157)
			(xy 273.246389 -72.486263) (xy 273.190952 -72.492363) (xy 273.135218 -72.490326) (xy 273.080375 -72.480196)
			(xy 273.027591 -72.462189) (xy 272.977991 -72.436688) (xy 272.932633 -72.404237) (xy 272.892484 -72.365528)
			(xy 272.858398 -72.321385) (xy 272.831102 -72.27275) (xy 272.811179 -72.220659) (xy 272.799053 -72.166222)
			(xy 272.794982 -72.1106) (xy 271.323308 -72.1106) (xy 271.322799 -72.138486) (xy 271.314679 -72.193662)
			(xy 271.298611 -72.247069) (xy 271.274939 -72.297566) (xy 271.244166 -72.344079) (xy 271.206949 -72.385616)
			(xy 271.164081 -72.421291) (xy 271.116475 -72.450345) (xy 271.065146 -72.472157) (xy 271.011189 -72.486263)
			(xy 270.955752 -72.492363) (xy 270.900018 -72.490326) (xy 270.845175 -72.480196) (xy 270.792391 -72.462189)
			(xy 270.742791 -72.436688) (xy 270.697433 -72.404237) (xy 270.657284 -72.365528) (xy 270.623198 -72.321385)
			(xy 270.595902 -72.27275) (xy 270.575979 -72.220659) (xy 270.563853 -72.166222) (xy 270.559782 -72.1106)
			(xy 267.250926 -72.1106) (xy 267.250926 -72.949308) (xy 267.251359 -72.959037) (xy 267.258598 -72.977098)
			(xy 267.272034 -72.991171) (xy 267.289741 -72.999237) (xy 267.29944 -73.000108) (xy 267.342292 -73.002596)
			(xy 267.427263 -73.014786) (xy 267.510663 -73.03511) (xy 267.591717 -73.063377) (xy 267.63091 -73.08088)
			(xy 267.631164 -73.08088) (xy 267.631672 -73.081134) (xy 267.641851 -73.085151) (xy 267.663711 -73.085028)
			(xy 267.673836 -73.08088) (xy 267.708901 -73.065153) (xy 267.781208 -73.039103) (xy 267.855493 -73.019391)
			(xy 267.931203 -73.006165) (xy 268.007772 -72.999523) (xy 268.0462 -72.999092) (xy 268.088548 -72.999596)
			(xy 268.172862 -73.007647) (xy 268.256028 -73.023676) (xy 268.337295 -73.047537) (xy 268.415925 -73.079016)
			(xy 268.491206 -73.117827) (xy 268.562458 -73.163617) (xy 268.629034 -73.215973) (xy 268.690332 -73.274421)
			(xy 268.745797 -73.338431) (xy 268.794926 -73.407423) (xy 268.837275 -73.480773) (xy 268.872459 -73.557816)
			(xy 268.900161 -73.637855) (xy 268.920129 -73.720164) (xy 268.932182 -73.803999) (xy 268.936213 -73.8886)
			(xy 268.934586 -73.922752) (xy 271.523436 -73.922752) (xy 271.523436 -73.868248) (xy 271.531192 -73.814297)
			(xy 271.546547 -73.762) (xy 271.569188 -73.71242) (xy 271.598653 -73.666567) (xy 271.634345 -73.625373)
			(xy 271.675535 -73.589677) (xy 271.721385 -73.560207) (xy 271.770963 -73.537561) (xy 271.823258 -73.522201)
			(xy 271.877208 -73.514439) (xy 271.90446 -73.51395) (xy 271.931186 -73.514462) (xy 271.984113 -73.521944)
			(xy 272.022499 -73.533) (xy 279.424382 -73.533) (xy 279.428453 -73.477378) (xy 279.440579 -73.422941)
			(xy 279.460502 -73.37085) (xy 279.487798 -73.322215) (xy 279.521884 -73.278072) (xy 279.562033 -73.239363)
			(xy 279.607391 -73.206912) (xy 279.656991 -73.181411) (xy 279.709775 -73.163404) (xy 279.764618 -73.153274)
			(xy 279.820352 -73.151237) (xy 279.875789 -73.157337) (xy 279.929746 -73.171443) (xy 279.981075 -73.193255)
			(xy 280.028681 -73.222309) (xy 280.071549 -73.257984) (xy 280.108766 -73.299521) (xy 280.139539 -73.346034)
			(xy 280.163211 -73.396531) (xy 280.174258 -73.433249) (xy 280.295378 -73.433249) (xy 280.295378 -73.378751)
			(xy 280.303133 -73.324808) (xy 280.318485 -73.272517) (xy 280.341123 -73.222943) (xy 280.370585 -73.177095)
			(xy 280.406271 -73.135906) (xy 280.447455 -73.100215) (xy 280.493299 -73.070747) (xy 280.54287 -73.048103)
			(xy 280.595159 -73.032743) (xy 280.649101 -73.024981) (xy 280.67635 -73.024492) (xy 280.702014 -73.024921)
			(xy 280.75288 -73.031791) (xy 280.802363 -73.045426) (xy 280.849569 -73.065579) (xy 280.893642 -73.091886)
			(xy 280.933786 -73.123871) (xy 280.969273 -73.160955) (xy 280.984706 -73.181464) (xy 280.993145 -73.19224)
			(xy 281.014584 -73.209239) (xy 281.03976 -73.21995) (xy 281.066875 -73.223607) (xy 281.09399 -73.21995)
			(xy 281.119166 -73.209239) (xy 281.140605 -73.19224) (xy 281.149044 -73.181464) (xy 281.164466 -73.160947)
			(xy 281.199964 -73.123874) (xy 281.240113 -73.091896) (xy 281.284187 -73.065592) (xy 281.331392 -73.045436)
			(xy 281.380873 -73.031794) (xy 281.431736 -73.02491) (xy 281.4574 -73.024492) (xy 281.484651 -73.024978)
			(xy 281.484804 -73.025) (xy 284.504382 -73.025) (xy 284.508453 -72.969378) (xy 284.520579 -72.914941)
			(xy 284.540502 -72.86285) (xy 284.567798 -72.814215) (xy 284.601884 -72.770072) (xy 284.642033 -72.731363)
			(xy 284.687391 -72.698912) (xy 284.736991 -72.673411) (xy 284.789775 -72.655404) (xy 284.844618 -72.645274)
			(xy 284.900352 -72.643237) (xy 284.955789 -72.649337) (xy 285.009746 -72.663443) (xy 285.061075 -72.685255)
			(xy 285.108681 -72.714309) (xy 285.151549 -72.749984) (xy 285.188766 -72.791521) (xy 285.219539 -72.838034)
			(xy 285.243211 -72.888531) (xy 285.259279 -72.941938) (xy 285.267399 -72.997114) (xy 285.267908 -73.025)
			(xy 285.267399 -73.052886) (xy 285.259279 -73.108062) (xy 285.243211 -73.161469) (xy 285.219539 -73.211966)
			(xy 285.188766 -73.258479) (xy 285.151549 -73.300016) (xy 285.108681 -73.335691) (xy 285.061075 -73.364745)
			(xy 285.009746 -73.386557) (xy 284.955789 -73.400663) (xy 284.900352 -73.406763) (xy 284.844618 -73.404726)
			(xy 284.789775 -73.394596) (xy 284.736991 -73.376589) (xy 284.687391 -73.351088) (xy 284.642033 -73.318637)
			(xy 284.601884 -73.279928) (xy 284.567798 -73.235785) (xy 284.540502 -73.18715) (xy 284.520579 -73.135059)
			(xy 284.508453 -73.080622) (xy 284.504382 -73.025) (xy 281.484804 -73.025) (xy 281.538599 -73.032734)
			(xy 281.590894 -73.048089) (xy 281.640471 -73.070731) (xy 281.686321 -73.100197) (xy 281.727512 -73.135888)
			(xy 281.763203 -73.177079) (xy 281.792669 -73.222929) (xy 281.815311 -73.272506) (xy 281.830666 -73.324801)
			(xy 281.838422 -73.378749) (xy 281.838422 -73.433251) (xy 281.830666 -73.487199) (xy 281.815311 -73.539494)
			(xy 281.792669 -73.589071) (xy 281.763203 -73.634921) (xy 281.727512 -73.676112) (xy 281.686321 -73.711803)
			(xy 281.640471 -73.741269) (xy 281.590894 -73.763911) (xy 281.538599 -73.779266) (xy 281.484651 -73.787022)
			(xy 281.4574 -73.787508) (xy 281.431735 -73.787116) (xy 281.380867 -73.78024) (xy 281.331383 -73.766599)
			(xy 281.284177 -73.74644) (xy 281.240104 -73.720127) (xy 281.199961 -73.688136) (xy 281.164476 -73.651048)
			(xy 281.149044 -73.630536) (xy 281.140632 -73.619716) (xy 281.119214 -73.602635) (xy 281.094023 -73.591867)
			(xy 281.066875 -73.58819) (xy 281.039727 -73.591867) (xy 281.014536 -73.602635) (xy 280.993118 -73.619716)
			(xy 280.984706 -73.630536) (xy 280.966599 -73.654391) (xy 280.924228 -73.696709) (xy 280.875763 -73.731886)
			(xy 280.822397 -73.759056) (xy 280.76544 -73.777551) (xy 280.706292 -73.786918) (xy 280.67635 -73.787508)
			(xy 280.649101 -73.787019) (xy 280.595159 -73.779257) (xy 280.54287 -73.763897) (xy 280.493299 -73.741253)
			(xy 280.447455 -73.711785) (xy 280.406271 -73.676094) (xy 280.370585 -73.634905) (xy 280.341123 -73.589057)
			(xy 280.318485 -73.539483) (xy 280.303133 -73.487192) (xy 280.295378 -73.433249) (xy 280.174258 -73.433249)
			(xy 280.179279 -73.449938) (xy 280.187399 -73.505114) (xy 280.187908 -73.533) (xy 280.187399 -73.560886)
			(xy 280.179279 -73.616062) (xy 280.163211 -73.669469) (xy 280.139539 -73.719966) (xy 280.108766 -73.766479)
			(xy 280.071549 -73.808016) (xy 280.028681 -73.843691) (xy 279.981075 -73.872745) (xy 279.929746 -73.894557)
			(xy 279.875789 -73.908663) (xy 279.820352 -73.914763) (xy 279.764618 -73.912726) (xy 279.709775 -73.902596)
			(xy 279.656991 -73.884589) (xy 279.607391 -73.859088) (xy 279.562033 -73.826637) (xy 279.521884 -73.787928)
			(xy 279.487798 -73.743785) (xy 279.460502 -73.69515) (xy 279.440579 -73.643059) (xy 279.428453 -73.588622)
			(xy 279.424382 -73.533) (xy 272.022499 -73.533) (xy 272.035477 -73.536738) (xy 272.084274 -73.558556)
			(xy 272.129549 -73.586971) (xy 272.170415 -73.621425) (xy 272.206074 -73.661246) (xy 272.235826 -73.705653)
			(xy 272.259089 -73.753778) (xy 272.27541 -73.804678) (xy 272.28038 -73.830942) (xy 272.283251 -73.844783)
			(xy 272.295401 -73.870287) (xy 272.314082 -73.891479) (xy 272.337861 -73.906733) (xy 272.364913 -73.914877)
			(xy 272.393161 -73.915286) (xy 272.420437 -73.907929) (xy 272.43278 -73.901046) (xy 272.455019 -73.888268)
			(xy 272.502189 -73.868127) (xy 272.551634 -73.854493) (xy 272.602461 -73.847615) (xy 272.628106 -73.847198)
			(xy 272.655357 -73.847672) (xy 272.709305 -73.85543) (xy 272.7616 -73.870785) (xy 272.811177 -73.893427)
			(xy 272.857028 -73.922894) (xy 272.898218 -73.958586) (xy 272.933909 -73.999777) (xy 272.960402 -74.041)
			(xy 281.837382 -74.041) (xy 281.841453 -73.985378) (xy 281.853579 -73.930941) (xy 281.873502 -73.87885)
			(xy 281.900798 -73.830215) (xy 281.934884 -73.786072) (xy 281.975033 -73.747363) (xy 282.020391 -73.714912)
			(xy 282.069991 -73.689411) (xy 282.122775 -73.671404) (xy 282.177618 -73.661274) (xy 282.233352 -73.659237)
			(xy 282.288789 -73.665337) (xy 282.342746 -73.679443) (xy 282.394075 -73.701255) (xy 282.441681 -73.730309)
			(xy 282.484549 -73.765984) (xy 282.521766 -73.807521) (xy 282.552539 -73.854034) (xy 282.576211 -73.904531)
			(xy 282.592279 -73.957938) (xy 282.600399 -74.013114) (xy 282.600908 -74.041) (xy 282.600399 -74.068886)
			(xy 282.592279 -74.124062) (xy 282.576211 -74.177469) (xy 282.552539 -74.227966) (xy 282.521766 -74.274479)
			(xy 282.484549 -74.316016) (xy 282.441681 -74.351691) (xy 282.394075 -74.380745) (xy 282.342746 -74.402557)
			(xy 282.288789 -74.416663) (xy 282.233352 -74.422763) (xy 282.177618 -74.420726) (xy 282.122775 -74.410596)
			(xy 282.069991 -74.392589) (xy 282.020391 -74.367088) (xy 281.975033 -74.334637) (xy 281.934884 -74.295928)
			(xy 281.900798 -74.251785) (xy 281.873502 -74.20315) (xy 281.853579 -74.151059) (xy 281.841453 -74.096622)
			(xy 281.837382 -74.041) (xy 272.960402 -74.041) (xy 272.963376 -74.045628) (xy 272.986017 -74.095205)
			(xy 273.001372 -74.147501) (xy 273.009128 -74.201449) (xy 273.009128 -74.255951) (xy 273.001372 -74.309899)
			(xy 272.986017 -74.362195) (xy 272.963376 -74.411772) (xy 272.933909 -74.457623) (xy 272.898218 -74.498814)
			(xy 272.857028 -74.534506) (xy 272.811177 -74.563973) (xy 272.7616 -74.586615) (xy 272.709305 -74.60197)
			(xy 272.655357 -74.609728) (xy 272.628106 -74.610214) (xy 272.601378 -74.609763) (xy 272.548447 -74.602276)
			(xy 272.49708 -74.587475) (xy 272.448281 -74.565651) (xy 272.403005 -74.537229) (xy 272.362138 -74.502768)
			(xy 272.326481 -74.46294) (xy 272.296731 -74.418526) (xy 272.27347 -74.370395) (xy 272.257154 -74.319489)
			(xy 272.252186 -74.293222) (xy 272.249384 -74.279365) (xy 272.237221 -74.253857) (xy 272.218526 -74.232664)
			(xy 272.194735 -74.217412) (xy 272.167673 -74.209272) (xy 272.139416 -74.208868) (xy 272.112132 -74.216231)
			(xy 272.099786 -74.223118) (xy 272.077552 -74.235905) (xy 272.030381 -74.256045) (xy 271.980934 -74.269676)
			(xy 271.930106 -74.276551) (xy 271.90446 -74.276966) (xy 271.877208 -74.276561) (xy 271.823258 -74.268799)
			(xy 271.770963 -74.253439) (xy 271.721385 -74.230793) (xy 271.675535 -74.201323) (xy 271.634345 -74.165627)
			(xy 271.598653 -74.124433) (xy 271.569188 -74.07858) (xy 271.546547 -74.029) (xy 271.531192 -73.976703)
			(xy 271.523436 -73.922752) (xy 268.934586 -73.922752) (xy 268.932182 -73.973201) (xy 268.920129 -74.057036)
			(xy 268.900161 -74.139345) (xy 268.872459 -74.219384) (xy 268.837275 -74.296427) (xy 268.794926 -74.369777)
			(xy 268.745797 -74.438769) (xy 268.690332 -74.502779) (xy 268.629034 -74.561227) (xy 268.562458 -74.613583)
			(xy 268.491206 -74.659373) (xy 268.458955 -74.676) (xy 274.090382 -74.676) (xy 274.094453 -74.620378)
			(xy 274.106579 -74.565941) (xy 274.126502 -74.51385) (xy 274.153798 -74.465215) (xy 274.187884 -74.421072)
			(xy 274.228033 -74.382363) (xy 274.273391 -74.349912) (xy 274.322991 -74.324411) (xy 274.375775 -74.306404)
			(xy 274.430618 -74.296274) (xy 274.486352 -74.294237) (xy 274.541789 -74.300337) (xy 274.595746 -74.314443)
			(xy 274.647075 -74.336255) (xy 274.694681 -74.365309) (xy 274.737549 -74.400984) (xy 274.774766 -74.442521)
			(xy 274.805539 -74.489034) (xy 274.829211 -74.539531) (xy 274.845279 -74.592938) (xy 274.853399 -74.648114)
			(xy 274.853908 -74.676) (xy 274.853399 -74.703886) (xy 274.845279 -74.759062) (xy 274.829211 -74.812469)
			(xy 274.805539 -74.862966) (xy 274.774766 -74.909479) (xy 274.737549 -74.951016) (xy 274.694681 -74.986691)
			(xy 274.647075 -75.015745) (xy 274.595746 -75.037557) (xy 274.541789 -75.051663) (xy 274.486352 -75.057763)
			(xy 274.430618 -75.055726) (xy 274.375775 -75.045596) (xy 274.322991 -75.027589) (xy 274.273391 -75.002088)
			(xy 274.228033 -74.969637) (xy 274.187884 -74.930928) (xy 274.153798 -74.886785) (xy 274.126502 -74.83815)
			(xy 274.106579 -74.786059) (xy 274.094453 -74.731622) (xy 274.090382 -74.676) (xy 268.458955 -74.676)
			(xy 268.415925 -74.698184) (xy 268.337295 -74.729663) (xy 268.256028 -74.753524) (xy 268.172862 -74.769553)
			(xy 268.088548 -74.777604) (xy 268.0462 -74.778108) (xy 268.007772 -74.777689) (xy 267.931204 -74.771035)
			(xy 267.855496 -74.757803) (xy 267.781211 -74.73809) (xy 267.708902 -74.712044) (xy 267.673836 -74.69632)
			(xy 267.663676 -74.691494) (xy 267.641832 -74.691494) (xy 267.631164 -74.69632) (xy 267.63091 -74.69632)
			(xy 267.591716 -74.713822) (xy 267.510662 -74.742085) (xy 267.427262 -74.762412) (xy 267.342292 -74.774611)
			(xy 267.29944 -74.777092) (xy 267.29436 -74.7776) (xy 267.285427 -74.779283) (xy 267.269504 -74.788024)
			(xy 267.257637 -74.801777) (xy 267.251323 -74.818809) (xy 267.250926 -74.827892) (xy 267.250926 -75.184)
			(xy 279.678382 -75.184) (xy 279.682453 -75.128378) (xy 279.694579 -75.073941) (xy 279.714502 -75.02185)
			(xy 279.741798 -74.973215) (xy 279.775884 -74.929072) (xy 279.816033 -74.890363) (xy 279.861391 -74.857912)
			(xy 279.910991 -74.832411) (xy 279.963775 -74.814404) (xy 280.018618 -74.804274) (xy 280.074352 -74.802237)
			(xy 280.129789 -74.808337) (xy 280.183746 -74.822443) (xy 280.235075 -74.844255) (xy 280.282681 -74.873309)
			(xy 280.325549 -74.908984) (xy 280.362766 -74.950521) (xy 280.393539 -74.997034) (xy 280.417211 -75.047531)
			(xy 280.433279 -75.100938) (xy 280.441399 -75.156114) (xy 280.441908 -75.184) (xy 282.065982 -75.184)
			(xy 282.070053 -75.128378) (xy 282.082179 -75.073941) (xy 282.102102 -75.02185) (xy 282.129398 -74.973215)
			(xy 282.163484 -74.929072) (xy 282.203633 -74.890363) (xy 282.248991 -74.857912) (xy 282.298591 -74.832411)
			(xy 282.351375 -74.814404) (xy 282.406218 -74.804274) (xy 282.461952 -74.802237) (xy 282.517389 -74.808337)
			(xy 282.571346 -74.822443) (xy 282.622675 -74.844255) (xy 282.670281 -74.873309) (xy 282.713149 -74.908984)
			(xy 282.750366 -74.950521) (xy 282.781139 -74.997034) (xy 282.804811 -75.047531) (xy 282.820879 -75.100938)
			(xy 282.828999 -75.156114) (xy 282.829508 -75.184) (xy 284.377382 -75.184) (xy 284.381453 -75.128378)
			(xy 284.393579 -75.073941) (xy 284.413502 -75.02185) (xy 284.440798 -74.973215) (xy 284.474884 -74.929072)
			(xy 284.515033 -74.890363) (xy 284.560391 -74.857912) (xy 284.609991 -74.832411) (xy 284.662775 -74.814404)
			(xy 284.717618 -74.804274) (xy 284.773352 -74.802237) (xy 284.828789 -74.808337) (xy 284.882746 -74.822443)
			(xy 284.934075 -74.844255) (xy 284.981681 -74.873309) (xy 285.024549 -74.908984) (xy 285.061766 -74.950521)
			(xy 285.092539 -74.997034) (xy 285.108267 -75.030584) (xy 293.371778 -75.030584) (xy 293.372359 -75.002079)
			(xy 293.380843 -74.945705) (xy 293.39762 -74.89122) (xy 293.422317 -74.839838) (xy 293.454384 -74.792703)
			(xy 293.493107 -74.750862) (xy 293.515034 -74.732642) (xy 293.523924 -74.72553) (xy 293.53383 -74.705718)
			(xy 293.53637 -74.605134) (xy 293.527734 -74.584814) (xy 293.519098 -74.577194) (xy 293.499313 -74.559012)
			(xy 293.464521 -74.518064) (xy 293.435822 -74.472637) (xy 293.413783 -74.423632) (xy 293.39884 -74.372018)
			(xy 293.391291 -74.318818) (xy 293.390828 -74.291952) (xy 293.391314 -74.264701) (xy 293.39907 -74.210753)
			(xy 293.414425 -74.158458) (xy 293.437067 -74.108881) (xy 293.466533 -74.063031) (xy 293.502224 -74.02184)
			(xy 293.543415 -73.986149) (xy 293.589265 -73.956683) (xy 293.638842 -73.934041) (xy 293.691137 -73.918686)
			(xy 293.745085 -73.91093) (xy 293.799587 -73.91093) (xy 293.853535 -73.918686) (xy 293.90583 -73.934041)
			(xy 293.955407 -73.956683) (xy 294.001257 -73.986149) (xy 294.042448 -74.02184) (xy 294.078139 -74.063031)
			(xy 294.107605 -74.108881) (xy 294.130247 -74.158458) (xy 294.145602 -74.210753) (xy 294.153358 -74.264701)
			(xy 294.153844 -74.291952) (xy 294.153318 -74.320459) (xy 294.144826 -74.376837) (xy 294.12804 -74.431324)
			(xy 294.103333 -74.482707) (xy 294.095579 -74.4941) (xy 303.021024 -74.4941) (xy 303.025053 -74.409502)
			(xy 303.037107 -74.325671) (xy 303.057074 -74.243365) (xy 303.084774 -74.163329) (xy 303.119957 -74.086289)
			(xy 303.162304 -74.012942) (xy 303.211431 -73.943953) (xy 303.266894 -73.879946) (xy 303.328189 -73.821501)
			(xy 303.394763 -73.769147) (xy 303.466012 -73.723358) (xy 303.54129 -73.684549) (xy 303.619917 -73.653071)
			(xy 303.70118 -73.629211) (xy 303.784343 -73.613182) (xy 303.868653 -73.605132) (xy 303.911 -73.604628)
			(xy 303.951053 -73.605065) (xy 304.030834 -73.612275) (xy 304.109644 -73.626629) (xy 304.186844 -73.64801)
			(xy 304.261809 -73.676245) (xy 304.333933 -73.711105) (xy 304.40263 -73.752308) (xy 304.467345 -73.799519)
			(xy 304.49774 -73.825608) (xy 304.504857 -73.831298) (xy 304.52191 -73.837677) (xy 304.531014 -73.838054)
			(xy 304.560986 -73.838054) (xy 304.570087 -73.837662) (xy 304.587138 -73.831287) (xy 304.59426 -73.825608)
			(xy 304.624662 -73.799528) (xy 304.689372 -73.752309) (xy 304.758067 -73.711101) (xy 304.830189 -73.676238)
			(xy 304.905154 -73.648002) (xy 304.982355 -73.626623) (xy 305.061165 -73.612273) (xy 305.140947 -73.605068)
			(xy 305.181 -73.604628) (xy 305.22335 -73.60506) (xy 305.307667 -73.613111) (xy 305.390837 -73.629141)
			(xy 305.472106 -73.653003) (xy 305.55074 -73.684483) (xy 305.626024 -73.723295) (xy 305.697279 -73.769088)
			(xy 305.763858 -73.821446) (xy 305.825158 -73.879896) (xy 305.880625 -73.943909) (xy 305.929756 -74.012903)
			(xy 305.972107 -74.086256) (xy 306.007292 -74.163302) (xy 306.034995 -74.243344) (xy 306.054964 -74.325657)
			(xy 306.067018 -74.409496) (xy 306.071049 -74.4941) (xy 306.067018 -74.578704) (xy 306.054964 -74.662543)
			(xy 306.034995 -74.744856) (xy 306.007292 -74.824898) (xy 305.972107 -74.901944) (xy 305.929756 -74.975297)
			(xy 305.880625 -75.044291) (xy 305.825158 -75.108304) (xy 305.763858 -75.166754) (xy 305.697279 -75.219112)
			(xy 305.626024 -75.264905) (xy 305.55074 -75.303717) (xy 305.472106 -75.335197) (xy 305.390837 -75.359059)
			(xy 305.307667 -75.375089) (xy 305.22335 -75.38314) (xy 305.181 -75.383644) (xy 305.140947 -75.383214)
			(xy 305.061165 -75.376003) (xy 304.982355 -75.361649) (xy 304.905155 -75.340267) (xy 304.830189 -75.312032)
			(xy 304.758066 -75.277171) (xy 304.689369 -75.235967) (xy 304.624654 -75.188753) (xy 304.59426 -75.162664)
			(xy 304.587137 -75.156983) (xy 304.570089 -75.150596) (xy 304.560986 -75.150218) (xy 304.531014 -75.150218)
			(xy 304.521914 -75.150616) (xy 304.504863 -75.156987) (xy 304.49774 -75.162664) (xy 304.467334 -75.18874)
			(xy 304.402625 -75.23596) (xy 304.333931 -75.277168) (xy 304.26181 -75.312032) (xy 304.186845 -75.340269)
			(xy 304.109645 -75.361649) (xy 304.030835 -75.375999) (xy 303.951053 -75.383204) (xy 303.911 -75.383644)
			(xy 303.868653 -75.383068) (xy 303.784343 -75.375018) (xy 303.70118 -75.358989) (xy 303.619917 -75.335129)
			(xy 303.54129 -75.303651) (xy 303.466012 -75.264842) (xy 303.394763 -75.219053) (xy 303.328189 -75.166699)
			(xy 303.266894 -75.108254) (xy 303.211431 -75.044247) (xy 303.162304 -74.975258) (xy 303.119957 -74.901911)
			(xy 303.084774 -74.824871) (xy 303.057074 -74.744835) (xy 303.037107 -74.662529) (xy 303.025053 -74.578698)
			(xy 303.021024 -74.4941) (xy 294.095579 -74.4941) (xy 294.071255 -74.529841) (xy 294.032521 -74.571677)
			(xy 294.010588 -74.589894) (xy 294.001698 -74.597006) (xy 293.991792 -74.616818) (xy 293.989252 -74.717402)
			(xy 293.997888 -74.737722) (xy 294.006524 -74.745342) (xy 294.026311 -74.763522) (xy 294.061106 -74.804469)
			(xy 294.089807 -74.849895) (xy 294.111846 -74.898901) (xy 294.126787 -74.950516) (xy 294.134333 -75.003717)
			(xy 294.134794 -75.030584) (xy 294.134308 -75.057835) (xy 294.126552 -75.111783) (xy 294.111197 -75.164078)
			(xy 294.088555 -75.213655) (xy 294.059089 -75.259505) (xy 294.023398 -75.300696) (xy 293.982207 -75.336387)
			(xy 293.936357 -75.365853) (xy 293.88678 -75.388495) (xy 293.834485 -75.40385) (xy 293.780537 -75.411606)
			(xy 293.726035 -75.411606) (xy 293.672087 -75.40385) (xy 293.619792 -75.388495) (xy 293.570215 -75.365853)
			(xy 293.524365 -75.336387) (xy 293.483174 -75.300696) (xy 293.447483 -75.259505) (xy 293.418017 -75.213655)
			(xy 293.395375 -75.164078) (xy 293.38002 -75.111783) (xy 293.372264 -75.057835) (xy 293.371778 -75.030584)
			(xy 285.108267 -75.030584) (xy 285.116211 -75.047531) (xy 285.132279 -75.100938) (xy 285.140399 -75.156114)
			(xy 285.140908 -75.184) (xy 285.140399 -75.211886) (xy 285.132279 -75.267062) (xy 285.116211 -75.320469)
			(xy 285.092539 -75.370966) (xy 285.061766 -75.417479) (xy 285.024549 -75.459016) (xy 284.981681 -75.494691)
			(xy 284.934075 -75.523745) (xy 284.882746 -75.545557) (xy 284.828789 -75.559663) (xy 284.773352 -75.565763)
			(xy 284.717618 -75.563726) (xy 284.662775 -75.553596) (xy 284.609991 -75.535589) (xy 284.560391 -75.510088)
			(xy 284.515033 -75.477637) (xy 284.474884 -75.438928) (xy 284.440798 -75.394785) (xy 284.413502 -75.34615)
			(xy 284.393579 -75.294059) (xy 284.381453 -75.239622) (xy 284.377382 -75.184) (xy 282.829508 -75.184)
			(xy 282.828999 -75.211886) (xy 282.820879 -75.267062) (xy 282.804811 -75.320469) (xy 282.781139 -75.370966)
			(xy 282.750366 -75.417479) (xy 282.713149 -75.459016) (xy 282.670281 -75.494691) (xy 282.622675 -75.523745)
			(xy 282.571346 -75.545557) (xy 282.517389 -75.559663) (xy 282.461952 -75.565763) (xy 282.406218 -75.563726)
			(xy 282.351375 -75.553596) (xy 282.298591 -75.535589) (xy 282.248991 -75.510088) (xy 282.203633 -75.477637)
			(xy 282.163484 -75.438928) (xy 282.129398 -75.394785) (xy 282.102102 -75.34615) (xy 282.082179 -75.294059)
			(xy 282.070053 -75.239622) (xy 282.065982 -75.184) (xy 280.441908 -75.184) (xy 280.441399 -75.211886)
			(xy 280.433279 -75.267062) (xy 280.417211 -75.320469) (xy 280.393539 -75.370966) (xy 280.362766 -75.417479)
			(xy 280.325549 -75.459016) (xy 280.282681 -75.494691) (xy 280.235075 -75.523745) (xy 280.183746 -75.545557)
			(xy 280.129789 -75.559663) (xy 280.074352 -75.565763) (xy 280.018618 -75.563726) (xy 279.963775 -75.553596)
			(xy 279.910991 -75.535589) (xy 279.861391 -75.510088) (xy 279.816033 -75.477637) (xy 279.775884 -75.438928)
			(xy 279.741798 -75.394785) (xy 279.714502 -75.34615) (xy 279.694579 -75.294059) (xy 279.682453 -75.239622)
			(xy 279.678382 -75.184) (xy 267.250926 -75.184) (xy 267.250926 -75.861348) (xy 297.179996 -75.861348)
			(xy 297.179996 -75.776652) (xy 297.188047 -75.692338) (xy 297.204076 -75.609172) (xy 297.227937 -75.527905)
			(xy 297.259416 -75.449275) (xy 297.298227 -75.373994) (xy 297.344017 -75.302742) (xy 297.396373 -75.236166)
			(xy 297.454821 -75.174868) (xy 297.518831 -75.119403) (xy 297.587823 -75.070274) (xy 297.661173 -75.027925)
			(xy 297.738216 -74.992741) (xy 297.818255 -74.965039) (xy 297.900564 -74.945071) (xy 297.984399 -74.933018)
			(xy 298.069 -74.928988) (xy 298.153601 -74.933018) (xy 298.237436 -74.945071) (xy 298.319745 -74.965039)
			(xy 298.399784 -74.992741) (xy 298.476827 -75.027925) (xy 298.550177 -75.070274) (xy 298.619169 -75.119403)
			(xy 298.683179 -75.174868) (xy 298.741627 -75.236166) (xy 298.793983 -75.302742) (xy 298.839773 -75.373994)
			(xy 298.878584 -75.449275) (xy 298.910063 -75.527905) (xy 298.933924 -75.609172) (xy 298.949953 -75.692338)
			(xy 298.958004 -75.776652) (xy 298.958508 -75.819) (xy 298.958004 -75.861348) (xy 298.949953 -75.945662)
			(xy 298.933924 -76.028828) (xy 298.910063 -76.110095) (xy 298.878584 -76.188725) (xy 298.839773 -76.264006)
			(xy 298.809865 -76.310544) (xy 305.873647 -76.310544) (xy 305.873647 -76.181404) (xy 305.881597 -76.052509)
			(xy 305.897467 -75.924349) (xy 305.921196 -75.797408) (xy 305.952695 -75.672169) (xy 305.991844 -75.549106)
			(xy 306.038495 -75.428687) (xy 306.09247 -75.311368) (xy 306.153565 -75.197594) (xy 306.221548 -75.087797)
			(xy 306.296162 -74.982394) (xy 306.377123 -74.881784) (xy 306.464123 -74.786349) (xy 306.556834 -74.69645)
			(xy 306.654904 -74.612429) (xy 306.757959 -74.534605) (xy 306.86561 -74.463273) (xy 306.977449 -74.398703)
			(xy 307.09305 -74.341141) (xy 307.211975 -74.290804) (xy 307.333774 -74.247884) (xy 307.457984 -74.212543)
			(xy 307.584133 -74.184916) (xy 307.711745 -74.165107) (xy 307.840334 -74.153191) (xy 307.969412 -74.149215)
			(xy 308.09849 -74.153191) (xy 308.227079 -74.165107) (xy 308.354691 -74.184916) (xy 308.48084 -74.212543)
			(xy 308.60505 -74.247884) (xy 308.726849 -74.290804) (xy 308.845774 -74.341141) (xy 308.961375 -74.398703)
			(xy 309.073214 -74.463273) (xy 309.180865 -74.534605) (xy 309.28392 -74.612429) (xy 309.38199 -74.69645)
			(xy 309.474701 -74.786349) (xy 309.561701 -74.881784) (xy 309.642662 -74.982394) (xy 309.717276 -75.087797)
			(xy 309.785259 -75.197594) (xy 309.846354 -75.311368) (xy 309.900329 -75.428687) (xy 309.94698 -75.549106)
			(xy 309.986129 -75.672169) (xy 310.017628 -75.797408) (xy 310.041357 -75.924349) (xy 310.057227 -76.052509)
			(xy 310.065177 -76.181404) (xy 310.065674 -76.245974) (xy 310.065177 -76.310544) (xy 310.057227 -76.439439)
			(xy 310.041357 -76.567599) (xy 310.017628 -76.69454) (xy 309.986129 -76.819779) (xy 309.94698 -76.942842)
			(xy 309.900329 -77.063261) (xy 309.846354 -77.18058) (xy 309.785259 -77.294354) (xy 309.717276 -77.404151)
			(xy 309.642662 -77.509554) (xy 309.561701 -77.610164) (xy 309.474701 -77.705599) (xy 309.38199 -77.795498)
			(xy 309.28392 -77.879519) (xy 309.180865 -77.957343) (xy 309.073214 -78.028675) (xy 308.961375 -78.093245)
			(xy 308.845774 -78.150807) (xy 308.726849 -78.201144) (xy 308.60505 -78.244064) (xy 308.48084 -78.279405)
			(xy 308.354691 -78.307032) (xy 308.227079 -78.326841) (xy 308.09849 -78.338757) (xy 307.969412 -78.342734)
			(xy 307.840334 -78.338757) (xy 307.711745 -78.326841) (xy 307.584133 -78.307032) (xy 307.457984 -78.279405)
			(xy 307.333774 -78.244064) (xy 307.211975 -78.201144) (xy 307.09305 -78.150807) (xy 306.977449 -78.093245)
			(xy 306.86561 -78.028675) (xy 306.757959 -77.957343) (xy 306.654904 -77.879519) (xy 306.556834 -77.795498)
			(xy 306.464123 -77.705599) (xy 306.377123 -77.610164) (xy 306.296162 -77.509554) (xy 306.221548 -77.404151)
			(xy 306.153565 -77.294354) (xy 306.09247 -77.18058) (xy 306.038495 -77.063261) (xy 305.991844 -76.942842)
			(xy 305.952695 -76.819779) (xy 305.921196 -76.69454) (xy 305.897467 -76.567599) (xy 305.881597 -76.439439)
			(xy 305.873647 -76.310544) (xy 298.809865 -76.310544) (xy 298.793983 -76.335258) (xy 298.741627 -76.401834)
			(xy 298.683179 -76.463132) (xy 298.619169 -76.518597) (xy 298.550177 -76.567726) (xy 298.476827 -76.610075)
			(xy 298.399784 -76.645259) (xy 298.319745 -76.672961) (xy 298.237436 -76.692929) (xy 298.153601 -76.704982)
			(xy 298.069 -76.709013) (xy 297.984399 -76.704982) (xy 297.900564 -76.692929) (xy 297.818255 -76.672961)
			(xy 297.738216 -76.645259) (xy 297.661173 -76.610075) (xy 297.587823 -76.567726) (xy 297.518831 -76.518597)
			(xy 297.454821 -76.463132) (xy 297.396373 -76.401834) (xy 297.344017 -76.335258) (xy 297.298227 -76.264006)
			(xy 297.259416 -76.188725) (xy 297.227937 -76.110095) (xy 297.204076 -76.028828) (xy 297.188047 -75.945662)
			(xy 297.179996 -75.861348) (xy 267.250926 -75.861348) (xy 267.250926 -76.327) (xy 281.837382 -76.327)
			(xy 281.841453 -76.271378) (xy 281.853579 -76.216941) (xy 281.873502 -76.16485) (xy 281.900798 -76.116215)
			(xy 281.934884 -76.072072) (xy 281.975033 -76.033363) (xy 282.020391 -76.000912) (xy 282.069991 -75.975411)
			(xy 282.122775 -75.957404) (xy 282.177618 -75.947274) (xy 282.233352 -75.945237) (xy 282.288789 -75.951337)
			(xy 282.342746 -75.965443) (xy 282.394075 -75.987255) (xy 282.441681 -76.016309) (xy 282.484549 -76.051984)
			(xy 282.521766 -76.093521) (xy 282.552539 -76.140034) (xy 282.576211 -76.190531) (xy 282.592279 -76.243938)
			(xy 282.600399 -76.299114) (xy 282.600908 -76.327) (xy 282.600399 -76.354886) (xy 282.592279 -76.410062)
			(xy 282.576211 -76.463469) (xy 282.552539 -76.513966) (xy 282.521766 -76.560479) (xy 282.484549 -76.602016)
			(xy 282.441681 -76.637691) (xy 282.394075 -76.666745) (xy 282.342746 -76.688557) (xy 282.288789 -76.702663)
			(xy 282.233352 -76.708763) (xy 282.177618 -76.706726) (xy 282.122775 -76.696596) (xy 282.069991 -76.678589)
			(xy 282.020391 -76.653088) (xy 281.975033 -76.620637) (xy 281.934884 -76.581928) (xy 281.900798 -76.537785)
			(xy 281.873502 -76.48915) (xy 281.853579 -76.437059) (xy 281.841453 -76.382622) (xy 281.837382 -76.327)
			(xy 267.250926 -76.327) (xy 267.250926 -77.47) (xy 269.518382 -77.47) (xy 269.522453 -77.414378)
			(xy 269.534579 -77.359941) (xy 269.554502 -77.30785) (xy 269.581798 -77.259215) (xy 269.615884 -77.215072)
			(xy 269.656033 -77.176363) (xy 269.701391 -77.143912) (xy 269.750991 -77.118411) (xy 269.803775 -77.100404)
			(xy 269.858618 -77.090274) (xy 269.914352 -77.088237) (xy 269.969789 -77.094337) (xy 270.023746 -77.108443)
			(xy 270.075075 -77.130255) (xy 270.122681 -77.159309) (xy 270.165549 -77.194984) (xy 270.202766 -77.236521)
			(xy 270.203842 -77.238148) (xy 270.643398 -77.238148) (xy 270.643398 -77.183652) (xy 270.651153 -77.129712)
			(xy 270.666505 -77.077424) (xy 270.689141 -77.027853) (xy 270.718601 -76.982007) (xy 270.754285 -76.940821)
			(xy 270.795467 -76.905131) (xy 270.841309 -76.875665) (xy 270.890877 -76.853022) (xy 270.943163 -76.837664)
			(xy 270.997103 -76.829902) (xy 271.02435 -76.829412) (xy 271.050953 -76.829893) (xy 271.103645 -76.837269)
			(xy 271.1548 -76.851897) (xy 271.203425 -76.873494) (xy 271.248576 -76.901641) (xy 271.289376 -76.93579)
			(xy 271.325032 -76.97528) (xy 271.340326 -76.997052) (xy 271.34866 -77.008532) (xy 271.370404 -77.026736)
			(xy 271.396317 -77.038254) (xy 271.4244 -77.042194) (xy 271.452483 -77.038254) (xy 271.478396 -77.026736)
			(xy 271.50014 -77.008532) (xy 271.508474 -76.997052) (xy 271.523777 -76.975288) (xy 271.559442 -76.935808)
			(xy 271.600244 -76.901664) (xy 271.645392 -76.873517) (xy 271.694012 -76.851914) (xy 271.745161 -76.837272)
			(xy 271.797848 -76.829876) (xy 271.82445 -76.829412) (xy 271.851707 -76.829831) (xy 271.905666 -76.837583)
			(xy 271.957973 -76.852936) (xy 272.007562 -76.875576) (xy 272.053423 -76.905045) (xy 272.094624 -76.94074)
			(xy 272.130325 -76.981936) (xy 272.1598 -77.027794) (xy 272.182447 -77.077381) (xy 272.185859 -77.089)
			(xy 283.589982 -77.089) (xy 283.594053 -77.033378) (xy 283.606179 -76.978941) (xy 283.626102 -76.92685)
			(xy 283.653398 -76.878215) (xy 283.687484 -76.834072) (xy 283.727633 -76.795363) (xy 283.772991 -76.762912)
			(xy 283.822591 -76.737411) (xy 283.875375 -76.719404) (xy 283.930218 -76.709274) (xy 283.985952 -76.707237)
			(xy 284.041389 -76.713337) (xy 284.095346 -76.727443) (xy 284.146675 -76.749255) (xy 284.194281 -76.778309)
			(xy 284.237149 -76.813984) (xy 284.274366 -76.855521) (xy 284.305139 -76.902034) (xy 284.328811 -76.952531)
			(xy 284.33166 -76.962) (xy 293.531034 -76.962) (xy 293.535105 -76.906378) (xy 293.547231 -76.851941)
			(xy 293.567154 -76.79985) (xy 293.59445 -76.751215) (xy 293.628536 -76.707072) (xy 293.668685 -76.668363)
			(xy 293.714043 -76.635912) (xy 293.763643 -76.610411) (xy 293.816427 -76.592404) (xy 293.87127 -76.582274)
			(xy 293.927004 -76.580237) (xy 293.982441 -76.586337) (xy 294.036398 -76.600443) (xy 294.087727 -76.622255)
			(xy 294.135333 -76.651309) (xy 294.178201 -76.686984) (xy 294.215418 -76.728521) (xy 294.246191 -76.775034)
			(xy 294.269863 -76.825531) (xy 294.285931 -76.878938) (xy 294.294051 -76.934114) (xy 294.29456 -76.962)
			(xy 294.294051 -76.989886) (xy 294.285931 -77.045062) (xy 294.269863 -77.098469) (xy 294.246191 -77.148966)
			(xy 294.215418 -77.195479) (xy 294.178201 -77.237016) (xy 294.135333 -77.272691) (xy 294.087727 -77.301745)
			(xy 294.036398 -77.323557) (xy 293.982441 -77.337663) (xy 293.927004 -77.343763) (xy 293.87127 -77.341726)
			(xy 293.816427 -77.331596) (xy 293.763643 -77.313589) (xy 293.714043 -77.288088) (xy 293.668685 -77.255637)
			(xy 293.628536 -77.216928) (xy 293.59445 -77.172785) (xy 293.567154 -77.12415) (xy 293.547231 -77.072059)
			(xy 293.535105 -77.017622) (xy 293.531034 -76.962) (xy 284.33166 -76.962) (xy 284.344879 -77.005938)
			(xy 284.352999 -77.061114) (xy 284.353508 -77.089) (xy 284.352999 -77.116886) (xy 284.344879 -77.172062)
			(xy 284.328811 -77.225469) (xy 284.305139 -77.275966) (xy 284.274366 -77.322479) (xy 284.237149 -77.364016)
			(xy 284.194281 -77.399691) (xy 284.146675 -77.428745) (xy 284.095346 -77.450557) (xy 284.041389 -77.464663)
			(xy 283.985952 -77.470763) (xy 283.930218 -77.468726) (xy 283.875375 -77.458596) (xy 283.822591 -77.440589)
			(xy 283.772991 -77.415088) (xy 283.727633 -77.382637) (xy 283.687484 -77.343928) (xy 283.653398 -77.299785)
			(xy 283.626102 -77.25115) (xy 283.606179 -77.199059) (xy 283.594053 -77.144622) (xy 283.589982 -77.089)
			(xy 272.185859 -77.089) (xy 272.197806 -77.129685) (xy 272.205565 -77.183643) (xy 272.205565 -77.238157)
			(xy 272.197806 -77.292115) (xy 272.182447 -77.344419) (xy 272.1598 -77.394006) (xy 272.130325 -77.439864)
			(xy 272.094624 -77.48106) (xy 272.053423 -77.516755) (xy 272.007562 -77.546224) (xy 271.957973 -77.568864)
			(xy 271.905666 -77.584217) (xy 271.851707 -77.591969) (xy 271.82445 -77.592428) (xy 271.797846 -77.591973)
			(xy 271.745152 -77.584596) (xy 271.693995 -77.569965) (xy 271.645369 -77.548365) (xy 271.600218 -77.520213)
			(xy 271.559419 -77.486058) (xy 271.523766 -77.446563) (xy 271.508474 -77.424788) (xy 271.50014 -77.413308)
			(xy 271.478396 -77.395104) (xy 271.452483 -77.383586) (xy 271.4244 -77.379646) (xy 271.396317 -77.383586)
			(xy 271.370404 -77.395104) (xy 271.34866 -77.413308) (xy 271.340326 -77.424788) (xy 271.325035 -77.446561)
			(xy 271.289367 -77.486039) (xy 271.248563 -77.520181) (xy 271.203412 -77.548326) (xy 271.15479 -77.569928)
			(xy 271.10364 -77.584568) (xy 271.050952 -77.591964) (xy 271.02435 -77.592428) (xy 270.997103 -77.591898)
			(xy 270.943163 -77.584136) (xy 270.890877 -77.568778) (xy 270.841309 -77.546135) (xy 270.795467 -77.516669)
			(xy 270.754285 -77.480979) (xy 270.718601 -77.439793) (xy 270.689141 -77.393947) (xy 270.666505 -77.344376)
			(xy 270.651153 -77.292088) (xy 270.643398 -77.238148) (xy 270.203842 -77.238148) (xy 270.233539 -77.283034)
			(xy 270.257211 -77.333531) (xy 270.273279 -77.386938) (xy 270.281399 -77.442114) (xy 270.281908 -77.47)
			(xy 270.281399 -77.497886) (xy 270.273279 -77.553062) (xy 270.257211 -77.606469) (xy 270.233539 -77.656966)
			(xy 270.202766 -77.703479) (xy 270.165549 -77.745016) (xy 270.122681 -77.780691) (xy 270.075075 -77.809745)
			(xy 270.023746 -77.831557) (xy 269.969789 -77.845663) (xy 269.914352 -77.851763) (xy 269.858618 -77.849726)
			(xy 269.803775 -77.839596) (xy 269.750991 -77.821589) (xy 269.701391 -77.796088) (xy 269.656033 -77.763637)
			(xy 269.615884 -77.724928) (xy 269.581798 -77.680785) (xy 269.554502 -77.63215) (xy 269.534579 -77.580059)
			(xy 269.522453 -77.525622) (xy 269.518382 -77.47) (xy 267.250926 -77.47) (xy 267.250926 -78.1558)
			(xy 279.439887 -78.1558) (xy 279.443918 -78.071199) (xy 279.455971 -77.987365) (xy 279.475939 -77.905056)
			(xy 279.50364 -77.825017) (xy 279.538825 -77.747974) (xy 279.581173 -77.674625) (xy 279.630301 -77.605633)
			(xy 279.685766 -77.541623) (xy 279.747063 -77.483176) (xy 279.813639 -77.430819) (xy 279.88489 -77.385029)
			(xy 279.960171 -77.346218) (xy 280.038801 -77.314739) (xy 280.120067 -77.290877) (xy 280.203233 -77.274847)
			(xy 280.287546 -77.266796) (xy 280.329894 -77.266292) (xy 280.330402 -77.266292) (xy 280.376734 -77.2669)
			(xy 280.468892 -77.276571) (xy 280.559546 -77.295766) (xy 280.647715 -77.324277) (xy 280.69032 -77.342492)
			(xy 280.700262 -77.346298) (xy 280.721526 -77.346298) (xy 280.731468 -77.342492) (xy 280.774072 -77.324272)
			(xy 280.862239 -77.295754) (xy 280.952894 -77.276561) (xy 281.045054 -77.2669) (xy 281.091386 -77.266292)
			(xy 281.091894 -77.266292) (xy 281.134243 -77.26678) (xy 281.218559 -77.27483) (xy 281.301727 -77.290859)
			(xy 281.382995 -77.314721) (xy 281.461627 -77.3462) (xy 281.536911 -77.385011) (xy 281.608164 -77.430802)
			(xy 281.674742 -77.48316) (xy 281.707292 -77.514196) (xy 286.663892 -77.514196) (xy 286.664378 -77.486945)
			(xy 286.672134 -77.432997) (xy 286.687489 -77.380702) (xy 286.710131 -77.331125) (xy 286.739597 -77.285275)
			(xy 286.775288 -77.244084) (xy 286.816479 -77.208393) (xy 286.862329 -77.178927) (xy 286.911906 -77.156285)
			(xy 286.964201 -77.14093) (xy 287.018149 -77.133174) (xy 287.072651 -77.133174) (xy 287.126599 -77.14093)
			(xy 287.178894 -77.156285) (xy 287.228471 -77.178927) (xy 287.274321 -77.208393) (xy 287.315512 -77.244084)
			(xy 287.351203 -77.285275) (xy 287.380669 -77.331125) (xy 287.403311 -77.380702) (xy 287.418666 -77.432997)
			(xy 287.426422 -77.486945) (xy 287.426908 -77.514196) (xy 287.426385 -77.542095) (xy 287.41822 -77.597293)
			(xy 287.402108 -77.650715) (xy 287.378392 -77.701222) (xy 287.363408 -77.724762) (xy 287.363154 -77.725016)
			(xy 287.358384 -77.733188) (xy 287.354466 -77.751683) (xy 287.355534 -77.761084) (xy 287.366456 -77.828648)
			(xy 287.368313 -77.837872) (xy 287.377698 -77.854162) (xy 287.384744 -77.860398) (xy 287.385252 -77.860652)
			(xy 287.385506 -77.860652) (xy 287.407795 -77.87888) (xy 287.447161 -77.920899) (xy 287.479773 -77.968352)
			(xy 287.50489 -78.020163) (xy 287.521943 -78.075158) (xy 287.530546 -78.13209) (xy 287.531048 -78.16088)
			(xy 287.530562 -78.188131) (xy 287.522806 -78.242079) (xy 287.507451 -78.294374) (xy 287.484809 -78.343951)
			(xy 287.455343 -78.389801) (xy 287.419652 -78.430992) (xy 287.378461 -78.466683) (xy 287.332611 -78.496149)
			(xy 287.283034 -78.518791) (xy 287.230739 -78.534146) (xy 287.176791 -78.541902) (xy 287.122289 -78.541902)
			(xy 287.068341 -78.534146) (xy 287.016046 -78.518791) (xy 286.966469 -78.496149) (xy 286.920619 -78.466683)
			(xy 286.879428 -78.430992) (xy 286.843737 -78.389801) (xy 286.814271 -78.343951) (xy 286.791629 -78.294374)
			(xy 286.776274 -78.242079) (xy 286.768518 -78.188131) (xy 286.768032 -78.16088) (xy 286.768554 -78.132981)
			(xy 286.776721 -78.077783) (xy 286.792833 -78.024362) (xy 286.816549 -77.973854) (xy 286.831532 -77.950314)
			(xy 286.831786 -77.95006) (xy 286.836571 -77.941895) (xy 286.840478 -77.923395) (xy 286.839406 -77.913992)
			(xy 286.828484 -77.846428) (xy 286.82671 -77.837177) (xy 286.817295 -77.820872) (xy 286.810196 -77.814678)
			(xy 286.809688 -77.814424) (xy 286.809434 -77.814424) (xy 286.787141 -77.796199) (xy 286.747774 -77.754181)
			(xy 286.715162 -77.706727) (xy 286.690045 -77.654915) (xy 286.672993 -77.599919) (xy 286.664392 -77.542986)
			(xy 286.663892 -77.514196) (xy 281.707292 -77.514196) (xy 281.736042 -77.541608) (xy 281.791508 -77.605619)
			(xy 281.840638 -77.674613) (xy 281.882988 -77.747964) (xy 281.918173 -77.825009) (xy 281.945875 -77.905049)
			(xy 281.965844 -77.98736) (xy 281.977898 -78.071197) (xy 281.981928 -78.1558) (xy 281.977898 -78.240403)
			(xy 281.965844 -78.32424) (xy 281.945875 -78.406551) (xy 281.918173 -78.486591) (xy 281.882988 -78.563636)
			(xy 281.840638 -78.636987) (xy 281.791508 -78.705981) (xy 281.736042 -78.769992) (xy 281.674742 -78.82844)
			(xy 281.608164 -78.880798) (xy 281.536911 -78.926589) (xy 281.461627 -78.9654) (xy 281.382995 -78.996879)
			(xy 281.301727 -79.020741) (xy 281.218559 -79.03677) (xy 281.134243 -79.04482) (xy 281.091894 -79.045308)
			(xy 281.091386 -79.045308) (xy 281.045054 -79.044704) (xy 280.952896 -79.035032) (xy 280.862242 -79.015836)
			(xy 280.774073 -78.987323) (xy 280.731468 -78.969108) (xy 280.721526 -78.965302) (xy 280.700262 -78.965302)
			(xy 280.69032 -78.969108) (xy 280.647718 -78.987332) (xy 280.55955 -79.015849) (xy 280.468894 -79.035041)
			(xy 280.376734 -79.0447) (xy 280.330402 -79.045308) (xy 280.329894 -79.045308) (xy 280.287546 -79.044804)
			(xy 280.203233 -79.036753) (xy 280.120067 -79.020723) (xy 280.038801 -78.996861) (xy 279.960171 -78.965382)
			(xy 279.88489 -78.926571) (xy 279.813639 -78.880781) (xy 279.747063 -78.828424) (xy 279.685766 -78.769977)
			(xy 279.630301 -78.705967) (xy 279.581173 -78.636975) (xy 279.538825 -78.563626) (xy 279.50364 -78.486583)
			(xy 279.475939 -78.406544) (xy 279.455971 -78.324235) (xy 279.443918 -78.240401) (xy 279.439887 -78.1558)
			(xy 267.250926 -78.1558) (xy 267.250926 -79.461106) (xy 289.584382 -79.461106) (xy 289.588453 -79.405484)
			(xy 289.600579 -79.351047) (xy 289.620502 -79.298956) (xy 289.647798 -79.250321) (xy 289.681884 -79.206178)
			(xy 289.722033 -79.167469) (xy 289.767391 -79.135018) (xy 289.816991 -79.109517) (xy 289.869775 -79.09151)
			(xy 289.924618 -79.08138) (xy 289.980352 -79.079343) (xy 290.035789 -79.085443) (xy 290.089746 -79.099549)
			(xy 290.141075 -79.121361) (xy 290.188681 -79.150415) (xy 290.231549 -79.18609) (xy 290.268766 -79.227627)
			(xy 290.290647 -79.2607) (xy 293.699182 -79.2607) (xy 293.703253 -79.205078) (xy 293.715379 -79.150641)
			(xy 293.735302 -79.09855) (xy 293.762598 -79.049915) (xy 293.796684 -79.005772) (xy 293.836833 -78.967063)
			(xy 293.882191 -78.934612) (xy 293.931791 -78.909111) (xy 293.984575 -78.891104) (xy 294.039418 -78.880974)
			(xy 294.095152 -78.878937) (xy 294.150589 -78.885037) (xy 294.204546 -78.899143) (xy 294.255875 -78.920955)
			(xy 294.303481 -78.950009) (xy 294.346349 -78.985684) (xy 294.383566 -79.027221) (xy 294.414339 -79.073734)
			(xy 294.438011 -79.124231) (xy 294.454079 -79.177638) (xy 294.462199 -79.232814) (xy 294.462708 -79.2607)
			(xy 294.462199 -79.288586) (xy 294.454079 -79.343762) (xy 294.438011 -79.397169) (xy 294.414339 -79.447666)
			(xy 294.383566 -79.494179) (xy 294.346349 -79.535716) (xy 294.303481 -79.571391) (xy 294.255875 -79.600445)
			(xy 294.204546 -79.622257) (xy 294.150589 -79.636363) (xy 294.095152 -79.642463) (xy 294.039418 -79.640426)
			(xy 293.984575 -79.630296) (xy 293.931791 -79.612289) (xy 293.882191 -79.586788) (xy 293.836833 -79.554337)
			(xy 293.796684 -79.515628) (xy 293.762598 -79.471485) (xy 293.735302 -79.42285) (xy 293.715379 -79.370759)
			(xy 293.703253 -79.316322) (xy 293.699182 -79.2607) (xy 290.290647 -79.2607) (xy 290.299539 -79.27414)
			(xy 290.323211 -79.324637) (xy 290.339279 -79.378044) (xy 290.347399 -79.43322) (xy 290.347908 -79.461106)
			(xy 290.347399 -79.488992) (xy 290.339279 -79.544168) (xy 290.323211 -79.597575) (xy 290.299539 -79.648072)
			(xy 290.268766 -79.694585) (xy 290.231549 -79.736122) (xy 290.188681 -79.771797) (xy 290.141075 -79.800851)
			(xy 290.089746 -79.822663) (xy 290.035789 -79.836769) (xy 289.980352 -79.842869) (xy 289.924618 -79.840832)
			(xy 289.869775 -79.830702) (xy 289.816991 -79.812695) (xy 289.767391 -79.787194) (xy 289.722033 -79.754743)
			(xy 289.681884 -79.716034) (xy 289.647798 -79.671891) (xy 289.620502 -79.623256) (xy 289.600579 -79.571165)
			(xy 289.588453 -79.516728) (xy 289.584382 -79.461106) (xy 267.250926 -79.461106) (xy 267.250926 -79.47406)
			(xy 267.251361 -79.484125) (xy 267.259093 -79.502711) (xy 267.265912 -79.510128) (xy 269.186406 -81.430622)
			(xy 269.193801 -81.437476) (xy 269.2124 -81.44522) (xy 269.222474 -81.445608) (xy 270.148304 -81.445608)
			(xy 270.155416 -81.443576) (xy 270.196548 -81.431836) (xy 270.280491 -81.415371) (xy 270.365629 -81.407051)
			(xy 270.4084 -81.406492) (xy 270.45117 -81.407066) (xy 270.536304 -81.4154) (xy 270.620247 -81.431858)
			(xy 270.661384 -81.443576) (xy 270.668496 -81.445608) (xy 272.180304 -81.445608) (xy 272.187416 -81.443576)
			(xy 272.228548 -81.431836) (xy 272.312491 -81.415371) (xy 272.397629 -81.407051) (xy 272.4404 -81.406492)
			(xy 272.48317 -81.407066) (xy 272.568304 -81.4154) (xy 272.652247 -81.431858) (xy 272.693384 -81.443576)
			(xy 272.700496 -81.445608) (xy 274.212304 -81.445608) (xy 274.219416 -81.443576) (xy 274.260548 -81.431836)
			(xy 274.344491 -81.415371) (xy 274.429629 -81.407051) (xy 274.4724 -81.406492) (xy 274.51517 -81.407066)
			(xy 274.600304 -81.4154) (xy 274.684247 -81.431858) (xy 274.725384 -81.443576) (xy 274.732496 -81.445608)
			(xy 275.302726 -81.445608) (xy 275.312794 -81.446036) (xy 275.331391 -81.453758) (xy 275.338794 -81.460594)
			(xy 276.464014 -82.585814) (xy 276.471409 -82.592668) (xy 276.490008 -82.60041) (xy 276.500082 -82.6008)
		)
		(stroke
			(width 0)
			(type solid)
		)
		(fill yes)
		(layer "In7.Cu")
		(net "GND")
	)
	(gr_poly
		(pts
			(xy 460.887318 -109.093) (xy 460.897195 -109.09254) (xy 460.915494 -109.085097) (xy 460.922878 -109.078522)
			(xy 460.923132 -109.078268) (xy 467.560914 -102.440486) (xy 467.561422 -102.439978) (xy 467.568012 -102.4326)
			(xy 467.575479 -102.414301) (xy 467.5759 -102.404418) (xy 467.5759 -90.889582) (xy 467.576327 -90.879513)
			(xy 467.584046 -90.860914) (xy 467.590886 -90.853514) (xy 469.504014 -88.940386) (xy 469.511634 -88.917526)
			(xy 469.509856 -88.905588) (xy 469.502849 -88.854697) (xy 469.495348 -88.752233) (xy 469.49487 -88.700864)
			(xy 469.49487 -88.700102) (xy 469.495377 -88.645998) (xy 469.503671 -88.538108) (xy 469.520209 -88.431172)
			(xy 469.544895 -88.325817) (xy 469.577583 -88.222665) (xy 469.618081 -88.122321) (xy 469.666151 -88.025377)
			(xy 469.72151 -87.932402) (xy 469.783833 -87.843943) (xy 469.852751 -87.760522) (xy 469.927861 -87.682628)
			(xy 470.00872 -87.61072) (xy 470.094853 -87.545221) (xy 470.14003 -87.515446) (xy 470.151206 -87.508334)
			(xy 470.163398 -87.485982) (xy 470.163398 -87.374222) (xy 470.151206 -87.35187) (xy 470.14003 -87.344758)
			(xy 470.098405 -87.317363) (xy 470.018714 -87.257522) (xy 469.943446 -87.192203) (xy 469.872978 -87.121734)
			(xy 469.807661 -87.046465) (xy 469.747821 -86.966772) (xy 469.720422 -86.92515) (xy 469.71331 -86.913974)
			(xy 469.690958 -86.901782) (xy 469.579198 -86.901782) (xy 469.556846 -86.913974) (xy 469.549734 -86.92515)
			(xy 469.519956 -86.970324) (xy 469.454457 -87.056457) (xy 469.38255 -87.137316) (xy 469.304656 -87.212426)
			(xy 469.221235 -87.281344) (xy 469.132777 -87.343666) (xy 469.039802 -87.399024) (xy 468.942858 -87.447093)
			(xy 468.842514 -87.487591) (xy 468.739362 -87.520278) (xy 468.634007 -87.544963) (xy 468.527071 -87.5615)
			(xy 468.419182 -87.569792) (xy 468.365078 -87.57031) (xy 468.312331 -87.569816) (xy 468.207131 -87.561931)
			(xy 468.102815 -87.546206) (xy 467.999966 -87.52273) (xy 467.899158 -87.491634) (xy 467.800957 -87.453091)
			(xy 467.70591 -87.407318) (xy 467.614549 -87.35457) (xy 467.527386 -87.295142) (xy 467.444907 -87.229366)
			(xy 467.367575 -87.157611) (xy 467.295821 -87.080277) (xy 467.230047 -86.997798) (xy 467.17062 -86.910634)
			(xy 467.117873 -86.819273) (xy 467.072101 -86.724225) (xy 467.033559 -86.626023) (xy 467.002465 -86.525215)
			(xy 466.97899 -86.422365) (xy 466.963267 -86.318049) (xy 466.955383 -86.212849) (xy 466.95487 -86.160102)
			(xy 466.955371 -86.106832) (xy 466.963411 -86.000595) (xy 466.979447 -85.895268) (xy 467.003387 -85.791452)
			(xy 467.035093 -85.689738) (xy 467.074386 -85.590708) (xy 467.12104 -85.494926) (xy 467.174791 -85.402938)
			(xy 467.235331 -85.315269) (xy 467.302315 -85.232419) (xy 467.37536 -85.154861) (xy 467.454051 -85.083037)
			(xy 467.537938 -85.017357) (xy 467.626543 -84.958196) (xy 467.719361 -84.90589) (xy 467.815861 -84.860739)
			(xy 467.915494 -84.823) (xy 468.01769 -84.792888) (xy 468.121868 -84.770575) (xy 468.174578 -84.762848)
			(xy 468.18296 -84.761578) (xy 468.197692 -84.754212) (xy 468.229188 -84.722716) (xy 468.236554 -84.707984)
			(xy 468.237824 -84.699602) (xy 468.245824 -84.644929) (xy 468.26928 -84.536941) (xy 468.301116 -84.431121)
			(xy 468.341135 -84.328116) (xy 468.389092 -84.228559) (xy 468.444694 -84.133061) (xy 468.507599 -84.042207)
			(xy 468.577421 -83.956554) (xy 468.653732 -83.876629) (xy 468.736064 -83.80292) (xy 468.823912 -83.735881)
			(xy 468.87003 -83.705446) (xy 468.880952 -83.698334) (xy 468.893398 -83.675728) (xy 468.893398 -83.564476)
			(xy 468.880952 -83.54187) (xy 468.87003 -83.534758) (xy 468.823903 -83.504333) (xy 468.736043 -83.437303)
			(xy 468.653699 -83.363602) (xy 468.577378 -83.28368) (xy 468.507547 -83.198029) (xy 468.444636 -83.107174)
			(xy 468.389031 -83.011674) (xy 468.341072 -82.912113) (xy 468.301054 -82.809104) (xy 468.269223 -82.703277)
			(xy 468.245774 -82.595284) (xy 468.237824 -82.540602) (xy 468.236554 -82.53222) (xy 468.229188 -82.517488)
			(xy 468.197692 -82.485992) (xy 468.18296 -82.478626) (xy 468.174578 -82.477356) (xy 468.121864 -82.469663)
			(xy 468.017689 -82.447343) (xy 467.915495 -82.417225) (xy 467.815866 -82.379481) (xy 467.719369 -82.334325)
			(xy 467.626555 -82.282015) (xy 467.537954 -82.22285) (xy 467.45407 -82.157167) (xy 467.375383 -82.085341)
			(xy 467.302341 -82.007781) (xy 467.235361 -81.92493) (xy 467.174824 -81.837261) (xy 467.121076 -81.745272)
			(xy 467.074424 -81.64949) (xy 467.035134 -81.55046) (xy 467.003429 -81.448747) (xy 466.979491 -81.344932)
			(xy 466.963456 -81.239606) (xy 466.955415 -81.13337) (xy 466.955415 -81.02683) (xy 466.963456 -80.920595)
			(xy 466.979491 -80.815269) (xy 467.003429 -80.711453) (xy 467.035133 -80.609741) (xy 467.074424 -80.510711)
			(xy 467.121076 -80.414928) (xy 467.174824 -80.32294) (xy 467.23536 -80.23527) (xy 467.302341 -80.152419)
			(xy 467.375383 -80.074859) (xy 467.45407 -80.003033) (xy 467.537953 -79.93735) (xy 467.626555 -79.878185)
			(xy 467.719368 -79.825875) (xy 467.815865 -79.780719) (xy 467.915495 -79.742975) (xy 468.017688 -79.712857)
			(xy 468.121864 -79.690537) (xy 468.174578 -79.682848) (xy 468.18296 -79.681578) (xy 468.197692 -79.674212)
			(xy 468.229188 -79.642716) (xy 468.236554 -79.627984) (xy 468.237824 -79.619602) (xy 468.243345 -79.581231)
			(xy 468.258083 -79.505114) (xy 468.267288 -79.467456) (xy 468.27059 -79.454248) (xy 468.263478 -79.428594)
			(xy 467.781894 -78.94701) (xy 467.775544 -78.941676) (xy 467.77529 -78.941422) (xy 467.768704 -78.937096)
			(xy 467.7537 -78.932312) (xy 467.745826 -78.932024) (xy 456.648566 -78.932024) (xy 456.640375 -78.932339)
			(xy 456.624836 -78.937531) (xy 456.618086 -78.942184) (xy 456.585031 -78.966533) (xy 456.515211 -79.009732)
			(xy 456.441705 -79.046309) (xy 456.365139 -79.075953) (xy 456.286167 -79.098411) (xy 456.20546 -79.113492)
			(xy 456.123706 -79.121067) (xy 456.082654 -79.121508) (xy 456.0824 -79.121508) (xy 456.038537 -79.12098)
			(xy 455.951239 -79.112342) (xy 455.865214 -79.095151) (xy 455.781301 -79.069573) (xy 455.700314 -79.035856)
			(xy 455.62304 -78.99433) (xy 455.550231 -78.945397) (xy 455.482593 -78.889532) (xy 455.420785 -78.827279)
			(xy 455.365407 -78.759243) (xy 455.34072 -78.722982) (xy 455.337164 -78.717648) (xy 455.32802 -78.70952)
			(xy 455.30262 -78.69555) (xy 455.296955 -78.692615) (xy 455.284613 -78.6894) (xy 455.278236 -78.6892)
			(xy 452.064882 -78.6892) (xy 452.054813 -78.689627) (xy 452.036214 -78.697346) (xy 452.028814 -78.704186)
			(xy 451.017386 -79.715614) (xy 451.009991 -79.722468) (xy 450.991392 -79.73021) (xy 450.981318 -79.7306)
			(xy 450.617082 -79.7306) (xy 450.607013 -79.730173) (xy 450.588414 -79.722454) (xy 450.581014 -79.715614)
			(xy 450.331586 -79.466186) (xy 450.324732 -79.458791) (xy 450.31699 -79.440192) (xy 450.3166 -79.430118)
			(xy 450.3166 -78.532482) (xy 450.316173 -78.522413) (xy 450.308454 -78.503814) (xy 450.301614 -78.496414)
			(xy 449.90004 -78.09484) (xy 449.892634 -78.088145) (xy 449.874198 -78.080542) (xy 449.864226 -78.080108)
			(xy 438.551828 -78.080108) (xy 438.529984 -78.0796) (xy 438.044082 -78.0796) (xy 438.034013 -78.079173)
			(xy 438.015414 -78.071454) (xy 438.008014 -78.064614) (xy 436.539386 -76.595986) (xy 436.532532 -76.588591)
			(xy 436.52479 -76.569992) (xy 436.5244 -76.559918) (xy 436.5244 -56.663082) (xy 436.523973 -56.653013)
			(xy 436.516254 -56.634414) (xy 436.509414 -56.627014) (xy 432.85029 -52.96789) (xy 432.84371 -52.961759)
			(xy 432.827425 -52.954153) (xy 432.809516 -52.952632) (xy 432.80076 -52.954682) (xy 432.786536 -52.958746)
			(xy 432.780948 -52.962048) (xy 432.746601 -52.98192) (xy 432.675014 -53.016171) (xy 432.600658 -53.043903)
			(xy 432.524126 -53.064896) (xy 432.446027 -53.078982) (xy 432.366983 -53.086049) (xy 432.327304 -53.086508)
			(xy 432.32705 -53.086508) (xy 432.285949 -53.086031) (xy 432.204098 -53.078442) (xy 432.123296 -53.063334)
			(xy 432.044233 -53.040834) (xy 431.967584 -53.011136) (xy 431.894001 -52.974493) (xy 431.824113 -52.931216)
			(xy 431.758516 -52.881676) (xy 431.697769 -52.826295) (xy 431.642392 -52.765546) (xy 431.592855 -52.699946)
			(xy 431.549583 -52.630056) (xy 431.512944 -52.556471) (xy 431.48325 -52.479819) (xy 431.460755 -52.400755)
			(xy 431.445651 -52.319952) (xy 431.438067 -52.238101) (xy 431.437542 -52.197) (xy 431.437542 -52.196746)
			(xy 431.437989 -52.156524) (xy 431.445253 -52.07641) (xy 431.459726 -51.99728) (xy 431.481289 -51.91978)
			(xy 431.509766 -51.844547) (xy 431.544924 -51.772193) (xy 431.565304 -51.737514) (xy 431.574448 -51.722274)
			(xy 431.57013 -51.68773) (xy 428.149512 -48.267112) (xy 428.143519 -48.261505) (xy 428.128883 -48.254104)
			(xy 428.12081 -48.252634) (xy 428.120048 -48.252634) (xy 428.078996 -48.246674) (xy 427.998146 -48.228091)
			(xy 427.919376 -48.202061) (xy 427.843374 -48.168808) (xy 427.770797 -48.128623) (xy 427.702278 -48.081855)
			(xy 427.638412 -48.028909) (xy 427.579753 -47.970247) (xy 427.526811 -47.906377) (xy 427.480047 -47.837855)
			(xy 427.439867 -47.765276) (xy 427.406619 -47.689271) (xy 427.380594 -47.6105) (xy 427.362016 -47.529648)
			(xy 427.356016 -47.488602) (xy 427.356016 -47.48784) (xy 427.354523 -47.479772) (xy 427.347143 -47.465129)
			(xy 427.341538 -47.459138) (xy 426.404786 -46.522386) (xy 426.397932 -46.514991) (xy 426.39019 -46.496392)
			(xy 426.3898 -46.486318) (xy 426.3898 -46.15688) (xy 426.389259 -46.146894) (xy 426.38154 -46.128467)
			(xy 426.374814 -46.121066) (xy 426.343693 -46.088975) (xy 426.289164 -46.018137) (xy 426.266102 -45.979842)
			(xy 426.2628 -45.974) (xy 424.448986 -44.160186) (xy 424.442132 -44.152791) (xy 424.43439 -44.134192)
			(xy 424.434 -44.124118) (xy 424.434 -37.105082) (xy 424.434427 -37.095013) (xy 424.442146 -37.076414)
			(xy 424.448986 -37.069014) (xy 425.806108 -35.711892) (xy 425.808394 -35.706304) (xy 425.905676 -35.612324)
			(xy 425.906438 -35.611562) (xy 426.15866 -35.35934) (xy 426.165355 -35.351934) (xy 426.172958 -35.333498)
			(xy 426.173392 -35.323526) (xy 426.173392 -30.030674) (xy 426.172913 -30.020709) (xy 426.165335 -30.002275)
			(xy 426.15866 -29.99486) (xy 424.067986 -27.904186) (xy 424.060874 -27.89682) (xy 424.042078 -27.8892)
			(xy 417.03625 -27.8892) (xy 417.026184 -27.888768) (xy 417.007593 -27.88104) (xy 417.000182 -27.874214)
			(xy 416.452304 -27.326336) (xy 416.445981 -27.320452) (xy 416.430442 -27.312936) (xy 416.41329 -27.311001)
			(xy 416.404806 -27.31262) (xy 416.404044 -27.312874) (xy 416.403536 -27.312874) (xy 416.368307 -27.32132)
			(xy 416.296828 -27.333152) (xy 416.224623 -27.339132) (xy 416.188398 -27.339544) (xy 416.147295 -27.339069)
			(xy 416.06544 -27.331484) (xy 415.984633 -27.316379) (xy 415.905565 -27.293883) (xy 415.82891 -27.264187)
			(xy 415.755322 -27.227546) (xy 415.685428 -27.184271) (xy 415.619826 -27.134731) (xy 415.559074 -27.07935)
			(xy 415.50369 -27.018601) (xy 415.454149 -26.953) (xy 415.410871 -26.883108) (xy 415.374227 -26.809521)
			(xy 415.344528 -26.732867) (xy 415.322029 -26.6538) (xy 415.30692 -26.572994) (xy 415.299332 -26.491139)
			(xy 415.29889 -26.450036) (xy 415.299301 -26.413811) (xy 415.305282 -26.341607) (xy 415.317119 -26.270129)
			(xy 415.32556 -26.234898) (xy 415.32556 -26.23439) (xy 415.325814 -26.233628) (xy 415.327423 -26.225143)
			(xy 415.325497 -26.207991) (xy 415.317981 -26.192453) (xy 415.312098 -26.18613) (xy 414.439608 -25.31364)
			(xy 414.432201 -25.30695) (xy 414.413764 -25.299359) (xy 414.403794 -25.298908) (xy 413.466026 -25.298908)
			(xy 413.456065 -25.299396) (xy 413.437643 -25.306986) (xy 413.430212 -25.31364) (xy 412.415736 -26.328116)
			(xy 412.408924 -26.33546) (xy 412.401192 -26.353923) (xy 412.40075 -26.36393) (xy 412.40075 -26.47696)
			(xy 413.097472 -26.47696) (xy 413.097976 -26.434612) (xy 413.106027 -26.350298) (xy 413.122056 -26.267132)
			(xy 413.145917 -26.185865) (xy 413.177396 -26.107235) (xy 413.216207 -26.031954) (xy 413.261997 -25.960702)
			(xy 413.314353 -25.894126) (xy 413.372801 -25.832828) (xy 413.436811 -25.777363) (xy 413.505803 -25.728234)
			(xy 413.579153 -25.685885) (xy 413.656196 -25.650701) (xy 413.736235 -25.622999) (xy 413.818544 -25.603031)
			(xy 413.902379 -25.590978) (xy 413.98698 -25.586948) (xy 414.071581 -25.590978) (xy 414.155416 -25.603031)
			(xy 414.237725 -25.622999) (xy 414.317764 -25.650701) (xy 414.394807 -25.685885) (xy 414.468157 -25.728234)
			(xy 414.537149 -25.777363) (xy 414.601159 -25.832828) (xy 414.659607 -25.894126) (xy 414.711963 -25.960702)
			(xy 414.757753 -26.031954) (xy 414.796564 -26.107235) (xy 414.828043 -26.185865) (xy 414.851904 -26.267132)
			(xy 414.867933 -26.350298) (xy 414.875984 -26.434612) (xy 414.876488 -26.47696) (xy 414.876488 -26.477468)
			(xy 414.875898 -26.52298) (xy 414.86657 -26.613525) (xy 414.848047 -26.702645) (xy 414.834832 -26.7462)
			(xy 414.834832 -26.746454) (xy 414.832316 -26.755969) (xy 414.833871 -26.775567) (xy 414.83788 -26.784554)
			(xy 414.874456 -26.856944) (xy 414.889188 -26.869898) (xy 414.89884 -26.8732) (xy 414.938982 -26.887384)
			(xy 415.016635 -26.922297) (xy 415.090598 -26.964469) (xy 415.160193 -27.013515) (xy 415.224784 -27.068984)
			(xy 415.283781 -27.130371) (xy 415.336643 -27.197113) (xy 415.382888 -27.268601) (xy 415.422091 -27.344179)
			(xy 415.453894 -27.423157) (xy 415.478006 -27.504812) (xy 415.494208 -27.588397) (xy 415.50235 -27.673148)
			(xy 415.502852 -27.715718) (xy 415.502329 -27.758789) (xy 415.494012 -27.84453) (xy 415.47744 -27.929063)
			(xy 415.452767 -28.011597) (xy 415.420225 -28.091357) (xy 415.38012 -28.167594) (xy 415.332827 -28.239593)
			(xy 415.27879 -28.30668) (xy 415.218517 -28.368224) (xy 415.152572 -28.423648) (xy 415.081574 -28.472432)
			(xy 415.044128 -28.49372) (xy 415.043874 -28.493974) (xy 415.043112 -28.494482) (xy 415.038543 -28.49727)
			(xy 415.030603 -28.504445) (xy 415.027364 -28.508706) (xy 415.024029 -28.513528) (xy 415.01941 -28.524301)
			(xy 415.01822 -28.530042) (xy 415.005266 -28.608528) (xy 415.003953 -28.619846) (xy 415.010154 -28.64174)
			(xy 415.017204 -28.650692) (xy 415.017458 -28.650946) (xy 415.017458 -28.6512) (xy 415.044333 -28.681769)
			(xy 415.093021 -28.747003) (xy 415.135539 -28.816416) (xy 415.171532 -28.889426) (xy 415.200698 -28.965421)
			(xy 415.222792 -29.043766) (xy 415.23763 -29.123802) (xy 415.245086 -29.20486) (xy 415.24555 -29.24556)
			(xy 415.245046 -29.287908) (xy 415.236995 -29.372222) (xy 415.220966 -29.455388) (xy 415.197105 -29.536655)
			(xy 415.165626 -29.615285) (xy 415.126815 -29.690566) (xy 415.081025 -29.761818) (xy 415.028669 -29.828394)
			(xy 414.970221 -29.889692) (xy 414.906211 -29.945157) (xy 414.837219 -29.994286) (xy 414.763869 -30.036635)
			(xy 414.686826 -30.071819) (xy 414.606787 -30.099521) (xy 414.524478 -30.119489) (xy 414.440643 -30.131542)
			(xy 414.356042 -30.135573) (xy 414.271441 -30.131542) (xy 414.187606 -30.119489) (xy 414.105297 -30.099521)
			(xy 414.025258 -30.071819) (xy 413.948215 -30.036635) (xy 413.874865 -29.994286) (xy 413.805873 -29.945157)
			(xy 413.741863 -29.889692) (xy 413.683415 -29.828394) (xy 413.631059 -29.761818) (xy 413.585269 -29.690566)
			(xy 413.546458 -29.615285) (xy 413.514979 -29.536655) (xy 413.491118 -29.455388) (xy 413.475089 -29.372222)
			(xy 413.467038 -29.287908) (xy 413.466534 -29.24556) (xy 413.467046 -29.202488) (xy 413.475365 -29.116748)
			(xy 413.491939 -29.032214) (xy 413.516613 -28.949681) (xy 413.549156 -28.869921) (xy 413.589263 -28.793684)
			(xy 413.636557 -28.721685) (xy 413.690594 -28.654598) (xy 413.750868 -28.593054) (xy 413.816814 -28.53763)
			(xy 413.887811 -28.488846) (xy 413.925258 -28.467558) (xy 413.925512 -28.467304) (xy 413.926274 -28.466796)
			(xy 413.930844 -28.46401) (xy 413.938783 -28.456834) (xy 413.942022 -28.452572) (xy 413.945362 -28.447753)
			(xy 413.949978 -28.436978) (xy 413.951166 -28.431236) (xy 413.96412 -28.35275) (xy 413.96545 -28.341432)
			(xy 413.959238 -28.319536) (xy 413.952182 -28.310586) (xy 413.951928 -28.310332) (xy 413.951928 -28.310078)
			(xy 413.92504 -28.27952) (xy 413.876353 -28.214284) (xy 413.833836 -28.14487) (xy 413.797845 -28.071858)
			(xy 413.768681 -27.995861) (xy 413.746589 -27.917515) (xy 413.731753 -27.837477) (xy 413.724299 -27.756418)
			(xy 413.723836 -27.715718) (xy 413.723836 -27.71521) (xy 413.724419 -27.669698) (xy 413.73375 -27.579153)
			(xy 413.752275 -27.490033) (xy 413.765492 -27.446478) (xy 413.765492 -27.446224) (xy 413.768018 -27.436711)
			(xy 413.766456 -27.417111) (xy 413.762444 -27.408124) (xy 413.725868 -27.335734) (xy 413.711136 -27.32278)
			(xy 413.701484 -27.319478) (xy 413.661319 -27.305358) (xy 413.583666 -27.270438) (xy 413.509704 -27.228258)
			(xy 413.44011 -27.179206) (xy 413.37552 -27.12373) (xy 413.316525 -27.062338) (xy 413.263665 -26.99559)
			(xy 413.217424 -26.924098) (xy 413.178223 -26.848515) (xy 413.146422 -26.769533) (xy 413.122312 -26.687874)
			(xy 413.106113 -26.604286) (xy 413.097973 -26.519532) (xy 413.097472 -26.47696) (xy 412.40075 -26.47696)
			(xy 412.40075 -27.568906) (xy 412.401207 -27.578785) (xy 412.408641 -27.597091) (xy 412.415228 -27.604466)
			(xy 412.415482 -27.60472) (xy 412.999936 -28.189174) (xy 413.006778 -28.196574) (xy 413.014495 -28.215172)
			(xy 413.014922 -28.225242) (xy 413.014922 -28.405328) (xy 413.015057 -28.410219) (xy 413.016971 -28.419813)
			(xy 413.018732 -28.424378) (xy 413.102298 -28.630626) (xy 413.10405 -28.635194) (xy 413.105962 -28.644786)
			(xy 413.106108 -28.649676) (xy 413.106108 -30.408372) (xy 413.105674 -30.442833) (xy 413.098742 -30.511407)
			(xy 413.084966 -30.578938) (xy 413.064485 -30.644748) (xy 413.037504 -30.70817) (xy 413.021272 -30.738572)
			(xy 413.018335 -30.744236) (xy 413.015116 -30.756579) (xy 413.014922 -30.762956) (xy 413.014922 -31.234126)
			(xy 416.16122 -31.234126) (xy 416.161677 -31.193022) (xy 416.16926 -31.111166) (xy 416.184364 -31.030358)
			(xy 416.206859 -30.951289) (xy 416.236555 -30.874633) (xy 416.273197 -30.801043) (xy 416.316473 -30.731149)
			(xy 416.366013 -30.665546) (xy 416.421396 -30.604794) (xy 416.482148 -30.549412) (xy 416.547751 -30.499872)
			(xy 416.617645 -30.456596) (xy 416.691234 -30.419954) (xy 416.767891 -30.390259) (xy 416.84696 -30.367763)
			(xy 416.927768 -30.35266) (xy 417.009624 -30.345077) (xy 417.050728 -30.344618) (xy 417.094383 -30.345135)
			(xy 417.181274 -30.353682) (xy 417.266909 -30.3707) (xy 417.350465 -30.396026) (xy 417.431138 -30.429415)
			(xy 417.508152 -30.470548) (xy 417.580766 -30.519027) (xy 417.614862 -30.546294) (xy 417.623752 -30.55366)
			(xy 417.645596 -30.559248) (xy 417.74491 -30.53969) (xy 417.763198 -30.526228) (xy 417.768532 -30.516322)
			(xy 417.789719 -30.4784) (xy 417.838378 -30.406435) (xy 417.893819 -30.339555) (xy 417.955514 -30.278396)
			(xy 418.022876 -30.223542) (xy 418.095263 -30.175513) (xy 418.171987 -30.134768) (xy 418.252316 -30.101694)
			(xy 418.335486 -30.076607) (xy 418.420705 -30.059745) (xy 418.507162 -30.051269) (xy 418.550598 -30.05074)
			(xy 418.5961 -30.051333) (xy 418.686628 -30.060621) (xy 418.775736 -30.079101) (xy 418.862492 -30.10658)
			(xy 418.94599 -30.14277) (xy 418.985954 -30.164532) (xy 418.996045 -30.169493) (xy 419.018447 -30.171076)
			(xy 419.029134 -30.16758) (xy 419.067741 -30.153083) (xy 419.147045 -30.130439) (xy 419.228105 -30.115234)
			(xy 419.310223 -30.107596) (xy 419.35146 -30.107128) (xy 419.392564 -30.10759) (xy 419.47442 -30.115172)
			(xy 419.555228 -30.130275) (xy 419.634298 -30.15277) (xy 419.710954 -30.182464) (xy 419.784544 -30.219106)
			(xy 419.854438 -30.262381) (xy 419.920042 -30.311921) (xy 419.980794 -30.367304) (xy 420.036176 -30.428055)
			(xy 420.085717 -30.493658) (xy 420.128992 -30.563553) (xy 420.165634 -30.637142) (xy 420.195329 -30.713798)
			(xy 420.217824 -30.792868) (xy 420.232927 -30.873676) (xy 420.240509 -30.955532) (xy 420.240968 -30.996636)
			(xy 420.24037 -31.043571) (xy 420.230478 -31.136919) (xy 420.210809 -31.228705) (xy 420.196772 -31.273496)
			(xy 420.193876 -31.283972) (xy 420.196242 -31.305556) (xy 420.201344 -31.315152) (xy 420.224528 -31.355392)
			(xy 420.263342 -31.439766) (xy 420.278814 -31.483554) (xy 420.278814 -31.483808) (xy 420.282737 -31.493775)
			(xy 420.297339 -31.509424) (xy 420.307008 -31.514034) (xy 420.38651 -31.54807) (xy 420.407846 -31.547816)
			(xy 420.417752 -31.543244) (xy 420.452886 -31.527471) (xy 420.525333 -31.501327) (xy 420.599769 -31.481546)
			(xy 420.675637 -31.468275) (xy 420.752368 -31.461613) (xy 420.790878 -31.461202) (xy 420.833228 -31.461669)
			(xy 420.917546 -31.469718) (xy 421.000716 -31.485746) (xy 421.081987 -31.509608) (xy 421.160621 -31.541086)
			(xy 421.235906 -31.579897) (xy 421.307162 -31.625689) (xy 421.373742 -31.678046) (xy 421.435043 -31.736496)
			(xy 421.490511 -31.800508) (xy 421.539643 -31.869502) (xy 421.581994 -31.942855) (xy 421.617181 -32.019901)
			(xy 421.644884 -32.099943) (xy 421.664853 -32.182257) (xy 421.676908 -32.266095) (xy 421.680938 -32.3507)
			(xy 421.676908 -32.435305) (xy 421.664853 -32.519143) (xy 421.644884 -32.601457) (xy 421.617181 -32.681499)
			(xy 421.581994 -32.758545) (xy 421.539643 -32.831898) (xy 421.490511 -32.900892) (xy 421.435043 -32.964904)
			(xy 421.373742 -33.023354) (xy 421.307162 -33.075711) (xy 421.235906 -33.121503) (xy 421.160621 -33.160314)
			(xy 421.081987 -33.191792) (xy 421.000716 -33.215654) (xy 420.917546 -33.231682) (xy 420.833228 -33.239731)
			(xy 420.790878 -33.240218) (xy 420.748319 -33.239733) (xy 420.663589 -33.231615) (xy 420.580023 -33.215437)
			(xy 420.498385 -33.191348) (xy 420.419423 -33.159566) (xy 420.34386 -33.120384) (xy 420.272387 -33.07416)
			(xy 420.205659 -33.021317) (xy 420.144286 -32.962339) (xy 420.08883 -32.897765) (xy 420.039799 -32.828188)
			(xy 419.997643 -32.754243) (xy 419.962745 -32.676607) (xy 419.948614 -32.63646) (xy 419.948614 -32.636206)
			(xy 419.944674 -32.626247) (xy 419.930084 -32.610594) (xy 419.92042 -32.60598) (xy 419.840918 -32.571944)
			(xy 419.819582 -32.572198) (xy 419.809676 -32.57677) (xy 419.774538 -32.592535) (xy 419.702092 -32.61868)
			(xy 419.627657 -32.638463) (xy 419.55179 -32.651736) (xy 419.47506 -32.6584) (xy 419.43655 -32.658812)
			(xy 419.394292 -32.658289) (xy 419.310157 -32.650285) (xy 419.22716 -32.634336) (xy 419.146051 -32.610586)
			(xy 419.06756 -32.579248) (xy 418.992396 -32.540605) (xy 418.921238 -32.495006) (xy 418.854726 -32.442862)
			(xy 418.79346 -32.384644) (xy 418.737994 -32.320876) (xy 418.688828 -32.252133) (xy 418.667184 -32.215836)
			(xy 418.660834 -32.204914) (xy 418.639752 -32.191706) (xy 418.531294 -32.183324) (xy 418.508688 -32.19323)
			(xy 418.50056 -32.202882) (xy 418.472438 -32.236746) (xy 418.410601 -32.299399) (xy 418.342878 -32.355636)
			(xy 418.26993 -32.404908) (xy 418.19247 -32.446731) (xy 418.111258 -32.480697) (xy 418.027088 -32.506474)
			(xy 417.940782 -32.523809) (xy 417.853186 -32.532533) (xy 417.809172 -32.533082) (xy 417.808918 -32.533082)
			(xy 417.765712 -32.532606) (xy 417.679707 -32.524234) (xy 417.594919 -32.507558) (xy 417.51215 -32.482735)
			(xy 417.432179 -32.449999) (xy 417.355761 -32.409659) (xy 417.283617 -32.362095) (xy 417.216428 -32.307757)
			(xy 417.154828 -32.247157) (xy 417.099397 -32.180866) (xy 417.074604 -32.145478) (xy 417.073588 -32.143954)
			(xy 417.066606 -32.135364) (xy 417.047242 -32.124692) (xy 417.03625 -32.12338) (xy 417.03371 -32.12338)
			(xy 416.990586 -32.122091) (xy 416.904884 -32.112106) (xy 416.820551 -32.093868) (xy 416.738382 -32.067549)
			(xy 416.659147 -32.033397) (xy 416.583592 -31.991732) (xy 416.512427 -31.942946) (xy 416.446321 -31.887498)
			(xy 416.385895 -31.825908) (xy 416.331717 -31.758756) (xy 416.284298 -31.686674) (xy 416.244082 -31.610337)
			(xy 416.211447 -31.530466) (xy 416.1867 -31.447809) (xy 416.170075 -31.363144) (xy 416.161726 -31.277267)
			(xy 416.16122 -31.234126) (xy 413.014922 -31.234126) (xy 413.014922 -31.510478) (xy 413.014417 -31.520529)
			(xy 413.006695 -31.539089) (xy 412.999936 -31.546546) (xy 412.303468 -32.243014) (xy 412.298354 -32.247816)
			(xy 412.286111 -32.254652) (xy 412.279338 -32.256476) (xy 412.27248 -32.258254) (xy 412.260542 -32.264858)
			(xy 410.712736 -33.812664) (xy 415.342574 -33.812664) (xy 415.342574 -33.727968) (xy 415.350625 -33.643654)
			(xy 415.366654 -33.560488) (xy 415.390515 -33.479221) (xy 415.421994 -33.400591) (xy 415.460805 -33.32531)
			(xy 415.506595 -33.254058) (xy 415.558951 -33.187482) (xy 415.617399 -33.126184) (xy 415.681409 -33.070719)
			(xy 415.750401 -33.02159) (xy 415.823751 -32.979241) (xy 415.900794 -32.944057) (xy 415.980833 -32.916355)
			(xy 416.063142 -32.896387) (xy 416.146977 -32.884334) (xy 416.231578 -32.880304) (xy 416.316179 -32.884334)
			(xy 416.400014 -32.896387) (xy 416.482323 -32.916355) (xy 416.562362 -32.944057) (xy 416.639405 -32.979241)
			(xy 416.712755 -33.02159) (xy 416.781747 -33.070719) (xy 416.845757 -33.126184) (xy 416.904205 -33.187482)
			(xy 416.956561 -33.254058) (xy 417.002351 -33.32531) (xy 417.041162 -33.400591) (xy 417.072641 -33.479221)
			(xy 417.096502 -33.560488) (xy 417.112531 -33.643654) (xy 417.120582 -33.727968) (xy 417.121086 -33.770316)
			(xy 417.1207 -33.802758) (xy 418.007034 -33.802758) (xy 418.007034 -33.718062) (xy 418.015085 -33.633748)
			(xy 418.031114 -33.550582) (xy 418.054975 -33.469315) (xy 418.086454 -33.390685) (xy 418.125265 -33.315404)
			(xy 418.171055 -33.244152) (xy 418.223411 -33.177576) (xy 418.281859 -33.116278) (xy 418.345869 -33.060813)
			(xy 418.414861 -33.011684) (xy 418.488211 -32.969335) (xy 418.565254 -32.934151) (xy 418.645293 -32.906449)
			(xy 418.727602 -32.886481) (xy 418.811437 -32.874428) (xy 418.896038 -32.870398) (xy 418.980639 -32.874428)
			(xy 419.064474 -32.886481) (xy 419.146783 -32.906449) (xy 419.226822 -32.934151) (xy 419.303865 -32.969335)
			(xy 419.377215 -33.011684) (xy 419.446207 -33.060813) (xy 419.510217 -33.116278) (xy 419.568665 -33.177576)
			(xy 419.621021 -33.244152) (xy 419.666811 -33.315404) (xy 419.705622 -33.390685) (xy 419.737101 -33.469315)
			(xy 419.760962 -33.550582) (xy 419.776991 -33.633748) (xy 419.785042 -33.718062) (xy 419.785546 -33.76041)
			(xy 419.785042 -33.802758) (xy 419.776991 -33.887072) (xy 419.760962 -33.970238) (xy 419.737101 -34.051505)
			(xy 419.705622 -34.130135) (xy 419.666811 -34.205416) (xy 419.621021 -34.276668) (xy 419.568665 -34.343244)
			(xy 419.510217 -34.404542) (xy 419.446207 -34.460007) (xy 419.377215 -34.509136) (xy 419.303865 -34.551485)
			(xy 419.226822 -34.586669) (xy 419.146783 -34.614371) (xy 419.064474 -34.634339) (xy 418.980639 -34.646392)
			(xy 418.896038 -34.650423) (xy 418.811437 -34.646392) (xy 418.727602 -34.634339) (xy 418.645293 -34.614371)
			(xy 418.565254 -34.586669) (xy 418.488211 -34.551485) (xy 418.414861 -34.509136) (xy 418.345869 -34.460007)
			(xy 418.281859 -34.404542) (xy 418.223411 -34.343244) (xy 418.171055 -34.276668) (xy 418.125265 -34.205416)
			(xy 418.086454 -34.130135) (xy 418.054975 -34.051505) (xy 418.031114 -33.970238) (xy 418.015085 -33.887072)
			(xy 418.007034 -33.802758) (xy 417.1207 -33.802758) (xy 417.120582 -33.812664) (xy 417.112531 -33.896978)
			(xy 417.096502 -33.980144) (xy 417.072641 -34.061411) (xy 417.041162 -34.140041) (xy 417.002351 -34.215322)
			(xy 416.956561 -34.286574) (xy 416.904205 -34.35315) (xy 416.845757 -34.414448) (xy 416.781747 -34.469913)
			(xy 416.712755 -34.519042) (xy 416.639405 -34.561391) (xy 416.562362 -34.596575) (xy 416.482323 -34.624277)
			(xy 416.400014 -34.644245) (xy 416.316179 -34.656298) (xy 416.231578 -34.660329) (xy 416.146977 -34.656298)
			(xy 416.063142 -34.644245) (xy 415.980833 -34.624277) (xy 415.900794 -34.596575) (xy 415.823751 -34.561391)
			(xy 415.750401 -34.519042) (xy 415.681409 -34.469913) (xy 415.617399 -34.414448) (xy 415.558951 -34.35315)
			(xy 415.506595 -34.286574) (xy 415.460805 -34.215322) (xy 415.421994 -34.140041) (xy 415.390515 -34.061411)
			(xy 415.366654 -33.980144) (xy 415.350625 -33.896978) (xy 415.342574 -33.812664) (xy 410.712736 -33.812664)
			(xy 409.431052 -35.094348) (xy 420.369996 -35.094348) (xy 420.369996 -35.009652) (xy 420.378047 -34.925338)
			(xy 420.394076 -34.842172) (xy 420.417937 -34.760905) (xy 420.449416 -34.682275) (xy 420.488227 -34.606994)
			(xy 420.534017 -34.535742) (xy 420.586373 -34.469166) (xy 420.644821 -34.407868) (xy 420.708831 -34.352403)
			(xy 420.777823 -34.303274) (xy 420.851173 -34.260925) (xy 420.928216 -34.225741) (xy 421.008255 -34.198039)
			(xy 421.090564 -34.178071) (xy 421.174399 -34.166018) (xy 421.259 -34.161988) (xy 421.343601 -34.166018)
			(xy 421.427436 -34.178071) (xy 421.509745 -34.198039) (xy 421.589784 -34.225741) (xy 421.666827 -34.260925)
			(xy 421.740177 -34.303274) (xy 421.809169 -34.352403) (xy 421.873179 -34.407868) (xy 421.931627 -34.469166)
			(xy 421.983983 -34.535742) (xy 422.029773 -34.606994) (xy 422.068584 -34.682275) (xy 422.100063 -34.760905)
			(xy 422.123924 -34.842172) (xy 422.139953 -34.925338) (xy 422.148004 -35.009652) (xy 422.148508 -35.052)
			(xy 422.148004 -35.094348) (xy 422.528996 -35.094348) (xy 422.528996 -35.009652) (xy 422.537047 -34.925338)
			(xy 422.553076 -34.842172) (xy 422.576937 -34.760905) (xy 422.608416 -34.682275) (xy 422.647227 -34.606994)
			(xy 422.693017 -34.535742) (xy 422.745373 -34.469166) (xy 422.803821 -34.407868) (xy 422.867831 -34.352403)
			(xy 422.936823 -34.303274) (xy 423.010173 -34.260925) (xy 423.087216 -34.225741) (xy 423.167255 -34.198039)
			(xy 423.249564 -34.178071) (xy 423.333399 -34.166018) (xy 423.418 -34.161988) (xy 423.502601 -34.166018)
			(xy 423.586436 -34.178071) (xy 423.668745 -34.198039) (xy 423.748784 -34.225741) (xy 423.825827 -34.260925)
			(xy 423.899177 -34.303274) (xy 423.968169 -34.352403) (xy 424.032179 -34.407868) (xy 424.090627 -34.469166)
			(xy 424.142983 -34.535742) (xy 424.188773 -34.606994) (xy 424.227584 -34.682275) (xy 424.259063 -34.760905)
			(xy 424.282924 -34.842172) (xy 424.298953 -34.925338) (xy 424.307004 -35.009652) (xy 424.307508 -35.052)
			(xy 424.307004 -35.094348) (xy 424.298953 -35.178662) (xy 424.282924 -35.261828) (xy 424.259063 -35.343095)
			(xy 424.227584 -35.421725) (xy 424.188773 -35.497006) (xy 424.142983 -35.568258) (xy 424.090627 -35.634834)
			(xy 424.032179 -35.696132) (xy 423.968169 -35.751597) (xy 423.899177 -35.800726) (xy 423.825827 -35.843075)
			(xy 423.748784 -35.878259) (xy 423.668745 -35.905961) (xy 423.586436 -35.925929) (xy 423.502601 -35.937982)
			(xy 423.418 -35.942013) (xy 423.333399 -35.937982) (xy 423.249564 -35.925929) (xy 423.167255 -35.905961)
			(xy 423.087216 -35.878259) (xy 423.010173 -35.843075) (xy 422.936823 -35.800726) (xy 422.867831 -35.751597)
			(xy 422.803821 -35.696132) (xy 422.745373 -35.634834) (xy 422.693017 -35.568258) (xy 422.647227 -35.497006)
			(xy 422.608416 -35.421725) (xy 422.576937 -35.343095) (xy 422.553076 -35.261828) (xy 422.537047 -35.178662)
			(xy 422.528996 -35.094348) (xy 422.148004 -35.094348) (xy 422.139953 -35.178662) (xy 422.123924 -35.261828)
			(xy 422.100063 -35.343095) (xy 422.068584 -35.421725) (xy 422.029773 -35.497006) (xy 421.983983 -35.568258)
			(xy 421.931627 -35.634834) (xy 421.873179 -35.696132) (xy 421.809169 -35.751597) (xy 421.740177 -35.800726)
			(xy 421.666827 -35.843075) (xy 421.589784 -35.878259) (xy 421.509745 -35.905961) (xy 421.427436 -35.925929)
			(xy 421.343601 -35.937982) (xy 421.259 -35.942013) (xy 421.174399 -35.937982) (xy 421.090564 -35.925929)
			(xy 421.008255 -35.905961) (xy 420.928216 -35.878259) (xy 420.851173 -35.843075) (xy 420.777823 -35.800726)
			(xy 420.708831 -35.751597) (xy 420.644821 -35.696132) (xy 420.586373 -35.634834) (xy 420.534017 -35.568258)
			(xy 420.488227 -35.497006) (xy 420.449416 -35.421725) (xy 420.417937 -35.343095) (xy 420.394076 -35.261828)
			(xy 420.378047 -35.178662) (xy 420.369996 -35.094348) (xy 409.431052 -35.094348) (xy 407.837386 -36.688014)
			(xy 407.83002 -36.695126) (xy 407.8224 -36.713922) (xy 407.8224 -37.8269) (xy 410.107438 -37.8269)
			(xy 410.111467 -37.742304) (xy 410.12352 -37.658473) (xy 410.143487 -37.576169) (xy 410.171187 -37.496134)
			(xy 410.20637 -37.419096) (xy 410.248716 -37.34575) (xy 410.297842 -37.276762) (xy 410.353304 -37.212756)
			(xy 410.414599 -37.154311) (xy 410.481171 -37.101958) (xy 410.552419 -37.05617) (xy 410.627696 -37.017362)
			(xy 410.706322 -36.985885) (xy 410.787583 -36.962024) (xy 410.870745 -36.945996) (xy 410.955054 -36.937946)
			(xy 410.9974 -36.937442) (xy 410.997654 -36.937442) (xy 411.041808 -36.937963) (xy 411.129679 -36.946735)
			(xy 411.216249 -36.964168) (xy 411.300666 -36.990089) (xy 411.382101 -37.024245) (xy 411.459753 -37.066299)
			(xy 411.532857 -37.115838) (xy 411.567122 -37.14369) (xy 411.578552 -37.153088) (xy 411.607508 -37.157152)
			(xy 411.704028 -37.112956) (xy 411.710413 -37.109772) (xy 411.721241 -37.100491) (xy 411.725364 -37.094668)
			(xy 411.733492 -37.082222) (xy 411.733746 -37.06749) (xy 411.73502 -37.025366) (xy 411.744528 -36.941623)
			(xy 411.761922 -36.859157) (xy 411.787046 -36.778708) (xy 411.819673 -36.700999) (xy 411.839156 -36.66363)
			(xy 411.844577 -36.652164) (xy 411.844577 -36.626836) (xy 411.839156 -36.61537) (xy 411.818917 -36.576528)
			(xy 411.785281 -36.495652) (xy 411.759768 -36.411859) (xy 411.742623 -36.325963) (xy 411.734013 -36.238796)
			(xy 411.733492 -36.195) (xy 411.733996 -36.152652) (xy 411.742047 -36.068338) (xy 411.758076 -35.985172)
			(xy 411.781937 -35.903905) (xy 411.813416 -35.825275) (xy 411.852227 -35.749994) (xy 411.898017 -35.678742)
			(xy 411.950373 -35.612166) (xy 412.008821 -35.550868) (xy 412.072831 -35.495403) (xy 412.141823 -35.446274)
			(xy 412.215173 -35.403925) (xy 412.292216 -35.368741) (xy 412.372255 -35.341039) (xy 412.454564 -35.321071)
			(xy 412.538399 -35.309018) (xy 412.623 -35.304988) (xy 412.707601 -35.309018) (xy 412.791436 -35.321071)
			(xy 412.873745 -35.341039) (xy 412.953784 -35.368741) (xy 413.030827 -35.403925) (xy 413.104177 -35.446274)
			(xy 413.173169 -35.495403) (xy 413.237179 -35.550868) (xy 413.295627 -35.612166) (xy 413.347983 -35.678742)
			(xy 413.393773 -35.749994) (xy 413.432584 -35.825275) (xy 413.464063 -35.903905) (xy 413.487924 -35.985172)
			(xy 413.503953 -36.068338) (xy 413.512004 -36.152652) (xy 413.512508 -36.195) (xy 413.511948 -36.238793)
			(xy 413.503318 -36.325954) (xy 413.486172 -36.411846) (xy 413.460675 -36.49564) (xy 413.427074 -36.576525)
			(xy 413.406844 -36.61537) (xy 413.401423 -36.626836) (xy 413.401423 -36.652164) (xy 413.406844 -36.66363)
			(xy 413.427083 -36.702472) (xy 413.460719 -36.783348) (xy 413.486232 -36.867141) (xy 413.503377 -36.953037)
			(xy 413.511987 -37.040204) (xy 413.512508 -37.084) (xy 413.512033 -37.125102) (xy 413.504448 -37.206957)
			(xy 413.489343 -37.287762) (xy 413.466847 -37.366829) (xy 413.437151 -37.443483) (xy 413.400509 -37.51707)
			(xy 413.357234 -37.586962) (xy 413.307694 -37.652563) (xy 413.252313 -37.713313) (xy 413.191563 -37.768694)
			(xy 413.125962 -37.818234) (xy 413.05607 -37.861509) (xy 412.982483 -37.898151) (xy 412.905829 -37.927847)
			(xy 412.826762 -37.950343) (xy 412.745957 -37.965448) (xy 412.664102 -37.973033) (xy 412.623 -37.973508)
			(xy 412.622746 -37.973508) (xy 412.578593 -37.972975) (xy 412.490722 -37.964204) (xy 412.404153 -37.946772)
			(xy 412.319736 -37.920852) (xy 412.238301 -37.886698) (xy 412.160649 -37.844647) (xy 412.087544 -37.795111)
			(xy 412.053278 -37.76726) (xy 412.041848 -37.757862) (xy 412.012892 -37.753798) (xy 411.916372 -37.797994)
			(xy 411.90998 -37.801165) (xy 411.899155 -37.810455) (xy 411.895036 -37.816282) (xy 411.886908 -37.828728)
			(xy 411.886654 -37.84346) (xy 411.885403 -37.886601) (xy 411.875462 -37.972341) (xy 411.857261 -38.056715)
			(xy 411.830972 -38.138928) (xy 411.796841 -38.218208) (xy 411.755191 -38.293808) (xy 411.706412 -38.365018)
			(xy 411.650964 -38.431167) (xy 411.589369 -38.491633) (xy 411.522205 -38.545847) (xy 411.450104 -38.593299)
			(xy 411.373746 -38.633543) (xy 411.293848 -38.666201) (xy 411.211162 -38.690964) (xy 411.126466 -38.7076)
			(xy 411.040557 -38.715952) (xy 410.9974 -38.716458) (xy 410.955054 -38.715854) (xy 410.870745 -38.707804)
			(xy 410.787583 -38.691776) (xy 410.706322 -38.667915) (xy 410.627696 -38.636438) (xy 410.552419 -38.59763)
			(xy 410.481171 -38.551842) (xy 410.414599 -38.499489) (xy 410.353304 -38.441044) (xy 410.297842 -38.377038)
			(xy 410.248716 -38.30805) (xy 410.20637 -38.234704) (xy 410.171187 -38.157666) (xy 410.143487 -38.077631)
			(xy 410.12352 -37.995327) (xy 410.111467 -37.911496) (xy 410.107438 -37.8269) (xy 407.8224 -37.8269)
			(xy 407.8224 -39.6065) (xy 411.123362 -39.6065) (xy 411.127392 -39.521896) (xy 411.139446 -39.438059)
			(xy 411.159414 -39.355747) (xy 411.187117 -39.275706) (xy 411.222302 -39.198661) (xy 411.264652 -39.125309)
			(xy 411.313782 -39.056315) (xy 411.369249 -38.992303) (xy 411.430549 -38.933854) (xy 411.497127 -38.881496)
			(xy 411.568381 -38.835704) (xy 411.643665 -38.796893) (xy 411.722297 -38.765413) (xy 411.803565 -38.74155)
			(xy 411.886734 -38.725521) (xy 411.97105 -38.71747) (xy 412.0134 -38.716966) (xy 412.053668 -38.717376)
			(xy 412.133873 -38.724659) (xy 412.21309 -38.739166) (xy 412.290672 -38.760777) (xy 412.365981 -38.789315)
			(xy 412.438401 -38.824547) (xy 412.507337 -38.866183) (xy 412.572226 -38.913883) (xy 412.60268 -38.940232)
			(xy 412.611939 -38.94762) (xy 412.634798 -38.953739) (xy 412.657991 -38.949047) (xy 412.667704 -38.942264)
			(xy 412.668974 -38.941248) (xy 412.703266 -38.913352) (xy 412.776412 -38.863705) (xy 412.854121 -38.821555)
			(xy 412.935626 -38.787319) (xy 413.020125 -38.761333) (xy 413.106784 -38.743854) (xy 413.194748 -38.735053)
			(xy 413.23895 -38.734492) (xy 413.281301 -38.734978) (xy 413.365619 -38.743025) (xy 413.448791 -38.75905)
			(xy 413.530062 -38.78291) (xy 413.608698 -38.814387) (xy 413.683985 -38.853196) (xy 413.73394 -38.885298)
			(xy 414.400996 -38.885298) (xy 414.400996 -38.800602) (xy 414.409047 -38.716288) (xy 414.425076 -38.633122)
			(xy 414.448937 -38.551855) (xy 414.480416 -38.473225) (xy 414.519227 -38.397944) (xy 414.565017 -38.326692)
			(xy 414.617373 -38.260116) (xy 414.675821 -38.198818) (xy 414.739831 -38.143353) (xy 414.808823 -38.094224)
			(xy 414.882173 -38.051875) (xy 414.959216 -38.016691) (xy 415.039255 -37.988989) (xy 415.121564 -37.969021)
			(xy 415.205399 -37.956968) (xy 415.29 -37.952938) (xy 415.374601 -37.956968) (xy 415.458436 -37.969021)
			(xy 415.540745 -37.988989) (xy 415.620784 -38.016691) (xy 415.697827 -38.051875) (xy 415.771177 -38.094224)
			(xy 415.840169 -38.143353) (xy 415.904179 -38.198818) (xy 415.962627 -38.260116) (xy 416.014983 -38.326692)
			(xy 416.060773 -38.397944) (xy 416.099584 -38.473225) (xy 416.131063 -38.551855) (xy 416.154924 -38.633122)
			(xy 416.170953 -38.716288) (xy 416.179004 -38.800602) (xy 416.179508 -38.84295) (xy 416.179004 -38.885298)
			(xy 416.170953 -38.969612) (xy 416.154924 -39.052778) (xy 416.131063 -39.134045) (xy 416.099584 -39.212675)
			(xy 416.060773 -39.287956) (xy 416.014983 -39.359208) (xy 415.962627 -39.425784) (xy 415.904179 -39.487082)
			(xy 415.840169 -39.542547) (xy 415.771177 -39.591676) (xy 415.697827 -39.634025) (xy 415.620784 -39.669209)
			(xy 415.540745 -39.696911) (xy 415.458436 -39.716879) (xy 415.374601 -39.728932) (xy 415.29 -39.732963)
			(xy 415.205399 -39.728932) (xy 415.121564 -39.716879) (xy 415.039255 -39.696911) (xy 414.959216 -39.669209)
			(xy 414.882173 -39.634025) (xy 414.808823 -39.591676) (xy 414.739831 -39.542547) (xy 414.675821 -39.487082)
			(xy 414.617373 -39.425784) (xy 414.565017 -39.359208) (xy 414.519227 -39.287956) (xy 414.480416 -39.212675)
			(xy 414.448937 -39.134045) (xy 414.425076 -39.052778) (xy 414.409047 -38.969612) (xy 414.400996 -38.885298)
			(xy 413.73394 -38.885298) (xy 413.755242 -38.898987) (xy 413.821824 -38.951344) (xy 413.883127 -39.009793)
			(xy 413.938596 -39.073805) (xy 413.987729 -39.142799) (xy 414.030081 -39.216152) (xy 414.065269 -39.293199)
			(xy 414.092973 -39.373241) (xy 414.112943 -39.455555) (xy 414.124998 -39.539394) (xy 414.129028 -39.624)
			(xy 414.124998 -39.708606) (xy 414.112943 -39.792445) (xy 414.092973 -39.874759) (xy 414.065269 -39.954801)
			(xy 414.030081 -40.031848) (xy 413.987729 -40.105201) (xy 413.938596 -40.174195) (xy 413.883127 -40.238207)
			(xy 413.821824 -40.296656) (xy 413.755242 -40.349013) (xy 413.683985 -40.394804) (xy 413.608698 -40.433613)
			(xy 413.530062 -40.46509) (xy 413.448791 -40.48895) (xy 413.365619 -40.504975) (xy 413.281301 -40.513022)
			(xy 413.23895 -40.513508) (xy 413.198684 -40.513048) (xy 413.118481 -40.50577) (xy 413.039265 -40.49127)
			(xy 412.961684 -40.469665) (xy 412.886375 -40.441134) (xy 412.813955 -40.405909) (xy 412.745017 -40.36428)
			(xy 412.680125 -40.316587) (xy 412.64967 -40.290242) (xy 412.640379 -40.282901) (xy 412.61754 -40.276772)
			(xy 412.594359 -40.281442) (xy 412.584646 -40.28821) (xy 412.583376 -40.289226) (xy 412.5491 -40.317142)
			(xy 412.475951 -40.366788) (xy 412.398239 -40.408935) (xy 412.316731 -40.443169) (xy 412.23223 -40.469152)
			(xy 412.145569 -40.486627) (xy 412.057602 -40.495423) (xy 412.0134 -40.495982) (xy 411.97105 -40.49553)
			(xy 411.886734 -40.487479) (xy 411.803565 -40.47145) (xy 411.722297 -40.447587) (xy 411.643665 -40.416107)
			(xy 411.568381 -40.377296) (xy 411.497127 -40.331504) (xy 411.430549 -40.279146) (xy 411.369249 -40.220697)
			(xy 411.313782 -40.156685) (xy 411.264652 -40.087691) (xy 411.222302 -40.014339) (xy 411.187117 -39.937294)
			(xy 411.159414 -39.857253) (xy 411.139446 -39.774941) (xy 411.127392 -39.691104) (xy 411.123362 -39.6065)
			(xy 407.8224 -39.6065) (xy 407.8224 -44.555918) (xy 407.82286 -44.565795) (xy 407.830303 -44.584094)
			(xy 407.836878 -44.591478) (xy 407.837132 -44.591732) (xy 408.4574 -45.212) (xy 411.377892 -45.212)
			(xy 411.378421 -45.168532) (xy 411.386913 -45.082011) (xy 411.403806 -44.996732) (xy 411.42894 -44.913508)
			(xy 411.462074 -44.833133) (xy 411.502892 -44.756375) (xy 411.551005 -44.683965) (xy 411.605953 -44.616596)
			(xy 411.63621 -44.585382) (xy 411.636464 -44.585128) (xy 411.643576 -44.577762) (xy 411.647386 -44.568872)
			(xy 411.65018 -44.55414) (xy 411.651196 -44.544234) (xy 411.651196 -44.477686) (xy 411.651095 -44.472667)
			(xy 411.649182 -44.462815) (xy 411.647386 -44.458128) (xy 411.643576 -44.449238) (xy 411.636464 -44.441872)
			(xy 411.63621 -44.441618) (xy 411.605962 -44.410395) (xy 411.551005 -44.343032) (xy 411.502886 -44.270627)
			(xy 411.462063 -44.19387) (xy 411.428927 -44.113496) (xy 411.403794 -44.030271) (xy 411.386904 -43.94499)
			(xy 411.378419 -43.858468) (xy 411.377892 -43.815) (xy 411.378444 -43.771801) (xy 411.38683 -43.685812)
			(xy 411.403513 -43.601041) (xy 411.428335 -43.518286) (xy 411.461064 -43.438328) (xy 411.501391 -43.36192)
			(xy 411.548935 -43.289781) (xy 411.60325 -43.222591) (xy 411.663822 -43.160984) (xy 411.730082 -43.105539)
			(xy 411.801405 -43.056779) (xy 411.877119 -43.015164) (xy 411.956511 -42.981085) (xy 412.038833 -42.954863)
			(xy 412.080964 -42.945304) (xy 412.091632 -42.943018) (xy 412.108904 -42.930572) (xy 412.152084 -42.855896)
			(xy 412.156873 -42.846402) (xy 412.159112 -42.825283) (xy 412.156402 -42.815002) (xy 412.143099 -42.771289)
			(xy 412.124447 -42.681837) (xy 412.115074 -42.590942) (xy 412.114492 -42.545254) (xy 412.114492 -42.545)
			(xy 412.114995 -42.502685) (xy 412.123026 -42.418437) (xy 412.139024 -42.335334) (xy 412.162845 -42.254125)
			(xy 412.194272 -42.175548) (xy 412.233023 -42.100311) (xy 412.255462 -42.064432) (xy 412.260345 -42.056043)
			(xy 412.264017 -42.037) (xy 412.260345 -42.017957) (xy 412.255462 -42.009568) (xy 412.233016 -41.973694)
			(xy 412.194273 -41.898453) (xy 412.162849 -41.819874) (xy 412.13903 -41.738665) (xy 412.12303 -41.655562)
			(xy 412.114994 -41.571315) (xy 412.114492 -41.529) (xy 412.114996 -41.486652) (xy 412.123047 -41.402338)
			(xy 412.139076 -41.319172) (xy 412.162937 -41.237905) (xy 412.194416 -41.159275) (xy 412.233227 -41.083994)
			(xy 412.279017 -41.012742) (xy 412.331373 -40.946166) (xy 412.389821 -40.884868) (xy 412.453831 -40.829403)
			(xy 412.522823 -40.780274) (xy 412.596173 -40.737925) (xy 412.673216 -40.702741) (xy 412.753255 -40.675039)
			(xy 412.835564 -40.655071) (xy 412.919399 -40.643018) (xy 413.004 -40.638988) (xy 413.088601 -40.643018)
			(xy 413.172436 -40.655071) (xy 413.254745 -40.675039) (xy 413.334784 -40.702741) (xy 413.411827 -40.737925)
			(xy 413.485177 -40.780274) (xy 413.554169 -40.829403) (xy 413.618179 -40.884868) (xy 413.676627 -40.946166)
			(xy 413.728983 -41.012742) (xy 413.774773 -41.083994) (xy 413.813584 -41.159275) (xy 413.845063 -41.237905)
			(xy 413.868924 -41.319172) (xy 413.884953 -41.402338) (xy 413.893004 -41.486652) (xy 413.893508 -41.529)
			(xy 413.893005 -41.571315) (xy 413.884974 -41.655563) (xy 413.868976 -41.738666) (xy 413.845155 -41.819875)
			(xy 413.813728 -41.898452) (xy 413.774977 -41.973689) (xy 413.752538 -42.009568) (xy 413.747655 -42.017957)
			(xy 413.743983 -42.037) (xy 413.747655 -42.056043) (xy 413.752538 -42.064432) (xy 413.774984 -42.100306)
			(xy 413.813727 -42.175547) (xy 413.845151 -42.254126) (xy 413.86897 -42.335335) (xy 413.88497 -42.418438)
			(xy 413.893006 -42.502685) (xy 413.893508 -42.545) (xy 413.892956 -42.588199) (xy 413.88457 -42.674188)
			(xy 413.867887 -42.758959) (xy 413.843065 -42.841714) (xy 413.810336 -42.921672) (xy 413.770009 -42.99808)
			(xy 413.722465 -43.070219) (xy 413.66815 -43.137409) (xy 413.607578 -43.199016) (xy 413.541318 -43.254461)
			(xy 413.469995 -43.303221) (xy 413.394281 -43.344836) (xy 413.314889 -43.378915) (xy 413.232567 -43.405137)
			(xy 413.190436 -43.414696) (xy 413.179768 -43.416982) (xy 413.162496 -43.429428) (xy 413.119316 -43.504104)
			(xy 413.114527 -43.513598) (xy 413.112288 -43.534717) (xy 413.114998 -43.544998) (xy 413.121679 -43.566514)
			(xy 413.133115 -43.610096) (xy 413.137858 -43.63212) (xy 413.137858 -43.632374) (xy 413.140652 -43.64482)
			(xy 413.148526 -43.654218) (xy 413.152496 -43.658857) (xy 413.16227 -43.666171) (xy 413.16783 -43.668696)
			(xy 413.244538 -43.701462) (xy 413.256075 -43.705605) (xy 413.280485 -43.703729) (xy 413.291274 -43.697906)
			(xy 413.291274 -43.697652) (xy 413.291782 -43.697652) (xy 413.327319 -43.675842) (xy 413.401695 -43.638143)
			(xy 413.479274 -43.607574) (xy 413.559374 -43.584401) (xy 413.641292 -43.568829) (xy 413.724308 -43.560994)
			(xy 413.766 -43.560492) (xy 413.808348 -43.560996) (xy 413.892662 -43.569047) (xy 413.975828 -43.585076)
			(xy 414.057095 -43.608937) (xy 414.135725 -43.640416) (xy 414.211006 -43.679227) (xy 414.282258 -43.725017)
			(xy 414.348834 -43.777373) (xy 414.410132 -43.835821) (xy 414.465597 -43.899831) (xy 414.514726 -43.968823)
			(xy 414.557075 -44.042173) (xy 414.588666 -44.111348) (xy 414.807396 -44.111348) (xy 414.807396 -44.026652)
			(xy 414.815447 -43.942338) (xy 414.831476 -43.859172) (xy 414.855337 -43.777905) (xy 414.886816 -43.699275)
			(xy 414.925627 -43.623994) (xy 414.971417 -43.552742) (xy 415.023773 -43.486166) (xy 415.082221 -43.424868)
			(xy 415.146231 -43.369403) (xy 415.215223 -43.320274) (xy 415.288573 -43.277925) (xy 415.365616 -43.242741)
			(xy 415.445655 -43.215039) (xy 415.527964 -43.195071) (xy 415.611799 -43.183018) (xy 415.6964 -43.178988)
			(xy 415.781001 -43.183018) (xy 415.864836 -43.195071) (xy 415.947145 -43.215039) (xy 416.027184 -43.242741)
			(xy 416.104227 -43.277925) (xy 416.177577 -43.320274) (xy 416.246569 -43.369403) (xy 416.310579 -43.424868)
			(xy 416.369027 -43.486166) (xy 416.421383 -43.552742) (xy 416.467173 -43.623994) (xy 416.505984 -43.699275)
			(xy 416.537463 -43.777905) (xy 416.561324 -43.859172) (xy 416.577353 -43.942338) (xy 416.585404 -44.026652)
			(xy 416.585908 -44.069) (xy 416.585404 -44.111348) (xy 416.577353 -44.195662) (xy 416.561324 -44.278828)
			(xy 416.537463 -44.360095) (xy 416.505984 -44.438725) (xy 416.467173 -44.514006) (xy 416.421383 -44.585258)
			(xy 416.369027 -44.651834) (xy 416.310579 -44.713132) (xy 416.246569 -44.768597) (xy 416.177577 -44.817726)
			(xy 416.104227 -44.860075) (xy 416.027184 -44.895259) (xy 415.947145 -44.922961) (xy 415.864836 -44.942929)
			(xy 415.781001 -44.954982) (xy 415.6964 -44.959013) (xy 415.611799 -44.954982) (xy 415.527964 -44.942929)
			(xy 415.445655 -44.922961) (xy 415.365616 -44.895259) (xy 415.288573 -44.860075) (xy 415.215223 -44.817726)
			(xy 415.146231 -44.768597) (xy 415.082221 -44.713132) (xy 415.023773 -44.651834) (xy 414.971417 -44.585258)
			(xy 414.925627 -44.514006) (xy 414.886816 -44.438725) (xy 414.855337 -44.360095) (xy 414.831476 -44.278828)
			(xy 414.815447 -44.195662) (xy 414.807396 -44.111348) (xy 414.588666 -44.111348) (xy 414.592259 -44.119216)
			(xy 414.619961 -44.199255) (xy 414.639929 -44.281564) (xy 414.651982 -44.365399) (xy 414.656013 -44.45)
			(xy 414.651982 -44.534601) (xy 414.639929 -44.618436) (xy 414.619961 -44.700745) (xy 414.592259 -44.780784)
			(xy 414.557075 -44.857827) (xy 414.514726 -44.931177) (xy 414.465597 -45.000169) (xy 414.410132 -45.064179)
			(xy 414.348834 -45.122627) (xy 414.282258 -45.174983) (xy 414.211006 -45.220773) (xy 414.135725 -45.259584)
			(xy 414.057095 -45.291063) (xy 413.975828 -45.314924) (xy 413.892662 -45.330953) (xy 413.808348 -45.339004)
			(xy 413.766 -45.339508) (xy 413.725805 -45.339092) (xy 413.645744 -45.331839) (xy 413.566663 -45.317392)
			(xy 413.489208 -45.29587) (xy 413.414011 -45.267446) (xy 413.341685 -45.232355) (xy 413.307022 -45.212)
			(xy 413.295592 -45.205142) (xy 413.26943 -45.204126) (xy 413.181038 -45.249338) (xy 413.175402 -45.252422)
			(xy 413.165755 -45.260899) (xy 413.161988 -45.266102) (xy 413.154368 -45.277278) (xy 413.153352 -45.290232)
			(xy 413.149296 -45.331258) (xy 413.134491 -45.412364) (xy 413.112243 -45.491751) (xy 413.082742 -45.568739)
			(xy 413.046242 -45.642665) (xy 413.003056 -45.712896) (xy 412.953555 -45.778828) (xy 412.898164 -45.839896)
			(xy 412.837359 -45.895574) (xy 412.771661 -45.945386) (xy 412.701635 -45.988902) (xy 412.627881 -46.025751)
			(xy 412.551034 -46.055615) (xy 412.471752 -46.078237) (xy 412.390716 -46.093425) (xy 412.308623 -46.101047)
			(xy 412.2674 -46.101508) (xy 412.226298 -46.101033) (xy 412.144443 -46.093448) (xy 412.063638 -46.078343)
			(xy 411.984571 -46.055847) (xy 411.907917 -46.026151) (xy 411.83433 -45.989509) (xy 411.764438 -45.946234)
			(xy 411.698837 -45.896694) (xy 411.638087 -45.841313) (xy 411.582706 -45.780563) (xy 411.533166 -45.714962)
			(xy 411.489891 -45.64507) (xy 411.453249 -45.571483) (xy 411.423553 -45.494829) (xy 411.401057 -45.415762)
			(xy 411.385952 -45.334957) (xy 411.378367 -45.253102) (xy 411.377892 -45.212) (xy 408.4574 -45.212)
			(xy 410.1084 -46.863) (xy 416.177988 -46.863) (xy 416.182018 -46.778399) (xy 416.194071 -46.694564)
			(xy 416.214039 -46.612255) (xy 416.241741 -46.532216) (xy 416.276925 -46.455173) (xy 416.319274 -46.381823)
			(xy 416.368403 -46.312831) (xy 416.423868 -46.248821) (xy 416.485166 -46.190373) (xy 416.551742 -46.138017)
			(xy 416.622994 -46.092227) (xy 416.698275 -46.053416) (xy 416.776905 -46.021937) (xy 416.858172 -45.998076)
			(xy 416.941338 -45.982047) (xy 417.025652 -45.973996) (xy 417.068 -45.973492) (xy 417.068508 -45.973492)
			(xy 417.11484 -45.974098) (xy 417.206998 -45.983769) (xy 417.297652 -46.002965) (xy 417.385821 -46.031477)
			(xy 417.428426 -46.049692) (xy 417.438368 -46.053498) (xy 417.459632 -46.053498) (xy 417.469574 -46.049692)
			(xy 417.512177 -46.03147) (xy 417.600344 -46.002952) (xy 417.691 -45.98376) (xy 417.78316 -45.9741)
			(xy 417.829492 -45.973492) (xy 417.83 -45.973492) (xy 417.867816 -45.973915) (xy 417.943173 -45.980372)
			(xy 418.017711 -45.993196) (xy 418.090893 -46.012295) (xy 418.126672 -46.024546) (xy 418.133206 -46.026571)
			(xy 418.146852 -46.027472) (xy 418.153596 -46.026324) (xy 418.160171 -46.024843) (xy 418.172276 -46.018931)
			(xy 418.177472 -46.01464) (xy 418.24402 -45.95622) (xy 418.24897 -45.951576) (xy 418.256442 -45.94025)
			(xy 418.258752 -45.933868) (xy 418.261038 -45.927264) (xy 418.2618 -45.914056) (xy 418.260276 -45.907198)
			(xy 418.250932 -45.860962) (xy 418.240873 -45.767166) (xy 418.24021 -45.72) (xy 418.240713 -45.678963)
			(xy 418.248277 -45.597239) (xy 418.263332 -45.516558) (xy 418.285751 -45.437605) (xy 418.315342 -45.361051)
			(xy 418.351855 -45.287546) (xy 418.394978 -45.217715) (xy 418.444347 -45.15215) (xy 418.499542 -45.091407)
			(xy 418.560095 -45.036004) (xy 418.592508 -45.010832) (xy 418.603176 -45.002958) (xy 418.61359 -44.978828)
			(xy 418.604192 -44.879768) (xy 418.603385 -44.87339) (xy 418.599027 -44.861302) (xy 418.595556 -44.855892)
			(xy 418.591811 -44.850788) (xy 418.582305 -44.842435) (xy 418.57676 -44.839382) (xy 418.576252 -44.839128)
			(xy 418.575998 -44.839128) (xy 418.539436 -44.820392) (xy 418.469611 -44.777093) (xy 418.404075 -44.727541)
			(xy 418.343388 -44.672156) (xy 418.288067 -44.611411) (xy 418.238582 -44.545824) (xy 418.195356 -44.475954)
			(xy 418.158757 -44.402395) (xy 418.129096 -44.325775) (xy 418.106627 -44.246747) (xy 418.09154 -44.165983)
			(xy 418.083965 -44.084172) (xy 418.083492 -44.043092) (xy 418.083996 -44.000744) (xy 418.092047 -43.91643)
			(xy 418.108076 -43.833264) (xy 418.131937 -43.751997) (xy 418.163416 -43.673367) (xy 418.202227 -43.598086)
			(xy 418.248017 -43.526834) (xy 418.300373 -43.460258) (xy 418.358821 -43.39896) (xy 418.422831 -43.343495)
			(xy 418.491823 -43.294366) (xy 418.565173 -43.252017) (xy 418.642216 -43.216833) (xy 418.722255 -43.189131)
			(xy 418.804564 -43.169163) (xy 418.888399 -43.15711) (xy 418.973 -43.15308) (xy 419.057601 -43.15711)
			(xy 419.141436 -43.169163) (xy 419.223745 -43.189131) (xy 419.303784 -43.216833) (xy 419.380827 -43.252017)
			(xy 419.454177 -43.294366) (xy 419.523169 -43.343495) (xy 419.587179 -43.39896) (xy 419.645627 -43.460258)
			(xy 419.697983 -43.526834) (xy 419.743773 -43.598086) (xy 419.782584 -43.673367) (xy 419.814063 -43.751997)
			(xy 419.837924 -43.833264) (xy 419.853953 -43.91643) (xy 419.862004 -44.000744) (xy 419.862508 -44.043092)
			(xy 419.861992 -44.084128) (xy 419.854429 -44.165852) (xy 419.839374 -44.246533) (xy 419.816957 -44.325485)
			(xy 419.787367 -44.402039) (xy 419.750856 -44.475543) (xy 419.707734 -44.545375) (xy 419.658366 -44.610941)
			(xy 419.603173 -44.671683) (xy 419.542623 -44.727088) (xy 419.51021 -44.75226) (xy 419.499542 -44.760134)
			(xy 419.489128 -44.784264) (xy 419.498526 -44.883324) (xy 419.499299 -44.889708) (xy 419.50368 -44.901794)
			(xy 419.507162 -44.9072) (xy 419.510886 -44.91232) (xy 419.520407 -44.920663) (xy 419.525958 -44.92371)
			(xy 419.526466 -44.923964) (xy 419.52672 -44.923964) (xy 419.563283 -44.942698) (xy 419.633108 -44.985997)
			(xy 419.698642 -45.035551) (xy 419.759329 -45.090936) (xy 419.81465 -45.151681) (xy 419.864134 -45.217268)
			(xy 419.90736 -45.287139) (xy 419.943959 -45.360697) (xy 419.97362 -45.437317) (xy 419.99609 -45.516346)
			(xy 420.011177 -45.597109) (xy 420.014718 -45.635348) (xy 420.242996 -45.635348) (xy 420.242996 -45.550652)
			(xy 420.251047 -45.466338) (xy 420.267076 -45.383172) (xy 420.290937 -45.301905) (xy 420.322416 -45.223275)
			(xy 420.361227 -45.147994) (xy 420.407017 -45.076742) (xy 420.459373 -45.010166) (xy 420.517821 -44.948868)
			(xy 420.581831 -44.893403) (xy 420.650823 -44.844274) (xy 420.724173 -44.801925) (xy 420.801216 -44.766741)
			(xy 420.881255 -44.739039) (xy 420.963564 -44.719071) (xy 421.047399 -44.707018) (xy 421.132 -44.702988)
			(xy 421.216601 -44.707018) (xy 421.300436 -44.719071) (xy 421.382745 -44.739039) (xy 421.462784 -44.766741)
			(xy 421.539827 -44.801925) (xy 421.613177 -44.844274) (xy 421.682169 -44.893403) (xy 421.746179 -44.948868)
			(xy 421.804627 -45.010166) (xy 421.856983 -45.076742) (xy 421.902773 -45.147994) (xy 421.941584 -45.223275)
			(xy 421.973063 -45.301905) (xy 421.996924 -45.383172) (xy 422.012953 -45.466338) (xy 422.021004 -45.550652)
			(xy 422.021508 -45.593) (xy 422.021004 -45.635348) (xy 422.012953 -45.719662) (xy 421.996924 -45.802828)
			(xy 421.973063 -45.884095) (xy 421.941584 -45.962725) (xy 421.902773 -46.038006) (xy 421.856983 -46.109258)
			(xy 421.820187 -46.156048) (xy 423.811696 -46.156048) (xy 423.811696 -46.071352) (xy 423.819747 -45.987038)
			(xy 423.835776 -45.903872) (xy 423.859637 -45.822605) (xy 423.891116 -45.743975) (xy 423.929927 -45.668694)
			(xy 423.975717 -45.597442) (xy 424.028073 -45.530866) (xy 424.086521 -45.469568) (xy 424.150531 -45.414103)
			(xy 424.219523 -45.364974) (xy 424.292873 -45.322625) (xy 424.369916 -45.287441) (xy 424.449955 -45.259739)
			(xy 424.532264 -45.239771) (xy 424.616099 -45.227718) (xy 424.7007 -45.223688) (xy 424.785301 -45.227718)
			(xy 424.869136 -45.239771) (xy 424.951445 -45.259739) (xy 425.031484 -45.287441) (xy 425.108527 -45.322625)
			(xy 425.181877 -45.364974) (xy 425.250869 -45.414103) (xy 425.314879 -45.469568) (xy 425.373327 -45.530866)
			(xy 425.425683 -45.597442) (xy 425.471473 -45.668694) (xy 425.510284 -45.743975) (xy 425.541763 -45.822605)
			(xy 425.565624 -45.903872) (xy 425.581653 -45.987038) (xy 425.589704 -46.071352) (xy 425.590208 -46.1137)
			(xy 425.589704 -46.156048) (xy 425.581653 -46.240362) (xy 425.565624 -46.323528) (xy 425.541763 -46.404795)
			(xy 425.510284 -46.483425) (xy 425.471473 -46.558706) (xy 425.425683 -46.629958) (xy 425.373327 -46.696534)
			(xy 425.314879 -46.757832) (xy 425.250869 -46.813297) (xy 425.181877 -46.862426) (xy 425.108527 -46.904775)
			(xy 425.031484 -46.939959) (xy 424.951445 -46.967661) (xy 424.869136 -46.987629) (xy 424.785301 -46.999682)
			(xy 424.7007 -47.003713) (xy 424.616099 -46.999682) (xy 424.532264 -46.987629) (xy 424.449955 -46.967661)
			(xy 424.369916 -46.939959) (xy 424.292873 -46.904775) (xy 424.219523 -46.862426) (xy 424.150531 -46.813297)
			(xy 424.086521 -46.757832) (xy 424.028073 -46.696534) (xy 423.975717 -46.629958) (xy 423.929927 -46.558706)
			(xy 423.891116 -46.483425) (xy 423.859637 -46.404795) (xy 423.835776 -46.323528) (xy 423.819747 -46.240362)
			(xy 423.811696 -46.156048) (xy 421.820187 -46.156048) (xy 421.804627 -46.175834) (xy 421.746179 -46.237132)
			(xy 421.682169 -46.292597) (xy 421.613177 -46.341726) (xy 421.539827 -46.384075) (xy 421.462784 -46.419259)
			(xy 421.382745 -46.446961) (xy 421.300436 -46.466929) (xy 421.216601 -46.478982) (xy 421.132 -46.483013)
			(xy 421.047399 -46.478982) (xy 420.963564 -46.466929) (xy 420.881255 -46.446961) (xy 420.801216 -46.419259)
			(xy 420.724173 -46.384075) (xy 420.650823 -46.341726) (xy 420.581831 -46.292597) (xy 420.517821 -46.237132)
			(xy 420.459373 -46.175834) (xy 420.407017 -46.109258) (xy 420.361227 -46.038006) (xy 420.322416 -45.962725)
			(xy 420.290937 -45.884095) (xy 420.267076 -45.802828) (xy 420.251047 -45.719662) (xy 420.242996 -45.635348)
			(xy 420.014718 -45.635348) (xy 420.018753 -45.67892) (xy 420.019226 -45.72) (xy 420.018733 -45.761102)
			(xy 420.011149 -45.842955) (xy 419.996044 -45.92376) (xy 419.973548 -46.002825) (xy 419.943853 -46.079478)
			(xy 419.907212 -46.153065) (xy 419.863938 -46.222956) (xy 419.814399 -46.288557) (xy 419.759019 -46.349307)
			(xy 419.698271 -46.404688) (xy 419.632671 -46.454227) (xy 419.56278 -46.497503) (xy 419.489195 -46.534146)
			(xy 419.412543 -46.563842) (xy 419.333477 -46.58634) (xy 419.252673 -46.601446) (xy 419.17082 -46.609033)
			(xy 419.129718 -46.609508) (xy 419.091902 -46.60908) (xy 419.016545 -46.602624) (xy 418.942007 -46.589802)
			(xy 418.868825 -46.570704) (xy 418.833046 -46.558454) (xy 418.82651 -46.556436) (xy 418.812866 -46.55553)
			(xy 418.806122 -46.556676) (xy 418.799539 -46.558129) (xy 418.787439 -46.564061) (xy 418.782246 -46.56836)
			(xy 418.715698 -46.62678) (xy 418.710736 -46.631413) (xy 418.703272 -46.642747) (xy 418.700966 -46.649132)
			(xy 418.69868 -46.655736) (xy 418.697918 -46.668944) (xy 418.699442 -46.675802) (xy 418.708786 -46.722038)
			(xy 418.718845 -46.815834) (xy 418.719508 -46.863) (xy 418.719033 -46.904102) (xy 418.711448 -46.985957)
			(xy 418.696343 -47.066762) (xy 418.673847 -47.145829) (xy 418.644151 -47.222483) (xy 418.607509 -47.29607)
			(xy 418.564234 -47.365962) (xy 418.514694 -47.431563) (xy 418.459313 -47.492313) (xy 418.398563 -47.547694)
			(xy 418.332962 -47.597234) (xy 418.26307 -47.640509) (xy 418.189483 -47.677151) (xy 418.112829 -47.706847)
			(xy 418.033762 -47.729343) (xy 417.952957 -47.744448) (xy 417.871102 -47.752033) (xy 417.83 -47.752508)
			(xy 417.829492 -47.752508) (xy 417.78316 -47.751902) (xy 417.691002 -47.742231) (xy 417.600348 -47.723035)
			(xy 417.512179 -47.694523) (xy 417.469574 -47.676308) (xy 417.459632 -47.672502) (xy 417.438368 -47.672502)
			(xy 417.428426 -47.676308) (xy 417.385823 -47.69453) (xy 417.297656 -47.723048) (xy 417.207 -47.74224)
			(xy 417.11484 -47.7519) (xy 417.068508 -47.752508) (xy 417.068 -47.752508) (xy 417.025652 -47.752004)
			(xy 416.941338 -47.743953) (xy 416.858172 -47.727924) (xy 416.776905 -47.704063) (xy 416.698275 -47.672584)
			(xy 416.622994 -47.633773) (xy 416.551742 -47.587983) (xy 416.485166 -47.535627) (xy 416.423868 -47.477179)
			(xy 416.368403 -47.413169) (xy 416.319274 -47.344177) (xy 416.276925 -47.270827) (xy 416.241741 -47.193784)
			(xy 416.214039 -47.113745) (xy 416.194071 -47.031436) (xy 416.182018 -46.947601) (xy 416.177988 -46.863)
			(xy 410.1084 -46.863) (xy 411.439868 -48.194468) (xy 411.442916 -48.197262) (xy 411.44317 -48.197516)
			(xy 411.450931 -48.203492) (xy 411.469525 -48.209595) (xy 411.489051 -48.208276) (xy 411.498034 -48.204374)
			(xy 411.599126 -48.155352) (xy 411.61462 -48.12665) (xy 411.612588 -48.110648) (xy 411.609735 -48.084771)
			(xy 411.606683 -48.032795) (xy 411.606492 -48.006762) (xy 411.606492 -48.006) (xy 411.606976 -47.964075)
			(xy 411.614867 -47.880596) (xy 411.630579 -47.798231) (xy 411.653972 -47.717709) (xy 411.68484 -47.639747)
			(xy 411.722907 -47.565036) (xy 411.767837 -47.494238) (xy 411.819229 -47.427983) (xy 411.876629 -47.366859)
			(xy 411.939526 -47.311407) (xy 412.007363 -47.262121) (xy 412.079537 -47.219438) (xy 412.155407 -47.183736)
			(xy 412.2343 -47.155332) (xy 412.315517 -47.134479) (xy 412.398335 -47.121362) (xy 412.48202 -47.116097)
			(xy 412.56583 -47.118731) (xy 412.649019 -47.12924) (xy 412.73085 -47.147532) (xy 412.810597 -47.173443)
			(xy 412.887551 -47.206744) (xy 412.96103 -47.24714) (xy 413.030382 -47.294271) (xy 413.09499 -47.347719)
			(xy 413.154281 -47.40701) (xy 413.207729 -47.471618) (xy 413.25486 -47.54097) (xy 413.295256 -47.614449)
			(xy 413.328557 -47.691403) (xy 413.354468 -47.77115) (xy 413.37276 -47.852981) (xy 413.383269 -47.93617)
			(xy 413.385014 -47.991706) (xy 413.533586 -47.991706) (xy 413.533586 -47.90701) (xy 413.541637 -47.822696)
			(xy 413.557666 -47.73953) (xy 413.581527 -47.658263) (xy 413.613006 -47.579633) (xy 413.651817 -47.504352)
			(xy 413.697607 -47.4331) (xy 413.749963 -47.366524) (xy 413.808411 -47.305226) (xy 413.872421 -47.249761)
			(xy 413.941413 -47.200632) (xy 414.014763 -47.158283) (xy 414.091806 -47.123099) (xy 414.171845 -47.095397)
			(xy 414.254154 -47.075429) (xy 414.337989 -47.063376) (xy 414.42259 -47.059346) (xy 414.507191 -47.063376)
			(xy 414.591026 -47.075429) (xy 414.673335 -47.095397) (xy 414.753374 -47.123099) (xy 414.830417 -47.158283)
			(xy 414.903767 -47.200632) (xy 414.972759 -47.249761) (xy 415.036769 -47.305226) (xy 415.095217 -47.366524)
			(xy 415.147573 -47.4331) (xy 415.193363 -47.504352) (xy 415.232174 -47.579633) (xy 415.263653 -47.658263)
			(xy 415.287514 -47.73953) (xy 415.303543 -47.822696) (xy 415.311594 -47.90701) (xy 415.312098 -47.949358)
			(xy 415.311594 -47.991706) (xy 415.303543 -48.07602) (xy 415.287514 -48.159186) (xy 415.263653 -48.240453)
			(xy 415.232174 -48.319083) (xy 415.193363 -48.394364) (xy 415.147573 -48.465616) (xy 415.095217 -48.532192)
			(xy 415.036769 -48.59349) (xy 414.972759 -48.648955) (xy 414.903767 -48.698084) (xy 414.830417 -48.740433)
			(xy 414.753374 -48.775617) (xy 414.673335 -48.803319) (xy 414.591026 -48.823287) (xy 414.507191 -48.83534)
			(xy 414.42259 -48.839371) (xy 414.337989 -48.83534) (xy 414.254154 -48.823287) (xy 414.171845 -48.803319)
			(xy 414.091806 -48.775617) (xy 414.014763 -48.740433) (xy 413.941413 -48.698084) (xy 413.872421 -48.648955)
			(xy 413.808411 -48.59349) (xy 413.749963 -48.532192) (xy 413.697607 -48.465616) (xy 413.651817 -48.394364)
			(xy 413.613006 -48.319083) (xy 413.581527 -48.240453) (xy 413.557666 -48.159186) (xy 413.541637 -48.07602)
			(xy 413.533586 -47.991706) (xy 413.385014 -47.991706) (xy 413.385903 -48.01998) (xy 413.380638 -48.103665)
			(xy 413.367521 -48.186483) (xy 413.346668 -48.2677) (xy 413.318264 -48.346593) (xy 413.282562 -48.422463)
			(xy 413.239879 -48.494637) (xy 413.190593 -48.562474) (xy 413.135141 -48.625371) (xy 413.074017 -48.682771)
			(xy 413.007762 -48.734163) (xy 412.936964 -48.779093) (xy 412.862253 -48.81716) (xy 412.784291 -48.848028)
			(xy 412.703769 -48.871421) (xy 412.621404 -48.887133) (xy 412.538179 -48.895) (xy 419.225988 -48.895)
			(xy 419.230018 -48.810399) (xy 419.242071 -48.726564) (xy 419.262039 -48.644255) (xy 419.289741 -48.564216)
			(xy 419.324925 -48.487173) (xy 419.367274 -48.413823) (xy 419.416403 -48.344831) (xy 419.471868 -48.280821)
			(xy 419.533166 -48.222373) (xy 419.599742 -48.170017) (xy 419.670994 -48.124227) (xy 419.746275 -48.085416)
			(xy 419.824905 -48.053937) (xy 419.906172 -48.030076) (xy 419.989338 -48.014047) (xy 420.073652 -48.005996)
			(xy 420.116 -48.005492) (xy 420.168445 -48.006254) (xy 420.272604 -48.018606) (xy 420.323772 -48.03013)
			(xy 420.33234 -48.031758) (xy 420.349665 -48.029875) (xy 420.365378 -48.022337) (xy 420.371778 -48.016414)
			(xy 420.403094 -47.985425) (xy 420.470852 -47.929109) (xy 420.543848 -47.87977) (xy 420.621366 -47.837892)
			(xy 420.702645 -47.803886) (xy 420.78689 -47.778086) (xy 420.873272 -47.760744) (xy 420.960947 -47.75203)
			(xy 421.005 -47.751492) (xy 421.046587 -47.751959) (xy 421.129397 -47.759724) (xy 421.211121 -47.775184)
			(xy 421.291045 -47.798207) (xy 421.368471 -47.828589) (xy 421.442723 -47.866067) (xy 421.513151 -47.910312)
			(xy 421.579142 -47.960939) (xy 421.640119 -48.017504) (xy 421.695549 -48.079515) (xy 421.744948 -48.14643)
			(xy 421.762379 -48.175348) (xy 422.802046 -48.175348) (xy 422.802046 -48.090652) (xy 422.810097 -48.006338)
			(xy 422.826126 -47.923172) (xy 422.849987 -47.841905) (xy 422.881466 -47.763275) (xy 422.920277 -47.687994)
			(xy 422.966067 -47.616742) (xy 423.018423 -47.550166) (xy 423.076871 -47.488868) (xy 423.140881 -47.433403)
			(xy 423.209873 -47.384274) (xy 423.283223 -47.341925) (xy 423.360266 -47.306741) (xy 423.440305 -47.279039)
			(xy 423.522614 -47.259071) (xy 423.606449 -47.247018) (xy 423.69105 -47.242988) (xy 423.775651 -47.247018)
			(xy 423.859486 -47.259071) (xy 423.941795 -47.279039) (xy 424.021834 -47.306741) (xy 424.098877 -47.341925)
			(xy 424.172227 -47.384274) (xy 424.241219 -47.433403) (xy 424.305229 -47.488868) (xy 424.363677 -47.550166)
			(xy 424.416033 -47.616742) (xy 424.461823 -47.687994) (xy 424.500634 -47.763275) (xy 424.532113 -47.841905)
			(xy 424.555974 -47.923172) (xy 424.572003 -48.006338) (xy 424.580054 -48.090652) (xy 424.580558 -48.133)
			(xy 424.580054 -48.175348) (xy 424.572003 -48.259662) (xy 424.555974 -48.342828) (xy 424.532113 -48.424095)
			(xy 424.500634 -48.502725) (xy 424.461823 -48.578006) (xy 424.416033 -48.649258) (xy 424.363677 -48.715834)
			(xy 424.305229 -48.777132) (xy 424.241219 -48.832597) (xy 424.172227 -48.881726) (xy 424.098877 -48.924075)
			(xy 424.021834 -48.959259) (xy 423.941795 -48.986961) (xy 423.859486 -49.006929) (xy 423.775651 -49.018982)
			(xy 423.69105 -49.023013) (xy 423.606449 -49.018982) (xy 423.522614 -49.006929) (xy 423.440305 -48.986961)
			(xy 423.360266 -48.959259) (xy 423.283223 -48.924075) (xy 423.209873 -48.881726) (xy 423.140881 -48.832597)
			(xy 423.076871 -48.777132) (xy 423.018423 -48.715834) (xy 422.966067 -48.649258) (xy 422.920277 -48.578006)
			(xy 422.881466 -48.502725) (xy 422.849987 -48.424095) (xy 422.826126 -48.342828) (xy 422.810097 -48.259662)
			(xy 422.802046 -48.175348) (xy 421.762379 -48.175348) (xy 421.787885 -48.217664) (xy 421.80637 -48.25492)
			(xy 421.811813 -48.264981) (xy 421.829645 -48.27927) (xy 421.84066 -48.282352) (xy 421.882124 -48.292487)
			(xy 421.963055 -48.319635) (xy 422.041014 -48.35441) (xy 422.115285 -48.396491) (xy 422.185183 -48.445492)
			(xy 422.250066 -48.500963) (xy 422.309338 -48.562394) (xy 422.362454 -48.629219) (xy 422.408926 -48.700824)
			(xy 422.448325 -48.776551) (xy 422.48029 -48.855703) (xy 422.504528 -48.937553) (xy 422.520814 -49.021349)
			(xy 422.528999 -49.106318) (xy 422.529508 -49.149) (xy 422.529058 -49.189964) (xy 422.521531 -49.271546)
			(xy 422.506531 -49.352089) (xy 422.484186 -49.430912) (xy 422.454684 -49.507344) (xy 422.452678 -49.511388)
			(xy 425.6217 -49.511388) (xy 425.6217 -49.426692) (xy 425.629751 -49.342378) (xy 425.64578 -49.259212)
			(xy 425.669641 -49.177945) (xy 425.70112 -49.099315) (xy 425.739931 -49.024034) (xy 425.785721 -48.952782)
			(xy 425.838077 -48.886206) (xy 425.896525 -48.824908) (xy 425.960535 -48.769443) (xy 426.029527 -48.720314)
			(xy 426.102877 -48.677965) (xy 426.17992 -48.642781) (xy 426.259959 -48.615079) (xy 426.342268 -48.595111)
			(xy 426.426103 -48.583058) (xy 426.510704 -48.579028) (xy 426.595305 -48.583058) (xy 426.67914 -48.595111)
			(xy 426.761449 -48.615079) (xy 426.841488 -48.642781) (xy 426.918531 -48.677965) (xy 426.991881 -48.720314)
			(xy 427.060873 -48.769443) (xy 427.124883 -48.824908) (xy 427.183331 -48.886206) (xy 427.235687 -48.952782)
			(xy 427.281477 -49.024034) (xy 427.320288 -49.099315) (xy 427.351767 -49.177945) (xy 427.375628 -49.259212)
			(xy 427.391657 -49.342378) (xy 427.399708 -49.426692) (xy 427.400212 -49.46904) (xy 427.399708 -49.511388)
			(xy 427.391657 -49.595702) (xy 427.375628 -49.678868) (xy 427.351767 -49.760135) (xy 427.320288 -49.838765)
			(xy 427.281477 -49.914046) (xy 427.235687 -49.985298) (xy 427.183331 -50.051874) (xy 427.124883 -50.113172)
			(xy 427.060873 -50.168637) (xy 426.991881 -50.217766) (xy 426.918531 -50.260115) (xy 426.841488 -50.295299)
			(xy 426.761449 -50.323001) (xy 426.67914 -50.342969) (xy 426.595305 -50.355022) (xy 426.510704 -50.359053)
			(xy 426.426103 -50.355022) (xy 426.342268 -50.342969) (xy 426.259959 -50.323001) (xy 426.17992 -50.295299)
			(xy 426.102877 -50.260115) (xy 426.029527 -50.217766) (xy 425.960535 -50.168637) (xy 425.896525 -50.113172)
			(xy 425.838077 -50.051874) (xy 425.785721 -49.985298) (xy 425.739931 -49.914046) (xy 425.70112 -49.838765)
			(xy 425.669641 -49.760135) (xy 425.64578 -49.678868) (xy 425.629751 -49.595702) (xy 425.6217 -49.511388)
			(xy 422.452678 -49.511388) (xy 422.418277 -49.580739) (xy 422.397174 -49.615852) (xy 422.391586 -49.624996)
			(xy 422.388538 -49.64557) (xy 422.41089 -49.727866) (xy 422.41418 -49.73779) (xy 422.427284 -49.754053)
			(xy 422.43629 -49.759362) (xy 422.468964 -49.77703) (xy 422.531547 -49.817055) (xy 422.590567 -49.862166)
			(xy 422.645614 -49.91205) (xy 422.67124 -49.93894) (xy 422.671494 -49.939194) (xy 422.679746 -49.947179)
			(xy 422.701168 -49.955384) (xy 422.712642 -49.954942) (xy 422.791636 -49.948592) (xy 422.80315 -49.947106)
			(xy 422.823137 -49.935354) (xy 422.82999 -49.925986) (xy 422.854657 -49.889855) (xy 422.910069 -49.822149)
			(xy 422.971859 -49.76021) (xy 423.039431 -49.704635) (xy 423.112133 -49.655963) (xy 423.189261 -49.614662)
			(xy 423.270072 -49.581132) (xy 423.353783 -49.555697) (xy 423.439587 -49.538603) (xy 423.526655 -49.530014)
			(xy 423.5704 -49.529492) (xy 423.611502 -49.529967) (xy 423.693357 -49.537552) (xy 423.774162 -49.552657)
			(xy 423.853229 -49.575153) (xy 423.929883 -49.604849) (xy 424.00347 -49.641491) (xy 424.073362 -49.684766)
			(xy 424.138963 -49.734306) (xy 424.199713 -49.789687) (xy 424.255094 -49.850437) (xy 424.304634 -49.916038)
			(xy 424.347909 -49.98593) (xy 424.384551 -50.059517) (xy 424.414247 -50.136171) (xy 424.436743 -50.215238)
			(xy 424.451848 -50.296043) (xy 424.459433 -50.377898) (xy 424.459908 -50.419) (xy 424.459437 -50.460531)
			(xy 424.451712 -50.543232) (xy 424.436309 -50.624852) (xy 424.413363 -50.704681) (xy 424.383074 -50.782023)
			(xy 424.345707 -50.856204) (xy 424.301585 -50.926578) (xy 424.251095 -50.992532) (xy 424.194675 -51.05349)
			(xy 424.132817 -51.108923) (xy 424.06606 -51.158347) (xy 423.994986 -51.201331) (xy 423.920214 -51.237502)
			(xy 423.842396 -51.266543) (xy 423.762208 -51.288203) (xy 423.68035 -51.302292) (xy 423.63898 -51.305968)
			(xy 423.638726 -51.305968) (xy 423.629023 -51.307106) (xy 423.611515 -51.31574) (xy 423.60469 -51.322732)
			(xy 423.558208 -51.374548) (xy 423.552032 -51.382006) (xy 423.545375 -51.400171) (xy 423.545254 -51.409854)
			(xy 423.545254 -51.410108) (xy 423.545508 -51.435) (xy 423.545033 -51.476102) (xy 423.537448 -51.557957)
			(xy 423.522343 -51.638762) (xy 423.499847 -51.717829) (xy 423.470151 -51.794483) (xy 423.433509 -51.86807)
			(xy 423.390234 -51.937962) (xy 423.340694 -52.003563) (xy 423.285313 -52.064313) (xy 423.224563 -52.119694)
			(xy 423.158962 -52.169234) (xy 423.08907 -52.212509) (xy 423.015483 -52.249151) (xy 422.938829 -52.278847)
			(xy 422.859762 -52.301343) (xy 422.778957 -52.316448) (xy 422.697102 -52.324033) (xy 422.656 -52.324508)
			(xy 422.614905 -52.324034) (xy 422.533065 -52.316452) (xy 422.452274 -52.301352) (xy 422.373221 -52.278864)
			(xy 422.296579 -52.249178) (xy 422.223002 -52.212549) (xy 422.153118 -52.169289) (xy 422.087523 -52.119766)
			(xy 422.026777 -52.064403) (xy 421.971397 -52.003672) (xy 421.921855 -51.938091) (xy 421.878575 -51.86822)
			(xy 421.841924 -51.794654) (xy 421.812217 -51.71802) (xy 421.789706 -51.638973) (xy 421.774584 -51.558186)
			(xy 421.766978 -51.476349) (xy 421.766492 -51.435254) (xy 421.765909 -51.424729) (xy 421.757454 -51.405451)
			(xy 421.74198 -51.391178) (xy 421.732202 -51.387248) (xy 421.692214 -51.373037) (xy 421.614926 -51.337971)
			(xy 421.541331 -51.295702) (xy 421.472097 -51.246613) (xy 421.407855 -51.191152) (xy 421.349188 -51.129822)
			(xy 421.296632 -51.063183) (xy 421.250663 -50.991839) (xy 421.211701 -50.91644) (xy 421.180098 -50.837673)
			(xy 421.156144 -50.756253) (xy 421.140056 -50.672921) (xy 421.13198 -50.588435) (xy 421.131492 -50.546)
			(xy 421.131942 -50.505036) (xy 421.139469 -50.423454) (xy 421.154469 -50.342911) (xy 421.176814 -50.264088)
			(xy 421.206316 -50.187656) (xy 421.242723 -50.114261) (xy 421.263826 -50.079148) (xy 421.269414 -50.070004)
			(xy 421.272462 -50.04943) (xy 421.25011 -49.967134) (xy 421.246899 -49.957331) (xy 421.234057 -49.941211)
			(xy 421.225218 -49.935892) (xy 421.225218 -49.935638) (xy 421.22471 -49.935638) (xy 421.189161 -49.91639)
			(xy 421.121389 -49.872307) (xy 421.057898 -49.822256) (xy 420.999209 -49.766651) (xy 420.945808 -49.705949)
			(xy 420.898136 -49.640653) (xy 420.856585 -49.5713) (xy 420.83863 -49.53508) (xy 420.833301 -49.52501)
			(xy 420.815562 -49.51074) (xy 420.804594 -49.507648) (xy 420.804086 -49.507648) (xy 420.79799 -49.506124)
			(xy 420.791659 -49.504657) (xy 420.778667 -49.504657) (xy 420.772336 -49.506124) (xy 420.765838 -49.508073)
			(xy 420.754118 -49.514891) (xy 420.749222 -49.519586) (xy 420.717906 -49.550575) (xy 420.650148 -49.606891)
			(xy 420.577152 -49.65623) (xy 420.499634 -49.698108) (xy 420.418355 -49.732114) (xy 420.33411 -49.757914)
			(xy 420.247728 -49.775256) (xy 420.160053 -49.78397) (xy 420.116 -49.784508) (xy 420.073652 -49.784004)
			(xy 419.989338 -49.775953) (xy 419.906172 -49.759924) (xy 419.824905 -49.736063) (xy 419.746275 -49.704584)
			(xy 419.670994 -49.665773) (xy 419.599742 -49.619983) (xy 419.533166 -49.567627) (xy 419.471868 -49.509179)
			(xy 419.416403 -49.445169) (xy 419.367274 -49.376177) (xy 419.324925 -49.302827) (xy 419.289741 -49.225784)
			(xy 419.262039 -49.145745) (xy 419.242071 -49.063436) (xy 419.230018 -48.979601) (xy 419.225988 -48.895)
			(xy 412.538179 -48.895) (xy 412.537925 -48.895024) (xy 412.496 -48.895508) (xy 412.495238 -48.895508)
			(xy 412.469205 -48.895318) (xy 412.417229 -48.892266) (xy 412.391352 -48.889412) (xy 412.37535 -48.88738)
			(xy 412.346648 -48.902874) (xy 412.297626 -49.003966) (xy 412.293611 -49.013328) (xy 412.292562 -49.033656)
			(xy 412.299456 -49.052808) (xy 412.306008 -49.060608) (xy 412.30677 -49.06137) (xy 416.519614 -53.274214)
			(xy 416.526468 -53.281609) (xy 416.53421 -53.300208) (xy 416.5346 -53.310282) (xy 416.5346 -53.890348)
			(xy 418.871396 -53.890348) (xy 418.871396 -53.805652) (xy 418.879447 -53.721338) (xy 418.895476 -53.638172)
			(xy 418.919337 -53.556905) (xy 418.950816 -53.478275) (xy 418.989627 -53.402994) (xy 419.035417 -53.331742)
			(xy 419.087773 -53.265166) (xy 419.146221 -53.203868) (xy 419.210231 -53.148403) (xy 419.279223 -53.099274)
			(xy 419.352573 -53.056925) (xy 419.429616 -53.021741) (xy 419.509655 -52.994039) (xy 419.591964 -52.974071)
			(xy 419.675799 -52.962018) (xy 419.7604 -52.957988) (xy 419.845001 -52.962018) (xy 419.928836 -52.974071)
			(xy 420.011145 -52.994039) (xy 420.091184 -53.021741) (xy 420.168227 -53.056925) (xy 420.241577 -53.099274)
			(xy 420.310569 -53.148403) (xy 420.374579 -53.203868) (xy 420.433027 -53.265166) (xy 420.485383 -53.331742)
			(xy 420.531173 -53.402994) (xy 420.569984 -53.478275) (xy 420.601463 -53.556905) (xy 420.625324 -53.638172)
			(xy 420.641353 -53.721338) (xy 420.649404 -53.805652) (xy 420.649908 -53.848) (xy 420.649404 -53.890348)
			(xy 420.641353 -53.974662) (xy 420.625324 -54.057828) (xy 420.601463 -54.139095) (xy 420.569984 -54.217725)
			(xy 420.531173 -54.293006) (xy 420.485383 -54.364258) (xy 420.433027 -54.430834) (xy 420.374579 -54.492132)
			(xy 420.310569 -54.547597) (xy 420.241577 -54.596726) (xy 420.168227 -54.639075) (xy 420.091184 -54.674259)
			(xy 420.011145 -54.701961) (xy 419.928836 -54.721929) (xy 419.845001 -54.733982) (xy 419.7604 -54.738013)
			(xy 419.675799 -54.733982) (xy 419.591964 -54.721929) (xy 419.509655 -54.701961) (xy 419.429616 -54.674259)
			(xy 419.352573 -54.639075) (xy 419.279223 -54.596726) (xy 419.210231 -54.547597) (xy 419.146221 -54.492132)
			(xy 419.087773 -54.430834) (xy 419.035417 -54.364258) (xy 418.989627 -54.293006) (xy 418.950816 -54.217725)
			(xy 418.919337 -54.139095) (xy 418.895476 -54.057828) (xy 418.879447 -53.974662) (xy 418.871396 -53.890348)
			(xy 416.5346 -53.890348) (xy 416.5346 -60.099956) (xy 419.2359 -60.099956) (xy 419.239883 -59.885707)
			(xy 419.251827 -59.671755) (xy 419.271716 -59.458394) (xy 419.299521 -59.24592) (xy 419.335205 -59.034627)
			(xy 419.378718 -58.824805) (xy 419.43 -58.616747) (xy 419.48898 -58.410738) (xy 419.555576 -58.207063)
			(xy 419.629697 -58.006005) (xy 419.711241 -57.807841) (xy 419.800093 -57.612845) (xy 419.896133 -57.421286)
			(xy 419.999226 -57.233429) (xy 420.109231 -57.049535) (xy 420.225995 -56.869856) (xy 420.349357 -56.694641)
			(xy 420.479146 -56.524133) (xy 420.615184 -56.358567) (xy 420.757281 -56.198172) (xy 420.905243 -56.043169)
			(xy 421.058863 -55.893774) (xy 421.217931 -55.750191) (xy 421.382225 -55.612621) (xy 421.55152 -55.481252)
			(xy 421.72558 -55.356267) (xy 421.904166 -55.237838) (xy 422.08703 -55.126129) (xy 422.273921 -55.021294)
			(xy 422.464578 -54.923479) (xy 422.65874 -54.832817) (xy 422.856138 -54.749436) (xy 423.056499 -54.673449)
			(xy 423.259545 -54.604962) (xy 423.464997 -54.54407) (xy 423.67257 -54.490856) (xy 423.881978 -54.445395)
			(xy 424.092931 -54.407749) (xy 424.305137 -54.37797) (xy 424.518304 -54.356099) (xy 424.732136 -54.342167)
			(xy 424.946338 -54.336193) (xy 425.160615 -54.338185) (xy 425.374669 -54.34814) (xy 425.588205 -54.366044)
			(xy 425.800928 -54.391873) (xy 426.012545 -54.425592) (xy 426.222761 -54.467153) (xy 426.431288 -54.516498)
			(xy 426.637836 -54.573561) (xy 426.84212 -54.638262) (xy 427.043859 -54.710511) (xy 427.242772 -54.790209)
			(xy 427.438586 -54.877246) (xy 427.631029 -54.9715) (xy 427.819836 -55.072843) (xy 428.004745 -55.181134)
			(xy 428.185501 -55.296223) (xy 428.361855 -55.417951) (xy 428.533562 -55.54615) (xy 428.700385 -55.680643)
			(xy 428.862094 -55.821243) (xy 429.018465 -55.967758) (xy 429.169282 -56.119983) (xy 429.314337 -56.277709)
			(xy 429.453429 -56.440718) (xy 429.586365 -56.608784) (xy 429.712963 -56.781675) (xy 429.833046 -56.959153)
			(xy 429.94645 -57.140971) (xy 430.053018 -57.326879) (xy 430.152601 -57.516619) (xy 430.245063 -57.70993)
			(xy 430.330276 -57.906544) (xy 430.408122 -58.10619) (xy 430.478493 -58.308591) (xy 430.541292 -58.513468)
			(xy 430.596432 -58.720538) (xy 430.643838 -58.929514) (xy 430.683443 -59.140108) (xy 430.715193 -59.352028)
			(xy 430.739044 -59.564982) (xy 430.754963 -59.778676) (xy 430.762928 -59.992813) (xy 430.763426 -60.099956)
			(xy 430.762928 -60.207099) (xy 430.754963 -60.421236) (xy 430.739044 -60.63493) (xy 430.715193 -60.847884)
			(xy 430.683443 -61.059804) (xy 430.643838 -61.270398) (xy 430.596432 -61.479374) (xy 430.541292 -61.686444)
			(xy 430.478493 -61.891321) (xy 430.408122 -62.093722) (xy 430.330276 -62.293368) (xy 430.245063 -62.489982)
			(xy 430.152601 -62.683293) (xy 430.053018 -62.873033) (xy 429.94645 -63.058941) (xy 429.833046 -63.240759)
			(xy 429.712963 -63.418237) (xy 429.586365 -63.591128) (xy 429.453429 -63.759194) (xy 429.314337 -63.922203)
			(xy 429.169282 -64.079929) (xy 429.018465 -64.232154) (xy 428.862094 -64.378669) (xy 428.700385 -64.519269)
			(xy 428.533562 -64.653762) (xy 428.361855 -64.781961) (xy 428.185501 -64.903689) (xy 428.004745 -65.018778)
			(xy 427.819836 -65.127069) (xy 427.631029 -65.228412) (xy 427.438586 -65.322666) (xy 427.242772 -65.409703)
			(xy 427.043859 -65.489401) (xy 426.84212 -65.56165) (xy 426.637836 -65.626351) (xy 426.431288 -65.683414)
			(xy 426.222761 -65.732759) (xy 426.012545 -65.77432) (xy 425.800928 -65.808039) (xy 425.588205 -65.833868)
			(xy 425.374669 -65.851772) (xy 425.160615 -65.861727) (xy 424.946338 -65.863719) (xy 424.732136 -65.857745)
			(xy 424.518304 -65.843813) (xy 424.305137 -65.821942) (xy 424.092931 -65.792163) (xy 423.881978 -65.754517)
			(xy 423.67257 -65.709056) (xy 423.464997 -65.655842) (xy 423.259545 -65.59495) (xy 423.056499 -65.526463)
			(xy 422.856138 -65.450476) (xy 422.65874 -65.367095) (xy 422.464578 -65.276433) (xy 422.273921 -65.178618)
			(xy 422.08703 -65.073783) (xy 421.904166 -64.962074) (xy 421.72558 -64.843645) (xy 421.55152 -64.71866)
			(xy 421.382225 -64.587291) (xy 421.217931 -64.449721) (xy 421.058863 -64.306138) (xy 420.905243 -64.156743)
			(xy 420.757281 -64.00174) (xy 420.615184 -63.841345) (xy 420.479146 -63.675779) (xy 420.349357 -63.505271)
			(xy 420.225995 -63.330056) (xy 420.109231 -63.150377) (xy 419.999226 -62.966483) (xy 419.896133 -62.778626)
			(xy 419.800093 -62.587067) (xy 419.711241 -62.392071) (xy 419.629697 -62.193907) (xy 419.555576 -61.992849)
			(xy 419.48898 -61.789174) (xy 419.43 -61.583165) (xy 419.378718 -61.375107) (xy 419.335205 -61.165285)
			(xy 419.299521 -60.953992) (xy 419.271716 -60.741518) (xy 419.251827 -60.528157) (xy 419.239883 -60.314205)
			(xy 419.2359 -60.099956) (xy 416.5346 -60.099956) (xy 416.5346 -89.000076) (xy 422.864788 -89.000076)
			(xy 422.864788 -84.000086) (xy 422.865283 -83.899245) (xy 422.873201 -83.697718) (xy 422.889025 -83.496658)
			(xy 422.91273 -83.296374) (xy 422.94428 -83.097175) (xy 422.983626 -82.899368) (xy 423.030708 -82.703259)
			(xy 423.085453 -82.509149) (xy 423.147776 -82.317338) (xy 423.217581 -82.128121) (xy 423.294762 -81.941792)
			(xy 423.379198 -81.758635) (xy 423.47076 -81.578935) (xy 423.569306 -81.402969) (xy 423.674684 -81.231006)
			(xy 423.786733 -81.063314) (xy 423.905279 -80.90015) (xy 424.030139 -80.741765) (xy 424.161121 -80.588405)
			(xy 424.298023 -80.440305) (xy 424.440633 -80.297695) (xy 424.588733 -80.160793) (xy 424.742093 -80.029811)
			(xy 424.900478 -79.904951) (xy 425.063642 -79.786405) (xy 425.231334 -79.674356) (xy 425.403297 -79.568978)
			(xy 425.579263 -79.470432) (xy 425.758963 -79.37887) (xy 425.94212 -79.294434) (xy 426.128449 -79.217253)
			(xy 426.317666 -79.147448) (xy 426.509477 -79.085125) (xy 426.703587 -79.03038) (xy 426.899696 -78.983298)
			(xy 427.097503 -78.943952) (xy 427.296702 -78.912402) (xy 427.496986 -78.888697) (xy 427.698046 -78.872873)
			(xy 427.899573 -78.864955) (xy 428.101255 -78.864955) (xy 428.302782 -78.872873) (xy 428.503842 -78.888697)
			(xy 428.704126 -78.912402) (xy 428.903325 -78.943952) (xy 429.101132 -78.983298) (xy 429.297241 -79.03038)
			(xy 429.491351 -79.085125) (xy 429.683162 -79.147448) (xy 429.872379 -79.217253) (xy 430.058708 -79.294434)
			(xy 430.241865 -79.37887) (xy 430.421565 -79.470432) (xy 430.597531 -79.568978) (xy 430.769494 -79.674356)
			(xy 430.937186 -79.786405) (xy 431.10035 -79.904951) (xy 431.258735 -80.029811) (xy 431.412095 -80.160793)
			(xy 431.560195 -80.297695) (xy 431.702805 -80.440305) (xy 431.839707 -80.588405) (xy 431.970689 -80.741765)
			(xy 432.095549 -80.90015) (xy 432.214095 -81.063314) (xy 432.326144 -81.231006) (xy 432.431522 -81.402969)
			(xy 432.435732 -81.410486) (xy 446.774312 -81.410486) (xy 446.774312 -81.32579) (xy 446.782363 -81.241476)
			(xy 446.798392 -81.15831) (xy 446.822253 -81.077043) (xy 446.853732 -80.998413) (xy 446.892543 -80.923132)
			(xy 446.938333 -80.85188) (xy 446.990689 -80.785304) (xy 447.049137 -80.724006) (xy 447.113147 -80.668541)
			(xy 447.182139 -80.619412) (xy 447.255489 -80.577063) (xy 447.332532 -80.541879) (xy 447.412571 -80.514177)
			(xy 447.49488 -80.494209) (xy 447.578715 -80.482156) (xy 447.663316 -80.478126) (xy 447.747917 -80.482156)
			(xy 447.831752 -80.494209) (xy 447.914061 -80.514177) (xy 447.9941 -80.541879) (xy 448.071143 -80.577063)
			(xy 448.144493 -80.619412) (xy 448.213485 -80.668541) (xy 448.277495 -80.724006) (xy 448.335943 -80.785304)
			(xy 448.388299 -80.85188) (xy 448.434089 -80.923132) (xy 448.4729 -80.998413) (xy 448.504379 -81.077043)
			(xy 448.52824 -81.15831) (xy 448.544269 -81.241476) (xy 448.55232 -81.32579) (xy 448.552824 -81.368138)
			(xy 448.55232 -81.410486) (xy 448.544269 -81.4948) (xy 448.52824 -81.577966) (xy 448.504379 -81.659233)
			(xy 448.4729 -81.737863) (xy 448.434089 -81.813144) (xy 448.388299 -81.884396) (xy 448.335943 -81.950972)
			(xy 448.277495 -82.01227) (xy 448.213485 -82.067735) (xy 448.144493 -82.116864) (xy 448.071143 -82.159213)
			(xy 447.9941 -82.194397) (xy 447.914061 -82.222099) (xy 447.831752 -82.242067) (xy 447.747917 -82.25412)
			(xy 447.663316 -82.258151) (xy 447.578715 -82.25412) (xy 447.49488 -82.242067) (xy 447.412571 -82.222099)
			(xy 447.332532 -82.194397) (xy 447.255489 -82.159213) (xy 447.182139 -82.116864) (xy 447.113147 -82.067735)
			(xy 447.049137 -82.01227) (xy 446.990689 -81.950972) (xy 446.938333 -81.884396) (xy 446.892543 -81.813144)
			(xy 446.853732 -81.737863) (xy 446.822253 -81.659233) (xy 446.798392 -81.577966) (xy 446.782363 -81.4948)
			(xy 446.774312 -81.410486) (xy 432.435732 -81.410486) (xy 432.530068 -81.578935) (xy 432.62163 -81.758635)
			(xy 432.706066 -81.941792) (xy 432.783247 -82.128121) (xy 432.853052 -82.317338) (xy 432.915375 -82.509149)
			(xy 432.97012 -82.703259) (xy 433.017202 -82.899368) (xy 433.056548 -83.097175) (xy 433.088098 -83.296374)
			(xy 433.111803 -83.496658) (xy 433.127627 -83.697718) (xy 433.135545 -83.899245) (xy 433.13604 -84.000086)
			(xy 433.13604 -87.68969) (xy 441.606178 -87.68969) (xy 441.60668 -87.646571) (xy 441.615029 -87.560739)
			(xy 441.631649 -87.476118) (xy 441.656382 -87.393503) (xy 441.672218 -87.353394) (xy 441.675559 -87.344026)
			(xy 441.675556 -87.324156) (xy 441.672218 -87.314786) (xy 441.656376 -87.27468) (xy 441.631644 -87.192064)
			(xy 441.615026 -87.107443) (xy 441.606679 -87.02161) (xy 441.60668 -86.935372) (xy 441.615029 -86.849539)
			(xy 441.631649 -86.764918) (xy 441.656382 -86.682303) (xy 441.672218 -86.642194) (xy 441.675559 -86.632826)
			(xy 441.675556 -86.612956) (xy 441.672218 -86.603586) (xy 441.656376 -86.56348) (xy 441.631644 -86.480864)
			(xy 441.615026 -86.396243) (xy 441.606679 -86.31041) (xy 441.60668 -86.224172) (xy 441.615029 -86.138339)
			(xy 441.631649 -86.053718) (xy 441.656382 -85.971103) (xy 441.672218 -85.930994) (xy 441.675559 -85.921626)
			(xy 441.675556 -85.901756) (xy 441.672218 -85.892386) (xy 441.656376 -85.85228) (xy 441.631644 -85.769664)
			(xy 441.615026 -85.685043) (xy 441.606679 -85.59921) (xy 441.60668 -85.512972) (xy 441.615029 -85.427139)
			(xy 441.631649 -85.342518) (xy 441.656382 -85.259903) (xy 441.672218 -85.219794) (xy 441.675559 -85.210426)
			(xy 441.675556 -85.190556) (xy 441.672218 -85.181186) (xy 441.656378 -85.141079) (xy 441.631649 -85.058463)
			(xy 441.615033 -84.973841) (xy 441.606686 -84.888009) (xy 441.606178 -84.84489) (xy 441.606657 -84.803788)
			(xy 441.614243 -84.721934) (xy 441.629348 -84.641129) (xy 441.651845 -84.562063) (xy 441.681541 -84.48541)
			(xy 441.718183 -84.411823) (xy 441.761458 -84.341932) (xy 441.810998 -84.276331) (xy 441.866378 -84.215581)
			(xy 441.927128 -84.1602) (xy 441.992729 -84.110661) (xy 442.06262 -84.067385) (xy 442.136206 -84.030743)
			(xy 442.212859 -84.001047) (xy 442.291925 -83.978549) (xy 442.37273 -83.963443) (xy 442.454584 -83.955857)
			(xy 442.495686 -83.955382) (xy 442.542784 -83.956017) (xy 442.636447 -83.96603) (xy 442.72853 -83.985871)
			(xy 442.818006 -84.015318) (xy 442.861192 -84.034122) (xy 442.870444 -84.037791) (xy 442.89032 -84.03843)
			(xy 442.8998 -84.035392) (xy 442.936707 -84.022278) (xy 443.01232 -84.001821) (xy 443.089439 -83.988096)
			(xy 443.167466 -83.981208) (xy 443.206632 -83.980782) (xy 443.20714 -83.980782) (xy 443.253504 -83.981382)
			(xy 443.345727 -83.991039) (xy 443.436445 -84.010233) (xy 443.524677 -84.038756) (xy 443.567312 -84.056982)
			(xy 443.577254 -84.060788) (xy 443.598518 -84.060788) (xy 443.60846 -84.056982) (xy 443.651064 -84.038764)
			(xy 443.739231 -84.010245) (xy 443.829886 -83.991052) (xy 443.922046 -83.981391) (xy 443.968378 -83.980782)
			(xy 443.968886 -83.980782) (xy 444.009989 -83.981265) (xy 444.091843 -83.988849) (xy 444.172649 -84.003953)
			(xy 444.251717 -84.026448) (xy 444.328371 -84.056143) (xy 444.401959 -84.092784) (xy 444.471852 -84.136059)
			(xy 444.537454 -84.185598) (xy 444.598205 -84.240978) (xy 444.653587 -84.301728) (xy 444.703128 -84.367328)
			(xy 444.746404 -84.43722) (xy 444.783047 -84.510807) (xy 444.812744 -84.587461) (xy 444.833667 -84.660994)
			(xy 447.966846 -84.660994) (xy 447.967345 -84.618387) (xy 447.975492 -84.533563) (xy 447.991713 -84.449907)
			(xy 448.015857 -84.368184) (xy 448.047703 -84.289145) (xy 448.086961 -84.213512) (xy 448.133269 -84.141979)
			(xy 448.186205 -84.075201) (xy 448.245282 -84.01379) (xy 448.309961 -83.958308) (xy 448.379647 -83.909264)
			(xy 448.453703 -83.867108) (xy 448.492372 -83.84921) (xy 448.502178 -83.844198) (xy 448.516684 -83.827668)
			(xy 448.522903 -83.806574) (xy 448.521836 -83.795616) (xy 448.517555 -83.763977) (xy 448.512976 -83.700288)
			(xy 448.512692 -83.668362) (xy 448.512692 -83.6676) (xy 448.513196 -83.625252) (xy 448.521247 -83.540938)
			(xy 448.537276 -83.457772) (xy 448.561137 -83.376505) (xy 448.592616 -83.297875) (xy 448.631427 -83.222594)
			(xy 448.677217 -83.151342) (xy 448.729573 -83.084766) (xy 448.788021 -83.023468) (xy 448.852031 -82.968003)
			(xy 448.921023 -82.918874) (xy 448.994373 -82.876525) (xy 449.071416 -82.841341) (xy 449.151455 -82.813639)
			(xy 449.233764 -82.793671) (xy 449.317599 -82.781618) (xy 449.4022 -82.777588) (xy 449.486801 -82.781618)
			(xy 449.570636 -82.793671) (xy 449.652945 -82.813639) (xy 449.732984 -82.841341) (xy 449.810027 -82.876525)
			(xy 449.883377 -82.918874) (xy 449.952369 -82.968003) (xy 450.016379 -83.023468) (xy 450.074827 -83.084766)
			(xy 450.127183 -83.151342) (xy 450.172973 -83.222594) (xy 450.211784 -83.297875) (xy 450.243263 -83.376505)
			(xy 450.267124 -83.457772) (xy 450.283153 -83.540938) (xy 450.291204 -83.625252) (xy 450.291708 -83.6676)
			(xy 450.291131 -83.711635) (xy 450.282404 -83.799272) (xy 450.265063 -83.885618) (xy 450.23928 -83.969829)
			(xy 450.205306 -84.051083) (xy 450.163472 -84.128583) (xy 450.114189 -84.201573) (xy 450.086476 -84.235798)
			(xy 450.080519 -84.243612) (xy 450.074506 -84.262299) (xy 450.074792 -84.27212) (xy 450.07784 -84.313014)
			(xy 450.086476 -84.330286) (xy 450.093842 -84.33689) (xy 450.124567 -84.365007) (xy 450.166185 -84.409788)
			(xy 450.585078 -84.409788) (xy 450.585078 -84.409534) (xy 450.585609 -84.365876) (xy 450.594185 -84.278982)
			(xy 450.61123 -84.193346) (xy 450.636579 -84.109791) (xy 450.669988 -84.029119) (xy 450.711136 -83.952107)
			(xy 450.734938 -83.915504) (xy 450.739998 -83.907215) (xy 450.744027 -83.888233) (xy 450.740694 -83.869117)
			(xy 450.735954 -83.86064) (xy 450.71486 -83.825522) (xy 450.67846 -83.752126) (xy 450.648964 -83.675693)
			(xy 450.626621 -83.596872) (xy 450.61162 -83.516331) (xy 450.604088 -83.434751) (xy 450.60362 -83.393788)
			(xy 450.604124 -83.35144) (xy 450.612175 -83.267126) (xy 450.628204 -83.18396) (xy 450.652065 -83.102693)
			(xy 450.683544 -83.024063) (xy 450.722355 -82.948782) (xy 450.768145 -82.87753) (xy 450.820501 -82.810954)
			(xy 450.878949 -82.749656) (xy 450.942959 -82.694191) (xy 451.011951 -82.645062) (xy 451.085301 -82.602713)
			(xy 451.162344 -82.567529) (xy 451.242383 -82.539827) (xy 451.324692 -82.519859) (xy 451.408527 -82.507806)
			(xy 451.493128 -82.503776) (xy 451.577729 -82.507806) (xy 451.661564 -82.519859) (xy 451.743873 -82.539827)
			(xy 451.823912 -82.567529) (xy 451.900955 -82.602713) (xy 451.974305 -82.645062) (xy 452.043297 -82.694191)
			(xy 452.107307 -82.749656) (xy 452.165755 -82.810954) (xy 452.218111 -82.87753) (xy 452.263901 -82.948782)
			(xy 452.302712 -83.024063) (xy 452.334191 -83.102693) (xy 452.358052 -83.18396) (xy 452.374081 -83.267126)
			(xy 452.382132 -83.35144) (xy 452.382636 -83.393788) (xy 452.382636 -83.394042) (xy 452.382107 -83.4377)
			(xy 452.373532 -83.524594) (xy 452.356488 -83.610231) (xy 452.331139 -83.693787) (xy 452.297729 -83.774458)
			(xy 452.256579 -83.85147) (xy 452.232776 -83.888072) (xy 452.227734 -83.896371) (xy 452.223697 -83.915347)
			(xy 452.227023 -83.93446) (xy 452.23176 -83.942936) (xy 452.252846 -83.978059) (xy 452.289246 -84.051454)
			(xy 452.318743 -84.127886) (xy 452.341088 -84.206705) (xy 452.356091 -84.287246) (xy 452.363625 -84.368825)
			(xy 452.364094 -84.409788) (xy 452.36359 -84.452136) (xy 452.355539 -84.53645) (xy 452.33951 -84.619616)
			(xy 452.315649 -84.700883) (xy 452.28417 -84.779513) (xy 452.245359 -84.854794) (xy 452.199569 -84.926046)
			(xy 452.147213 -84.992622) (xy 452.088765 -85.05392) (xy 452.024755 -85.109385) (xy 451.955763 -85.158514)
			(xy 451.882413 -85.200863) (xy 451.80537 -85.236047) (xy 451.725331 -85.263749) (xy 451.643022 -85.283717)
			(xy 451.559187 -85.29577) (xy 451.474586 -85.299801) (xy 451.389985 -85.29577) (xy 451.30615 -85.283717)
			(xy 451.223841 -85.263749) (xy 451.143802 -85.236047) (xy 451.066759 -85.200863) (xy 450.993409 -85.158514)
			(xy 450.924417 -85.109385) (xy 450.860407 -85.05392) (xy 450.801959 -84.992622) (xy 450.749603 -84.926046)
			(xy 450.703813 -84.854794) (xy 450.665002 -84.779513) (xy 450.633523 -84.700883) (xy 450.609662 -84.619616)
			(xy 450.593633 -84.53645) (xy 450.585582 -84.452136) (xy 450.585078 -84.409788) (xy 450.166185 -84.409788)
			(xy 450.181268 -84.426018) (xy 450.232018 -84.492062) (xy 450.276374 -84.562559) (xy 450.313948 -84.636893)
			(xy 450.34441 -84.714413) (xy 450.367495 -84.79444) (xy 450.382999 -84.876275) (xy 450.390788 -84.959201)
			(xy 450.391276 -85.000846) (xy 450.390814 -85.042456) (xy 450.383033 -85.125312) (xy 450.367553 -85.207081)
			(xy 450.34451 -85.287047) (xy 450.314103 -85.364514) (xy 450.276599 -85.438805) (xy 450.232325 -85.509271)
			(xy 450.181668 -85.575298) (xy 450.125069 -85.636308) (xy 450.063023 -85.69177) (xy 450.029834 -85.716872)
			(xy 450.02958 -85.716872) (xy 450.029326 -85.717126) (xy 450.020797 -85.724134) (xy 450.010253 -85.743497)
			(xy 450.009006 -85.754464) (xy 450.003164 -85.84311) (xy 450.011038 -85.863938) (xy 450.01942 -85.871812)
			(xy 450.051215 -85.903246) (xy 450.10905 -85.971436) (xy 450.159752 -86.045085) (xy 450.20281 -86.123448)
			(xy 450.237789 -86.205735) (xy 450.264337 -86.291117) (xy 450.282186 -86.378731) (xy 450.291156 -86.467693)
			(xy 450.291708 -86.5124) (xy 450.291227 -86.553939) (xy 450.28348 -86.636654) (xy 450.268055 -86.718287)
			(xy 450.245085 -86.798126) (xy 450.21477 -86.875476) (xy 450.177375 -86.949661) (xy 450.133226 -87.020037)
			(xy 450.082707 -87.085989) (xy 450.026259 -87.146943) (xy 449.964372 -87.202369) (xy 449.897587 -87.251782)
			(xy 449.826486 -87.294753) (xy 449.789296 -87.313262) (xy 449.779136 -87.318088) (xy 449.76542 -87.334344)
			(xy 449.738496 -87.428578) (xy 449.741544 -87.44966) (xy 449.747386 -87.459058) (xy 449.769353 -87.494669)
			(xy 449.807273 -87.569261) (xy 449.838019 -87.647085) (xy 449.86132 -87.727453) (xy 449.876969 -87.809654)
			(xy 449.884828 -87.892961) (xy 449.885308 -87.9348) (xy 449.884809 -87.976715) (xy 449.876928 -88.060172)
			(xy 449.861226 -88.142518) (xy 449.837842 -88.223019) (xy 449.806985 -88.300963) (xy 449.768929 -88.375655)
			(xy 449.746878 -88.411304) (xy 449.742473 -88.418931) (xy 449.738591 -88.436097) (xy 449.740719 -88.453567)
			(xy 449.744338 -88.461596) (xy 449.745354 -88.463628) (xy 449.767262 -88.503653) (xy 449.768937 -88.5075)
			(xy 450.566278 -88.5075) (xy 450.566278 -88.422804) (xy 450.574329 -88.33849) (xy 450.590358 -88.255324)
			(xy 450.614219 -88.174057) (xy 450.645698 -88.095427) (xy 450.684509 -88.020146) (xy 450.730299 -87.948894)
			(xy 450.782655 -87.882318) (xy 450.841103 -87.82102) (xy 450.905113 -87.765555) (xy 450.974105 -87.716426)
			(xy 451.047455 -87.674077) (xy 451.124498 -87.638893) (xy 451.204537 -87.611191) (xy 451.286846 -87.591223)
			(xy 451.370681 -87.57917) (xy 451.455282 -87.57514) (xy 451.539883 -87.57917) (xy 451.623718 -87.591223)
			(xy 451.706027 -87.611191) (xy 451.786066 -87.638893) (xy 451.863109 -87.674077) (xy 451.936459 -87.716426)
			(xy 452.005451 -87.765555) (xy 452.069461 -87.82102) (xy 452.127909 -87.882318) (xy 452.180265 -87.948894)
			(xy 452.226055 -88.020146) (xy 452.264866 -88.095427) (xy 452.296345 -88.174057) (xy 452.320206 -88.255324)
			(xy 452.336235 -88.33849) (xy 452.344286 -88.422804) (xy 452.34479 -88.465152) (xy 452.344286 -88.5075)
			(xy 452.336235 -88.591814) (xy 452.320206 -88.67498) (xy 452.296345 -88.756247) (xy 452.264866 -88.834877)
			(xy 452.226055 -88.910158) (xy 452.180265 -88.98141) (xy 452.127909 -89.047986) (xy 452.069461 -89.109284)
			(xy 452.005451 -89.164749) (xy 451.936459 -89.213878) (xy 451.863109 -89.256227) (xy 451.786066 -89.291411)
			(xy 451.706027 -89.319113) (xy 451.623718 -89.339081) (xy 451.539883 -89.351134) (xy 451.455282 -89.355165)
			(xy 451.370681 -89.351134) (xy 451.286846 -89.339081) (xy 451.204537 -89.319113) (xy 451.124498 -89.291411)
			(xy 451.047455 -89.256227) (xy 450.974105 -89.213878) (xy 450.905113 -89.164749) (xy 450.841103 -89.109284)
			(xy 450.782655 -89.047986) (xy 450.730299 -88.98141) (xy 450.684509 -88.910158) (xy 450.645698 -88.834877)
			(xy 450.614219 -88.756247) (xy 450.590358 -88.67498) (xy 450.574329 -88.591814) (xy 450.566278 -88.5075)
			(xy 449.768937 -88.5075) (xy 449.803682 -88.587319) (xy 449.831342 -88.674276) (xy 449.849953 -88.763607)
			(xy 449.859318 -88.854375) (xy 449.859908 -88.9) (xy 449.859404 -88.942348) (xy 449.851353 -89.026662)
			(xy 449.835324 -89.109828) (xy 449.811463 -89.191095) (xy 449.779984 -89.269725) (xy 449.741173 -89.345006)
			(xy 449.695383 -89.416258) (xy 449.643027 -89.482834) (xy 449.584579 -89.544132) (xy 449.520569 -89.599597)
			(xy 449.451577 -89.648726) (xy 449.378227 -89.691075) (xy 449.301184 -89.726259) (xy 449.221145 -89.753961)
			(xy 449.138836 -89.773929) (xy 449.055001 -89.785982) (xy 448.9704 -89.790013) (xy 448.885799 -89.785982)
			(xy 448.801964 -89.773929) (xy 448.719655 -89.753961) (xy 448.639616 -89.726259) (xy 448.562573 -89.691075)
			(xy 448.489223 -89.648726) (xy 448.420231 -89.599597) (xy 448.356221 -89.544132) (xy 448.297773 -89.482834)
			(xy 448.245417 -89.416258) (xy 448.199627 -89.345006) (xy 448.160816 -89.269725) (xy 448.129337 -89.191095)
			(xy 448.105476 -89.109828) (xy 448.089447 -89.026662) (xy 448.081396 -88.942348) (xy 448.080892 -88.9)
			(xy 448.081391 -88.858085) (xy 448.089272 -88.774628) (xy 448.104974 -88.692282) (xy 448.128358 -88.611781)
			(xy 448.159215 -88.533837) (xy 448.197271 -88.459145) (xy 448.219322 -88.423496) (xy 448.223727 -88.415869)
			(xy 448.227609 -88.398703) (xy 448.225481 -88.381233) (xy 448.221862 -88.373204) (xy 448.220846 -88.371172)
			(xy 448.198938 -88.331147) (xy 448.162518 -88.247481) (xy 448.134858 -88.160524) (xy 448.116247 -88.071193)
			(xy 448.106882 -87.980425) (xy 448.106292 -87.9348) (xy 448.106773 -87.893261) (xy 448.11452 -87.810546)
			(xy 448.129945 -87.728913) (xy 448.152915 -87.649074) (xy 448.18323 -87.571724) (xy 448.220625 -87.497539)
			(xy 448.264774 -87.427163) (xy 448.315293 -87.361211) (xy 448.371741 -87.300257) (xy 448.433628 -87.244831)
			(xy 448.500413 -87.195418) (xy 448.571514 -87.152447) (xy 448.608704 -87.133938) (xy 448.618864 -87.129112)
			(xy 448.63258 -87.112856) (xy 448.659504 -87.018622) (xy 448.656456 -86.99754) (xy 448.650614 -86.988142)
			(xy 448.628647 -86.952531) (xy 448.590727 -86.877939) (xy 448.559981 -86.800115) (xy 448.53668 -86.719747)
			(xy 448.521031 -86.637546) (xy 448.513172 -86.554239) (xy 448.512692 -86.5124) (xy 448.513202 -86.470791)
			(xy 448.520978 -86.387937) (xy 448.536453 -86.30617) (xy 448.559492 -86.226205) (xy 448.589894 -86.148738)
			(xy 448.627393 -86.074448) (xy 448.671661 -86.003981) (xy 448.722313 -85.937954) (xy 448.778907 -85.876942)
			(xy 448.840948 -85.821478) (xy 448.874134 -85.796374) (xy 448.874388 -85.796374) (xy 448.874642 -85.79612)
			(xy 448.883163 -85.789105) (xy 448.893709 -85.769747) (xy 448.894962 -85.758782) (xy 448.900804 -85.670136)
			(xy 448.89293 -85.649308) (xy 448.884548 -85.641434) (xy 448.866067 -85.623351) (xy 448.830993 -85.585354)
			(xy 448.814444 -85.565488) (xy 448.807674 -85.557925) (xy 448.789714 -85.5485) (xy 448.779646 -85.5472)
			(xy 448.738565 -85.543209) (xy 448.657342 -85.528498) (xy 448.57783 -85.506326) (xy 448.500715 -85.476883)
			(xy 448.426659 -85.440423) (xy 448.3563 -85.397259) (xy 448.290242 -85.347762) (xy 448.229053 -85.292358)
			(xy 448.173261 -85.231524) (xy 448.123344 -85.165783) (xy 448.079732 -85.0957) (xy 448.0428 -85.021878)
			(xy 448.012867 -84.944952) (xy 447.990188 -84.865584) (xy 447.97496 -84.784456) (xy 447.967314 -84.702266)
			(xy 447.966846 -84.660994) (xy 444.833667 -84.660994) (xy 444.835241 -84.666527) (xy 444.850348 -84.747333)
			(xy 444.857933 -84.829187) (xy 444.858394 -84.87029) (xy 444.857888 -84.913409) (xy 444.84954 -84.999241)
			(xy 444.832922 -85.083862) (xy 444.80819 -85.166477) (xy 444.792354 -85.206586) (xy 444.789021 -85.215957)
			(xy 444.789017 -85.235825) (xy 444.792354 -85.245194) (xy 444.808182 -85.285306) (xy 444.832913 -85.36792)
			(xy 444.849531 -85.452541) (xy 444.85788 -85.538372) (xy 444.85788 -85.624609) (xy 444.849534 -85.710441)
			(xy 444.832917 -85.795062) (xy 444.808188 -85.877677) (xy 444.792354 -85.917786) (xy 444.789021 -85.927157)
			(xy 444.789017 -85.947025) (xy 444.792354 -85.956394) (xy 444.808182 -85.996506) (xy 444.832913 -86.07912)
			(xy 444.849531 -86.163741) (xy 444.85788 -86.249572) (xy 444.85788 -86.335809) (xy 444.849534 -86.421641)
			(xy 444.832917 -86.506262) (xy 444.808188 -86.588877) (xy 444.792354 -86.628986) (xy 444.789103 -86.638306)
			(xy 444.78909 -86.658026) (xy 444.792354 -86.66734) (xy 444.80165 -86.690609) (xy 444.817915 -86.738008)
			(xy 444.824866 -86.762082) (xy 444.829438 -86.773512) (xy 444.833953 -86.780809) (xy 444.846876 -86.792082)
			(xy 444.862797 -86.798455) (xy 444.871348 -86.799166) (xy 444.913569 -86.801772) (xy 444.997283 -86.813963)
			(xy 445.079462 -86.834046) (xy 445.159363 -86.86184) (xy 445.236264 -86.897093) (xy 445.309472 -86.939488)
			(xy 445.378324 -86.988641) (xy 445.442199 -87.044109) (xy 445.50052 -87.105389) (xy 445.55276 -87.17193)
			(xy 445.598447 -87.243129) (xy 445.637169 -87.318344) (xy 445.668575 -87.396895) (xy 445.692382 -87.478073)
			(xy 445.708376 -87.561145) (xy 445.716411 -87.64536) (xy 445.716914 -87.687658) (xy 445.716408 -87.72876)
			(xy 445.708827 -87.810615) (xy 445.693725 -87.89142) (xy 445.671232 -87.970487) (xy 445.641539 -88.047142)
			(xy 445.6049 -88.12073) (xy 445.561627 -88.190623) (xy 445.51209 -88.256225) (xy 445.456711 -88.316977)
			(xy 445.395962 -88.372359) (xy 445.330363 -88.4219) (xy 445.260472 -88.465176) (xy 445.186886 -88.50182)
			(xy 445.110233 -88.531517) (xy 445.031167 -88.554014) (xy 444.950362 -88.56912) (xy 444.868508 -88.576706)
			(xy 444.827406 -88.577166) (xy 444.773304 -88.575642) (xy 444.763999 -88.575525) (xy 444.74628 -88.581165)
			(xy 444.73172 -88.592732) (xy 444.722218 -88.608717) (xy 444.720218 -88.617806) (xy 444.711401 -88.665205)
			(xy 444.684828 -88.757885) (xy 444.648378 -88.847145) (xy 444.625984 -88.88984) (xy 444.620588 -88.901314)
			(xy 444.620575 -88.926634) (xy 444.625984 -88.9381) (xy 444.646511 -88.977177) (xy 444.680612 -89.058599)
			(xy 444.706488 -89.142996) (xy 444.723883 -89.22954) (xy 444.732628 -89.317381) (xy 444.733172 -89.361518)
			(xy 444.733172 -89.361772) (xy 444.732703 -89.402592) (xy 444.725223 -89.48389) (xy 444.710326 -89.56416)
			(xy 444.688134 -89.642727) (xy 444.658837 -89.71893) (xy 444.622679 -89.792127) (xy 444.579965 -89.861703)
			(xy 444.55588 -89.894664) (xy 444.550149 -89.903078) (xy 444.545253 -89.922822) (xy 444.548384 -89.942921)
			(xy 444.55334 -89.951814) (xy 444.574684 -89.98707) (xy 444.611489 -90.060818) (xy 444.641321 -90.137652)
			(xy 444.663924 -90.216914) (xy 444.679103 -90.297927) (xy 444.68673 -90.379995) (xy 444.687198 -90.421206)
			(xy 444.687198 -90.42146) (xy 444.686605 -90.466265) (xy 444.677577 -90.55542) (xy 444.659637 -90.643217)
			(xy 444.632967 -90.728768) (xy 444.597838 -90.811206) (xy 444.576708 -90.85072) (xy 444.572875 -90.858366)
			(xy 444.570054 -90.875227) (xy 444.572893 -90.892086) (xy 444.576708 -90.899742) (xy 444.597857 -90.939249)
			(xy 444.633015 -91.02168) (xy 444.659698 -91.107231) (xy 444.677635 -91.195033) (xy 444.686645 -91.284194)
			(xy 444.687198 -91.329002) (xy 444.687198 -91.329256) (xy 444.686661 -91.373068) (xy 444.678046 -91.460267)
			(xy 444.660896 -91.546197) (xy 444.635377 -91.630022) (xy 444.601736 -91.710931) (xy 444.5603 -91.788138)
			(xy 444.536322 -91.82481) (xy 444.53114 -91.833423) (xy 444.527245 -91.853126) (xy 444.53116 -91.872825)
			(xy 444.536322 -91.881452) (xy 444.560307 -91.91812) (xy 444.601742 -91.995328) (xy 444.635383 -92.076238)
			(xy 444.660903 -92.160064) (xy 444.678055 -92.245994) (xy 444.686673 -92.333194) (xy 444.687198 -92.377006)
			(xy 444.687198 -92.37726) (xy 444.686605 -92.422065) (xy 444.677577 -92.51122) (xy 444.659637 -92.599017)
			(xy 444.632967 -92.684568) (xy 444.597838 -92.767006) (xy 444.576708 -92.80652) (xy 444.572875 -92.814166)
			(xy 444.570054 -92.831027) (xy 444.572893 -92.847886) (xy 444.576708 -92.855542) (xy 444.597857 -92.895049)
			(xy 444.633015 -92.97748) (xy 444.659698 -93.063031) (xy 444.677635 -93.150833) (xy 444.686645 -93.239994)
			(xy 444.687198 -93.284802) (xy 444.687198 -93.285056) (xy 444.686661 -93.328868) (xy 444.678046 -93.416067)
			(xy 444.660896 -93.501997) (xy 444.635377 -93.585822) (xy 444.601736 -93.666731) (xy 444.5603 -93.743938)
			(xy 444.536322 -93.78061) (xy 444.53114 -93.789223) (xy 444.527245 -93.808926) (xy 444.53116 -93.828625)
			(xy 444.536322 -93.837252) (xy 444.560307 -93.87392) (xy 444.601742 -93.951128) (xy 444.635383 -94.032038)
			(xy 444.660903 -94.115864) (xy 444.678055 -94.201794) (xy 444.686673 -94.288994) (xy 444.687198 -94.332806)
			(xy 444.687198 -94.33306) (xy 444.686828 -94.361) (xy 450.239892 -94.361) (xy 450.239892 -94.360492)
			(xy 450.240498 -94.31416) (xy 450.250169 -94.222002) (xy 450.269365 -94.131348) (xy 450.297877 -94.043179)
			(xy 450.316092 -94.000574) (xy 450.319898 -93.990632) (xy 450.319898 -93.969368) (xy 450.316092 -93.959426)
			(xy 450.29787 -93.916823) (xy 450.269352 -93.828656) (xy 450.25016 -93.738) (xy 450.2405 -93.64584)
			(xy 450.239892 -93.599508) (xy 450.239892 -93.599) (xy 450.240475 -93.554828) (xy 450.24926 -93.466923)
			(xy 450.266716 -93.380321) (xy 450.292668 -93.295875) (xy 450.326863 -93.214418) (xy 450.368962 -93.136751)
			(xy 450.393308 -93.09989) (xy 450.398473 -93.091332) (xy 450.402501 -93.071775) (xy 450.398832 -93.052147)
			(xy 450.393816 -93.043502) (xy 450.370954 -93.007408) (xy 450.331465 -92.931636) (xy 450.299423 -92.852426)
			(xy 450.275123 -92.77051) (xy 450.258789 -92.686641) (xy 450.250571 -92.601592) (xy 450.250052 -92.55887)
			(xy 450.250052 -92.558362) (xy 450.250568 -92.515104) (xy 450.258999 -92.428999) (xy 450.275749 -92.34412)
			(xy 450.300659 -92.261267) (xy 450.3166 -92.22105) (xy 450.320086 -92.211355) (xy 450.319826 -92.190774)
			(xy 450.316092 -92.181172) (xy 450.297855 -92.138541) (xy 450.269329 -92.05031) (xy 450.250138 -91.959589)
			(xy 450.24049 -91.867364) (xy 450.239892 -91.821) (xy 450.24034 -91.780707) (xy 450.247622 -91.700452)
			(xy 450.262133 -91.621185) (xy 450.283756 -91.543555) (xy 450.312313 -91.4682) (xy 450.347571 -91.395737)
			(xy 450.389239 -91.326761) (xy 450.436976 -91.261837) (xy 450.49039 -91.201498) (xy 450.549045 -91.146238)
			(xy 450.612457 -91.096512) (xy 450.646038 -91.07424) (xy 450.65442 -91.06916) (xy 450.660008 -91.061032)
			(xy 450.662687 -91.057073) (xy 450.666657 -91.04838) (xy 450.667882 -91.04376) (xy 450.684646 -90.976196)
			(xy 450.686455 -90.966733) (xy 450.683723 -90.947677) (xy 450.679312 -90.939112) (xy 450.65718 -90.898918)
			(xy 450.620404 -90.814847) (xy 450.592483 -90.727436) (xy 450.573714 -90.637613) (xy 450.564298 -90.546335)
			(xy 450.563742 -90.500454) (xy 450.563742 -90.5002) (xy 450.564246 -90.457852) (xy 450.572297 -90.373538)
			(xy 450.588326 -90.290372) (xy 450.612187 -90.209105) (xy 450.643666 -90.130475) (xy 450.682477 -90.055194)
			(xy 450.728267 -89.983942) (xy 450.780623 -89.917366) (xy 450.839071 -89.856068) (xy 450.903081 -89.800603)
			(xy 450.972073 -89.751474) (xy 451.045423 -89.709125) (xy 451.122466 -89.673941) (xy 451.202505 -89.646239)
			(xy 451.284814 -89.626271) (xy 451.368649 -89.614218) (xy 451.45325 -89.610188) (xy 451.537851 -89.614218)
			(xy 451.621686 -89.626271) (xy 451.703995 -89.646239) (xy 451.784034 -89.673941) (xy 451.861077 -89.709125)
			(xy 451.934427 -89.751474) (xy 452.003419 -89.800603) (xy 452.067429 -89.856068) (xy 452.125877 -89.917366)
			(xy 452.178233 -89.983942) (xy 452.224023 -90.055194) (xy 452.262834 -90.130475) (xy 452.294313 -90.209105)
			(xy 452.318174 -90.290372) (xy 452.334203 -90.373538) (xy 452.342254 -90.457852) (xy 452.342758 -90.5002)
			(xy 452.342332 -90.540493) (xy 452.335051 -90.62075) (xy 452.320538 -90.700019) (xy 452.298914 -90.777649)
			(xy 452.270355 -90.853005) (xy 452.235095 -90.925469) (xy 452.193425 -90.994445) (xy 452.145685 -91.059368)
			(xy 452.092268 -91.119706) (xy 452.03361 -91.174965) (xy 451.970194 -91.224689) (xy 451.936612 -91.24696)
			(xy 451.92823 -91.25204) (xy 451.922642 -91.260168) (xy 451.919959 -91.264124) (xy 451.915992 -91.272819)
			(xy 451.914768 -91.27744) (xy 451.898004 -91.345004) (xy 451.896201 -91.354468) (xy 451.898931 -91.373522)
			(xy 451.903338 -91.382088) (xy 451.925475 -91.42228) (xy 451.962249 -91.506351) (xy 451.990169 -91.593763)
			(xy 452.008936 -91.683586) (xy 452.018352 -91.774864) (xy 452.018908 -91.820746) (xy 452.018908 -91.821254)
			(xy 452.018388 -91.864543) (xy 452.009973 -91.950713) (xy 451.993227 -92.035657) (xy 451.968309 -92.118572)
			(xy 451.95236 -92.15882) (xy 451.948893 -92.16852) (xy 451.949142 -92.189096) (xy 451.952868 -92.198698)
			(xy 451.971093 -92.241334) (xy 451.999622 -92.329563) (xy 452.018817 -92.420282) (xy 452.028468 -92.512506)
			(xy 452.029068 -92.55887) (xy 452.028528 -92.603043) (xy 452.019735 -92.69095) (xy 452.002272 -92.777553)
			(xy 451.976312 -92.861998) (xy 451.942109 -92.943455) (xy 451.900002 -93.02112) (xy 451.875652 -93.05798)
			(xy 451.870508 -93.06655) (xy 451.866467 -93.0861) (xy 451.870129 -93.105725) (xy 451.875144 -93.114368)
			(xy 451.898 -93.150466) (xy 451.937489 -93.226238) (xy 451.969531 -93.305446) (xy 451.993832 -93.387362)
			(xy 452.010168 -93.47123) (xy 452.018388 -93.556278) (xy 452.018908 -93.599) (xy 452.018908 -93.599508)
			(xy 452.018302 -93.64584) (xy 452.008631 -93.737998) (xy 451.989435 -93.828652) (xy 451.960923 -93.916821)
			(xy 451.942708 -93.959426) (xy 451.938902 -93.969368) (xy 451.938902 -93.990632) (xy 451.942708 -94.000574)
			(xy 451.96093 -94.043177) (xy 451.989448 -94.131344) (xy 452.00864 -94.222) (xy 452.0183 -94.31416)
			(xy 452.018908 -94.360492) (xy 452.018908 -94.361) (xy 452.018404 -94.403348) (xy 452.010353 -94.487662)
			(xy 451.994324 -94.570828) (xy 451.970463 -94.652095) (xy 451.938984 -94.730725) (xy 451.900173 -94.806006)
			(xy 451.854383 -94.877258) (xy 451.802027 -94.943834) (xy 451.743579 -95.005132) (xy 451.679569 -95.060597)
			(xy 451.610577 -95.109726) (xy 451.537227 -95.152075) (xy 451.460184 -95.187259) (xy 451.380145 -95.214961)
			(xy 451.297836 -95.234929) (xy 451.214001 -95.246982) (xy 451.1294 -95.251013) (xy 451.044799 -95.246982)
			(xy 450.960964 -95.234929) (xy 450.878655 -95.214961) (xy 450.798616 -95.187259) (xy 450.721573 -95.152075)
			(xy 450.648223 -95.109726) (xy 450.579231 -95.060597) (xy 450.515221 -95.005132) (xy 450.456773 -94.943834)
			(xy 450.404417 -94.877258) (xy 450.358627 -94.806006) (xy 450.319816 -94.730725) (xy 450.288337 -94.652095)
			(xy 450.264476 -94.570828) (xy 450.248447 -94.487662) (xy 450.240396 -94.403348) (xy 450.239892 -94.361)
			(xy 444.686828 -94.361) (xy 444.686605 -94.377865) (xy 444.677577 -94.46702) (xy 444.659637 -94.554817)
			(xy 444.632967 -94.640368) (xy 444.597838 -94.722806) (xy 444.576708 -94.76232) (xy 444.572875 -94.769966)
			(xy 444.570054 -94.786827) (xy 444.572893 -94.803686) (xy 444.576708 -94.811342) (xy 444.597857 -94.850849)
			(xy 444.633015 -94.93328) (xy 444.659698 -95.018831) (xy 444.677635 -95.106633) (xy 444.686645 -95.195794)
			(xy 444.687198 -95.240602) (xy 444.687198 -95.240856) (xy 444.686694 -95.283204) (xy 444.678643 -95.367518)
			(xy 444.662614 -95.450684) (xy 444.638753 -95.531951) (xy 444.607274 -95.610581) (xy 444.568463 -95.685862)
			(xy 444.522673 -95.757114) (xy 444.470317 -95.82369) (xy 444.411869 -95.884988) (xy 444.347859 -95.940453)
			(xy 444.278867 -95.989582) (xy 444.205517 -96.031931) (xy 444.128474 -96.067115) (xy 444.048435 -96.094817)
			(xy 443.966126 -96.114785) (xy 443.882291 -96.126838) (xy 443.79769 -96.130869) (xy 443.713089 -96.126838)
			(xy 443.629254 -96.114785) (xy 443.546945 -96.094817) (xy 443.466906 -96.067115) (xy 443.389863 -96.031931)
			(xy 443.316513 -95.989582) (xy 443.247521 -95.940453) (xy 443.183511 -95.884988) (xy 443.125063 -95.82369)
			(xy 443.072707 -95.757114) (xy 443.026917 -95.685862) (xy 442.988106 -95.610581) (xy 442.956627 -95.531951)
			(xy 442.932766 -95.450684) (xy 442.916737 -95.367518) (xy 442.908686 -95.283204) (xy 442.908182 -95.240856)
			(xy 442.908182 -95.240602) (xy 442.908748 -95.195796) (xy 442.917782 -95.10664) (xy 442.935727 -95.018842)
			(xy 442.962402 -94.933292) (xy 442.997538 -94.850855) (xy 443.018672 -94.811342) (xy 443.022519 -94.803691)
			(xy 443.025415 -94.786827) (xy 443.022537 -94.76996) (xy 443.018672 -94.76232) (xy 442.997507 -94.722822)
			(xy 442.962352 -94.640388) (xy 442.935673 -94.554835) (xy 442.917739 -94.467031) (xy 442.908734 -94.377868)
			(xy 442.908182 -94.33306) (xy 442.908182 -94.332806) (xy 442.908703 -94.288994) (xy 442.917321 -94.201794)
			(xy 442.934475 -94.115865) (xy 442.959997 -94.032039) (xy 442.99364 -93.95113) (xy 443.035079 -93.873923)
			(xy 443.059058 -93.837252) (xy 443.064319 -93.828658) (xy 443.068302 -93.808926) (xy 443.064339 -93.789189)
			(xy 443.059058 -93.78061) (xy 443.035054 -93.743955) (xy 442.993622 -93.666743) (xy 442.959984 -93.58583)
			(xy 442.934468 -93.502002) (xy 442.917319 -93.41607) (xy 442.908706 -93.328869) (xy 442.908182 -93.285056)
			(xy 442.908182 -93.284802) (xy 442.908748 -93.239996) (xy 442.917782 -93.15084) (xy 442.935727 -93.063042)
			(xy 442.962402 -92.977492) (xy 442.997538 -92.895055) (xy 443.018672 -92.855542) (xy 443.022519 -92.847891)
			(xy 443.025415 -92.831027) (xy 443.022537 -92.81416) (xy 443.018672 -92.80652) (xy 442.997507 -92.767022)
			(xy 442.962352 -92.684588) (xy 442.935673 -92.599035) (xy 442.917739 -92.511231) (xy 442.908734 -92.422068)
			(xy 442.908182 -92.37726) (xy 442.908182 -92.377006) (xy 442.908703 -92.333194) (xy 442.917321 -92.245994)
			(xy 442.934475 -92.160065) (xy 442.959997 -92.076239) (xy 442.99364 -91.99533) (xy 443.035079 -91.918123)
			(xy 443.059058 -91.881452) (xy 443.064319 -91.872858) (xy 443.068302 -91.853126) (xy 443.064339 -91.833389)
			(xy 443.059058 -91.82481) (xy 443.035054 -91.788155) (xy 442.993622 -91.710943) (xy 442.959984 -91.63003)
			(xy 442.934468 -91.546202) (xy 442.917319 -91.46027) (xy 442.908706 -91.373069) (xy 442.908182 -91.329256)
			(xy 442.908182 -91.329002) (xy 442.908748 -91.284196) (xy 442.917782 -91.19504) (xy 442.935727 -91.107242)
			(xy 442.962402 -91.021692) (xy 442.997538 -90.939255) (xy 443.018672 -90.899742) (xy 443.022519 -90.892091)
			(xy 443.025415 -90.875227) (xy 443.022537 -90.85836) (xy 443.018672 -90.85072) (xy 442.997507 -90.811222)
			(xy 442.962352 -90.728788) (xy 442.935673 -90.643235) (xy 442.917739 -90.555431) (xy 442.908734 -90.466268)
			(xy 442.908182 -90.42146) (xy 442.908182 -90.420952) (xy 442.908618 -90.380131) (xy 442.916104 -90.298832)
			(xy 442.931008 -90.218562) (xy 442.953205 -90.139995) (xy 442.982507 -90.063792) (xy 443.01867 -89.990596)
			(xy 443.061387 -89.921021) (xy 443.085474 -89.88806) (xy 443.091187 -89.879635) (xy 443.096094 -89.859898)
			(xy 443.092968 -89.839802) (xy 443.088014 -89.83091) (xy 443.066675 -89.795651) (xy 443.02987 -89.721903)
			(xy 443.000038 -89.64507) (xy 442.977435 -89.565808) (xy 442.962254 -89.484797) (xy 442.954625 -89.402729)
			(xy 442.954156 -89.361518) (xy 442.954708 -89.31738) (xy 442.963428 -89.229535) (xy 442.980813 -89.142988)
			(xy 443.006692 -89.058591) (xy 443.040811 -88.977175) (xy 443.061344 -88.9381) (xy 443.066779 -88.926641)
			(xy 443.066766 -88.901307) (xy 443.061344 -88.88984) (xy 443.043472 -88.855988) (xy 443.012933 -88.785786)
			(xy 442.98855 -88.713217) (xy 442.970502 -88.638819) (xy 442.964316 -88.601042) (xy 442.962487 -88.59186)
			(xy 442.953234 -88.575605) (xy 442.93877 -88.563745) (xy 442.930026 -88.560402) (xy 442.907471 -88.552812)
			(xy 442.863125 -88.535529) (xy 442.84138 -88.525858) (xy 442.832115 -88.522229) (xy 442.812251 -88.521565)
			(xy 442.802772 -88.524588) (xy 442.765898 -88.5377) (xy 442.690347 -88.558143) (xy 442.613291 -88.571867)
			(xy 442.535328 -88.578764) (xy 442.496194 -88.579198) (xy 442.495686 -88.579198) (xy 442.454583 -88.578747)
			(xy 442.372728 -88.57116) (xy 442.291922 -88.556054) (xy 442.212854 -88.533556) (xy 442.1362 -88.503859)
			(xy 442.062612 -88.467215) (xy 441.99272 -88.423938) (xy 441.927119 -88.374397) (xy 441.866369 -88.319014)
			(xy 441.810988 -88.258263) (xy 441.761448 -88.19266) (xy 441.718173 -88.122767) (xy 441.681532 -88.049178)
			(xy 441.651836 -87.972523) (xy 441.629341 -87.893455) (xy 441.614236 -87.812648) (xy 441.606652 -87.730793)
			(xy 441.606178 -87.68969) (xy 433.13604 -87.68969) (xy 433.13604 -89.000076) (xy 433.135545 -89.100917)
			(xy 433.127627 -89.302444) (xy 433.111803 -89.503504) (xy 433.088098 -89.703788) (xy 433.056548 -89.902987)
			(xy 433.017202 -90.100794) (xy 432.97012 -90.296903) (xy 432.915375 -90.491013) (xy 432.853052 -90.682824)
			(xy 432.783247 -90.872041) (xy 432.706066 -91.05837) (xy 432.62163 -91.241527) (xy 432.530068 -91.421227)
			(xy 432.431522 -91.597193) (xy 432.326144 -91.769156) (xy 432.214095 -91.936848) (xy 432.095549 -92.100012)
			(xy 431.970689 -92.258397) (xy 431.839707 -92.411757) (xy 431.702805 -92.559857) (xy 431.560195 -92.702467)
			(xy 431.412095 -92.839369) (xy 431.258735 -92.970351) (xy 431.10035 -93.095211) (xy 430.937186 -93.213757)
			(xy 430.769494 -93.325806) (xy 430.597531 -93.431184) (xy 430.421565 -93.52973) (xy 430.241865 -93.621292)
			(xy 430.058708 -93.705728) (xy 429.872379 -93.782909) (xy 429.683162 -93.852714) (xy 429.491351 -93.915037)
			(xy 429.297241 -93.969782) (xy 429.101132 -94.016864) (xy 428.903325 -94.05621) (xy 428.704126 -94.08776)
			(xy 428.503842 -94.111465) (xy 428.302782 -94.127289) (xy 428.101255 -94.135207) (xy 427.899573 -94.135207)
			(xy 427.698046 -94.127289) (xy 427.496986 -94.111465) (xy 427.296702 -94.08776) (xy 427.097503 -94.05621)
			(xy 426.899696 -94.016864) (xy 426.703587 -93.969782) (xy 426.509477 -93.915037) (xy 426.317666 -93.852714)
			(xy 426.128449 -93.782909) (xy 425.94212 -93.705728) (xy 425.758963 -93.621292) (xy 425.579263 -93.52973)
			(xy 425.403297 -93.431184) (xy 425.231334 -93.325806) (xy 425.063642 -93.213757) (xy 424.900478 -93.095211)
			(xy 424.742093 -92.970351) (xy 424.588733 -92.839369) (xy 424.440633 -92.702467) (xy 424.298023 -92.559857)
			(xy 424.161121 -92.411757) (xy 424.030139 -92.258397) (xy 423.905279 -92.100012) (xy 423.786733 -91.936848)
			(xy 423.674684 -91.769156) (xy 423.569306 -91.597193) (xy 423.47076 -91.421227) (xy 423.379198 -91.241527)
			(xy 423.294762 -91.05837) (xy 423.217581 -90.872041) (xy 423.147776 -90.682824) (xy 423.085453 -90.491013)
			(xy 423.030708 -90.296903) (xy 422.983626 -90.100794) (xy 422.94428 -89.902987) (xy 422.91273 -89.703788)
			(xy 422.889025 -89.503504) (xy 422.873201 -89.302444) (xy 422.865283 -89.100917) (xy 422.864788 -89.000076)
			(xy 416.5346 -89.000076) (xy 416.5346 -96.854518) (xy 416.53506 -96.864395) (xy 416.542503 -96.882694)
			(xy 416.549078 -96.890078) (xy 416.549332 -96.890332) (xy 418.043614 -98.384614) (xy 418.044122 -98.385122)
			(xy 418.0515 -98.391712) (xy 418.069799 -98.399179) (xy 418.079682 -98.3996) (xy 431.778918 -98.3996)
			(xy 431.788987 -98.400027) (xy 431.807586 -98.407746) (xy 431.814986 -98.414586) (xy 431.8254 -98.425)
			(xy 438.174388 -98.425) (xy 438.178418 -98.340399) (xy 438.190471 -98.256564) (xy 438.210439 -98.174255)
			(xy 438.238141 -98.094216) (xy 438.273325 -98.017173) (xy 438.315674 -97.943823) (xy 438.364803 -97.874831)
			(xy 438.420268 -97.810821) (xy 438.481566 -97.752373) (xy 438.548142 -97.700017) (xy 438.619394 -97.654227)
			(xy 438.694675 -97.615416) (xy 438.773305 -97.583937) (xy 438.854572 -97.560076) (xy 438.937738 -97.544047)
			(xy 439.022052 -97.535996) (xy 439.0644 -97.535492) (xy 439.102688 -97.535938) (xy 439.178978 -97.542556)
			(xy 439.254418 -97.5557) (xy 439.32845 -97.575274) (xy 439.364628 -97.587816) (xy 439.373066 -97.590458)
			(xy 439.390734 -97.590458) (xy 439.399172 -97.587816) (xy 439.435347 -97.57526) (xy 439.509376 -97.555663)
			(xy 439.584817 -97.542512) (xy 439.661111 -97.535903) (xy 439.6994 -97.535492) (xy 439.737688 -97.535938)
			(xy 439.813978 -97.542556) (xy 439.889418 -97.5557) (xy 439.96345 -97.575274) (xy 439.999628 -97.587816)
			(xy 440.008066 -97.590458) (xy 440.025734 -97.590458) (xy 440.034172 -97.587816) (xy 440.070347 -97.57526)
			(xy 440.144376 -97.555663) (xy 440.219817 -97.542512) (xy 440.296111 -97.535903) (xy 440.3344 -97.535492)
			(xy 440.376748 -97.535996) (xy 440.461062 -97.544047) (xy 440.544228 -97.560076) (xy 440.625495 -97.583937)
			(xy 440.704125 -97.615416) (xy 440.779406 -97.654227) (xy 440.850658 -97.700017) (xy 440.917234 -97.752373)
			(xy 440.978532 -97.810821) (xy 441.033997 -97.874831) (xy 441.083126 -97.943823) (xy 441.125475 -98.017173)
			(xy 441.160659 -98.094216) (xy 441.188361 -98.174255) (xy 441.208329 -98.256564) (xy 441.220382 -98.340399)
			(xy 441.224413 -98.425) (xy 441.220382 -98.509601) (xy 441.208329 -98.593436) (xy 441.188361 -98.675745)
			(xy 441.160659 -98.755784) (xy 441.125475 -98.832827) (xy 441.083126 -98.906177) (xy 441.033997 -98.975169)
			(xy 440.978532 -99.039179) (xy 440.917234 -99.097627) (xy 440.850658 -99.149983) (xy 440.779406 -99.195773)
			(xy 440.704125 -99.234584) (xy 440.625495 -99.266063) (xy 440.544228 -99.289924) (xy 440.461062 -99.305953)
			(xy 440.376748 -99.314004) (xy 440.3344 -99.314508) (xy 440.296112 -99.314062) (xy 440.219822 -99.307444)
			(xy 440.144382 -99.2943) (xy 440.07035 -99.274726) (xy 440.034172 -99.262184) (xy 440.025734 -99.259542)
			(xy 440.008066 -99.259542) (xy 439.999628 -99.262184) (xy 439.963453 -99.27474) (xy 439.889424 -99.294337)
			(xy 439.813983 -99.307488) (xy 439.737689 -99.314097) (xy 439.6994 -99.314508) (xy 439.661112 -99.314062)
			(xy 439.584822 -99.307444) (xy 439.509382 -99.2943) (xy 439.43535 -99.274726) (xy 439.399172 -99.262184)
			(xy 439.390734 -99.259542) (xy 439.373066 -99.259542) (xy 439.364628 -99.262184) (xy 439.328453 -99.27474)
			(xy 439.254424 -99.294337) (xy 439.178983 -99.307488) (xy 439.102689 -99.314097) (xy 439.0644 -99.314508)
			(xy 439.022052 -99.314004) (xy 438.937738 -99.305953) (xy 438.854572 -99.289924) (xy 438.773305 -99.266063)
			(xy 438.694675 -99.234584) (xy 438.619394 -99.195773) (xy 438.548142 -99.149983) (xy 438.481566 -99.097627)
			(xy 438.420268 -99.039179) (xy 438.364803 -98.975169) (xy 438.315674 -98.906177) (xy 438.273325 -98.832827)
			(xy 438.238141 -98.755784) (xy 438.210439 -98.675745) (xy 438.190471 -98.593436) (xy 438.178418 -98.509601)
			(xy 438.174388 -98.425) (xy 431.8254 -98.425) (xy 434.3654 -100.965) (xy 438.174388 -100.965) (xy 438.178418 -100.880399)
			(xy 438.190471 -100.796564) (xy 438.210439 -100.714255) (xy 438.238141 -100.634216) (xy 438.273325 -100.557173)
			(xy 438.315674 -100.483823) (xy 438.364803 -100.414831) (xy 438.420268 -100.350821) (xy 438.481566 -100.292373)
			(xy 438.548142 -100.240017) (xy 438.619394 -100.194227) (xy 438.694675 -100.155416) (xy 438.773305 -100.123937)
			(xy 438.854572 -100.100076) (xy 438.937738 -100.084047) (xy 439.022052 -100.075996) (xy 439.0644 -100.075492)
			(xy 439.102688 -100.075938) (xy 439.178978 -100.082556) (xy 439.254418 -100.0957) (xy 439.32845 -100.115274)
			(xy 439.364628 -100.127816) (xy 439.373066 -100.130458) (xy 439.390734 -100.130458) (xy 439.399172 -100.127816)
			(xy 439.435347 -100.11526) (xy 439.509376 -100.095663) (xy 439.584817 -100.082512) (xy 439.661111 -100.075903)
			(xy 439.6994 -100.075492) (xy 439.737688 -100.075938) (xy 439.813978 -100.082556) (xy 439.889418 -100.0957)
			(xy 439.96345 -100.115274) (xy 439.999628 -100.127816) (xy 440.008066 -100.130458) (xy 440.025734 -100.130458)
			(xy 440.034172 -100.127816) (xy 440.070347 -100.11526) (xy 440.144376 -100.095663) (xy 440.219817 -100.082512)
			(xy 440.296111 -100.075903) (xy 440.3344 -100.075492) (xy 440.376748 -100.075996) (xy 440.461062 -100.084047)
			(xy 440.544228 -100.100076) (xy 440.625495 -100.123937) (xy 440.704125 -100.155416) (xy 440.779406 -100.194227)
			(xy 440.850658 -100.240017) (xy 440.917234 -100.292373) (xy 440.978532 -100.350821) (xy 441.033997 -100.414831)
			(xy 441.083126 -100.483823) (xy 441.125475 -100.557173) (xy 441.160659 -100.634216) (xy 441.188361 -100.714255)
			(xy 441.208329 -100.796564) (xy 441.220382 -100.880399) (xy 441.224413 -100.965) (xy 441.220382 -101.049601)
			(xy 441.208329 -101.133436) (xy 441.188361 -101.215745) (xy 441.160659 -101.295784) (xy 441.125475 -101.372827)
			(xy 441.083126 -101.446177) (xy 441.033997 -101.515169) (xy 440.978532 -101.579179) (xy 440.917234 -101.637627)
			(xy 440.850658 -101.689983) (xy 440.779406 -101.735773) (xy 440.704125 -101.774584) (xy 440.625495 -101.806063)
			(xy 440.544228 -101.829924) (xy 440.461062 -101.845953) (xy 440.376748 -101.854004) (xy 440.3344 -101.854508)
			(xy 440.296112 -101.854062) (xy 440.219822 -101.847444) (xy 440.144382 -101.8343) (xy 440.07035 -101.814726)
			(xy 440.034172 -101.802184) (xy 440.025734 -101.799542) (xy 440.008066 -101.799542) (xy 439.999628 -101.802184)
			(xy 439.963453 -101.81474) (xy 439.889424 -101.834337) (xy 439.813983 -101.847488) (xy 439.737689 -101.854097)
			(xy 439.6994 -101.854508) (xy 439.661112 -101.854062) (xy 439.584822 -101.847444) (xy 439.509382 -101.8343)
			(xy 439.43535 -101.814726) (xy 439.399172 -101.802184) (xy 439.390734 -101.799542) (xy 439.373066 -101.799542)
			(xy 439.364628 -101.802184) (xy 439.328453 -101.81474) (xy 439.254424 -101.834337) (xy 439.178983 -101.847488)
			(xy 439.102689 -101.854097) (xy 439.0644 -101.854508) (xy 439.022052 -101.854004) (xy 438.937738 -101.845953)
			(xy 438.854572 -101.829924) (xy 438.773305 -101.806063) (xy 438.694675 -101.774584) (xy 438.619394 -101.735773)
			(xy 438.548142 -101.689983) (xy 438.481566 -101.637627) (xy 438.420268 -101.579179) (xy 438.364803 -101.515169)
			(xy 438.315674 -101.446177) (xy 438.273325 -101.372827) (xy 438.238141 -101.295784) (xy 438.210439 -101.215745)
			(xy 438.190471 -101.133436) (xy 438.178418 -101.049601) (xy 438.174388 -100.965) (xy 434.3654 -100.965)
			(xy 442.478414 -109.078014) (xy 442.478922 -109.078522) (xy 442.4863 -109.085112) (xy 442.504599 -109.092579)
			(xy 442.514482 -109.093)
		)
		(stroke
			(width 0)
			(type solid)
		)
		(fill yes)
		(layer "In7.Cu")
		(net "P12V_HPDB")
	)
	(gr_poly
		(pts
			(xy 292.034214 -101.7143) (xy 292.041734 -101.712701) (xy 292.055425 -101.705729) (xy 292.061138 -101.700584)
			(xy 293.087298 -100.674424) (xy 293.090346 -100.671122) (xy 293.102284 -100.659184) (xy 293.102284 -96.724216)
			(xy 293.101845 -96.714153) (xy 293.094107 -96.695572) (xy 293.087298 -96.688148) (xy 292.29939 -95.899986)
			(xy 290.670488 -94.271084) (xy 290.663376 -94.263718) (xy 290.64458 -94.256098) (xy 268.349984 -94.256098)
			(xy 268.339915 -94.256524) (xy 268.321315 -94.264242) (xy 268.313916 -94.271084) (xy 266.729972 -95.855028)
			(xy 266.722575 -95.861878) (xy 266.703977 -95.869613) (xy 266.693904 -95.870014) (xy 264.979404 -95.870014)
			(xy 264.972454 -95.870257) (xy 264.959065 -95.873998) (xy 264.952988 -95.87738) (xy 264.952734 -95.877634)
			(xy 264.946728 -95.881021) (xy 264.933462 -95.884756) (xy 264.926572 -95.885) (xy 256.850642 -95.885)
			(xy 256.840577 -95.884566) (xy 256.821987 -95.876837) (xy 256.814574 -95.870014) (xy 256.395728 -95.451168)
			(xy 256.388883 -95.443769) (xy 256.381156 -95.425171) (xy 256.380742 -95.4151) (xy 256.380742 -76.729082)
			(xy 256.380314 -76.719015) (xy 256.372589 -76.70042) (xy 256.365756 -76.693014) (xy 255.53289 -75.860148)
			(xy 255.525778 -75.852782) (xy 255.506982 -75.845162) (xy 240.898172 -75.845162) (xy 240.883327 -75.845678)
			(xy 240.854893 -75.854227) (xy 240.830121 -75.870595) (xy 240.811105 -75.893398) (xy 240.799452 -75.920707)
			(xy 240.796149 -75.950214) (xy 240.801474 -75.979424) (xy 240.814977 -76.005867) (xy 240.835517 -76.027307)
			(xy 240.848134 -76.035154) (xy 240.926749 -76.08036) (xy 241.080386 -76.176748) (xy 241.229642 -76.27979)
			(xy 241.374228 -76.389288) (xy 241.513865 -76.50503) (xy 241.648284 -76.626794) (xy 241.777226 -76.754343)
			(xy 241.900441 -76.887433) (xy 242.017692 -77.025806) (xy 242.128753 -77.169195) (xy 242.233408 -77.317323)
			(xy 242.331458 -77.469905) (xy 242.422711 -77.626646) (xy 242.506992 -77.787244) (xy 242.584138 -77.951388)
			(xy 242.654001 -78.118762) (xy 242.716445 -78.289043) (xy 242.771351 -78.461902) (xy 242.818611 -78.637006)
			(xy 242.858136 -78.814016) (xy 242.889848 -78.992592) (xy 242.913686 -79.172388) (xy 242.929605 -79.353057)
			(xy 242.937573 -79.534251) (xy 242.938046 -79.624936) (xy 242.937541 -79.716267) (xy 242.929461 -79.898751)
			(xy 242.913317 -80.080699) (xy 242.889141 -80.261755) (xy 242.85698 -80.441564) (xy 242.816897 -80.619774)
			(xy 242.76897 -80.796037) (xy 242.713293 -80.970008) (xy 242.649976 -81.141345) (xy 242.579141 -81.309714)
			(xy 242.500929 -81.474786) (xy 242.415491 -81.636235) (xy 242.322996 -81.793748) (xy 242.223624 -81.947015)
			(xy 242.117569 -82.095737) (xy 242.00504 -82.239622) (xy 241.886257 -82.378388) (xy 241.761451 -82.511764)
			(xy 241.630869 -82.63949) (xy 241.494764 -82.761314) (xy 241.353404 -82.876999) (xy 241.207065 -82.986317)
			(xy 241.056033 -83.089056) (xy 240.900605 -83.185013) (xy 240.741085 -83.274001) (xy 240.577785 -83.355846)
			(xy 240.411024 -83.430388) (xy 240.241129 -83.49748) (xy 240.068433 -83.556992) (xy 239.893273 -83.608806)
			(xy 239.715993 -83.652822) (xy 239.536939 -83.688953) (xy 239.356463 -83.717129) (xy 239.174916 -83.737293)
			(xy 238.992656 -83.749408) (xy 238.810038 -83.753449) (xy 238.62742 -83.749408) (xy 238.44516 -83.737293)
			(xy 238.263613 -83.717129) (xy 238.083137 -83.688953) (xy 237.904083 -83.652822) (xy 237.726803 -83.608806)
			(xy 237.551643 -83.556992) (xy 237.378947 -83.49748) (xy 237.209052 -83.430388) (xy 237.042291 -83.355846)
			(xy 236.878991 -83.274001) (xy 236.719471 -83.185013) (xy 236.564043 -83.089056) (xy 236.413011 -82.986317)
			(xy 236.266672 -82.876999) (xy 236.125312 -82.761314) (xy 235.989207 -82.63949) (xy 235.858625 -82.511764)
			(xy 235.733819 -82.378388) (xy 235.615036 -82.239622) (xy 235.502507 -82.095737) (xy 235.396452 -81.947015)
			(xy 235.29708 -81.793748) (xy 235.204585 -81.636235) (xy 235.119147 -81.474786) (xy 235.040935 -81.309714)
			(xy 234.9701 -81.141345) (xy 234.906783 -80.970008) (xy 234.851106 -80.796037) (xy 234.803179 -80.619774)
			(xy 234.763096 -80.441564) (xy 234.730935 -80.261755) (xy 234.706759 -80.080699) (xy 234.690615 -79.898751)
			(xy 234.682535 -79.716267) (xy 234.68203 -79.624936) (xy 234.682527 -79.534251) (xy 234.690492 -79.353056)
			(xy 234.706407 -79.172386) (xy 234.730241 -78.992589) (xy 234.76195 -78.814013) (xy 234.801471 -78.637001)
			(xy 234.848729 -78.461896) (xy 234.903631 -78.289036) (xy 234.966073 -78.118754) (xy 235.035934 -77.951379)
			(xy 235.113078 -77.787233) (xy 235.197358 -77.626635) (xy 235.28861 -77.469892) (xy 235.386658 -77.317309)
			(xy 235.491313 -77.16918) (xy 235.602372 -77.02579) (xy 235.719623 -76.887416) (xy 235.842838 -76.754326)
			(xy 235.971779 -76.626775) (xy 236.106199 -76.505011) (xy 236.245836 -76.389269) (xy 236.390422 -76.27977)
			(xy 236.539678 -76.176728) (xy 236.693316 -76.080341) (xy 236.771942 -76.035154) (xy 236.784608 -76.027393)
			(xy 236.805142 -76.005946) (xy 236.818638 -75.979499) (xy 236.823955 -75.950287) (xy 236.820644 -75.920781)
			(xy 236.808985 -75.893474) (xy 236.789963 -75.870676) (xy 236.765186 -75.854314) (xy 236.73675 -75.845771)
			(xy 236.721904 -75.845162) (xy 230.83901 -75.845162) (xy 230.82894 -75.84474) (xy 230.810336 -75.837024)
			(xy 230.802942 -75.830176) (xy 226.979734 -72.006968) (xy 226.972889 -71.999569) (xy 226.965161 -71.980971)
			(xy 226.964748 -71.9709) (xy 226.964748 -28.986734) (xy 226.965185 -28.97667) (xy 226.972921 -28.958088)
			(xy 226.979734 -28.950666) (xy 229.922578 -26.007822) (xy 229.92998 -26.000985) (xy 229.948578 -25.993276)
			(xy 229.958646 -25.992836) (xy 236.31652 -25.992836) (xy 236.33071 -25.992337) (xy 236.357979 -25.98447)
			(xy 236.382032 -25.969403) (xy 236.401011 -25.948301) (xy 236.413452 -25.922791) (xy 236.418394 -25.894843)
			(xy 236.415456 -25.866614) (xy 236.404865 -25.840282) (xy 236.387438 -25.817881) (xy 236.37621 -25.809194)
			(xy 236.301866 -25.754291) (xy 236.1576 -25.638742) (xy 236.01865 -25.516851) (xy 235.885296 -25.388863)
			(xy 235.757804 -25.255034) (xy 235.63643 -25.115632) (xy 235.521418 -24.970938) (xy 235.412997 -24.82124)
			(xy 235.311386 -24.66684) (xy 235.216788 -24.508046) (xy 235.129392 -24.345176) (xy 235.049375 -24.178559)
			(xy 234.976895 -24.008526) (xy 234.912099 -23.83542) (xy 234.855116 -23.659586) (xy 234.806061 -23.481379)
			(xy 234.765032 -23.301154) (xy 234.732111 -23.119273) (xy 234.707364 -22.936101) (xy 234.690841 -22.752005)
			(xy 234.682575 -22.567354) (xy 234.68203 -22.474936) (xy 234.682535 -22.383605) (xy 234.690615 -22.201121)
			(xy 234.706759 -22.019173) (xy 234.730935 -21.838117) (xy 234.763096 -21.658308) (xy 234.803179 -21.480098)
			(xy 234.851106 -21.303835) (xy 234.906783 -21.129864) (xy 234.9701 -20.958527) (xy 235.040935 -20.790158)
			(xy 235.119147 -20.625086) (xy 235.204585 -20.463637) (xy 235.29708 -20.306124) (xy 235.396452 -20.152857)
			(xy 235.502507 -20.004135) (xy 235.615036 -19.86025) (xy 235.733819 -19.721484) (xy 235.858625 -19.588108)
			(xy 235.989207 -19.460382) (xy 236.125312 -19.338558) (xy 236.266672 -19.222873) (xy 236.413011 -19.113555)
			(xy 236.564043 -19.010816) (xy 236.719471 -18.914859) (xy 236.878991 -18.825871) (xy 237.042291 -18.744026)
			(xy 237.209052 -18.669484) (xy 237.378947 -18.602392) (xy 237.551643 -18.54288) (xy 237.726803 -18.491066)
			(xy 237.904083 -18.44705) (xy 238.083137 -18.410919) (xy 238.263613 -18.382743) (xy 238.44516 -18.362579)
			(xy 238.62742 -18.350464) (xy 238.810038 -18.346423) (xy 238.992656 -18.350464) (xy 239.174916 -18.362579)
			(xy 239.356463 -18.382743) (xy 239.536939 -18.410919) (xy 239.715993 -18.44705) (xy 239.893273 -18.491066)
			(xy 240.068433 -18.54288) (xy 240.241129 -18.602392) (xy 240.411024 -18.669484) (xy 240.577785 -18.744026)
			(xy 240.741085 -18.825871) (xy 240.900605 -18.914859) (xy 241.056033 -19.010816) (xy 241.207065 -19.113555)
			(xy 241.353404 -19.222873) (xy 241.494764 -19.338558) (xy 241.630869 -19.460382) (xy 241.761451 -19.588108)
			(xy 241.886257 -19.721484) (xy 242.00504 -19.86025) (xy 242.117569 -20.004135) (xy 242.223624 -20.152857)
			(xy 242.322996 -20.306124) (xy 242.415491 -20.463637) (xy 242.500929 -20.625086) (xy 242.579141 -20.790158)
			(xy 242.649976 -20.958527) (xy 242.713293 -21.129864) (xy 242.76897 -21.303835) (xy 242.816897 -21.480098)
			(xy 242.85698 -21.658308) (xy 242.889141 -21.838117) (xy 242.913317 -22.019173) (xy 242.929461 -22.201121)
			(xy 242.937541 -22.383605) (xy 242.938046 -22.474936) (xy 242.937531 -22.567354) (xy 242.929256 -22.752005)
			(xy 242.912726 -22.9361) (xy 242.887973 -23.119271) (xy 242.855046 -23.301151) (xy 242.814012 -23.481375)
			(xy 242.764954 -23.659581) (xy 242.707968 -23.835413) (xy 242.643169 -24.008519) (xy 242.570688 -24.178551)
			(xy 242.49067 -24.345169) (xy 242.403275 -24.508038) (xy 242.308677 -24.666832) (xy 242.207067 -24.821234)
			(xy 242.098649 -24.970933) (xy 241.983639 -25.11563) (xy 241.862269 -25.255034) (xy 241.73478 -25.388866)
			(xy 241.60143 -25.516858) (xy 241.462485 -25.638754) (xy 241.318223 -25.754309) (xy 241.243866 -25.809194)
			(xy 241.232694 -25.817938) (xy 241.215284 -25.840324) (xy 241.204704 -25.866636) (xy 241.20177 -25.894843)
			(xy 241.206708 -25.922769) (xy 241.219138 -25.948259) (xy 241.2381 -25.969347) (xy 241.262131 -25.984405)
			(xy 241.289378 -25.992271) (xy 241.303556 -25.992836) (xy 247.14454 -25.992836) (xy 247.154081 -25.992384)
			(xy 247.171819 -25.985331) (xy 247.185782 -25.972317) (xy 247.19026 -25.96388) (xy 247.195086 -25.95372)
			(xy 247.196356 -25.949656) (xy 247.21947 -25.872186) (xy 247.221916 -25.862475) (xy 247.219802 -25.842577)
			(xy 247.215406 -25.833578) (xy 247.215406 -25.833324) (xy 247.203468 -25.812242) (xy 247.195086 -25.803098)
			(xy 247.190006 -25.799542) (xy 247.105018 -25.743376) (xy 246.939048 -25.625211) (xy 246.777894 -25.500556)
			(xy 246.621811 -25.369608) (xy 246.471045 -25.232574) (xy 246.325831 -25.089667) (xy 246.186399 -24.941114)
			(xy 246.052968 -24.787149) (xy 245.925749 -24.628013) (xy 245.80494 -24.463956) (xy 245.690733 -24.295237)
			(xy 245.583307 -24.122122) (xy 245.482831 -23.944883) (xy 245.389464 -23.763798) (xy 245.303351 -23.579153)
			(xy 245.224629 -23.391238) (xy 245.153421 -23.200349) (xy 245.08984 -23.006786) (xy 245.033985 -22.810854)
			(xy 244.985945 -22.612861) (xy 244.945795 -22.413118) (xy 244.913598 -22.21194) (xy 244.889405 -22.009643)
			(xy 244.873253 -21.806547) (xy 244.865169 -21.602969) (xy 244.864636 -21.5011) (xy 244.864636 -16.500348)
			(xy 244.865131 -16.399507) (xy 244.873049 -16.19798) (xy 244.888873 -15.99692) (xy 244.912578 -15.796636)
			(xy 244.944128 -15.597437) (xy 244.983474 -15.39963) (xy 245.030556 -15.203521) (xy 245.085301 -15.009411)
			(xy 245.147624 -14.8176) (xy 245.217429 -14.628383) (xy 245.29461 -14.442054) (xy 245.379046 -14.258897)
			(xy 245.470608 -14.079197) (xy 245.569154 -13.903231) (xy 245.674532 -13.731268) (xy 245.786581 -13.563576)
			(xy 245.905127 -13.400412) (xy 246.029987 -13.242027) (xy 246.160969 -13.088667) (xy 246.297871 -12.940567)
			(xy 246.440481 -12.797957) (xy 246.588581 -12.661055) (xy 246.741941 -12.530073) (xy 246.900326 -12.405213)
			(xy 247.06349 -12.286667) (xy 247.231182 -12.174618) (xy 247.403145 -12.06924) (xy 247.579111 -11.970694)
			(xy 247.758811 -11.879132) (xy 247.941968 -11.794696) (xy 248.128297 -11.717515) (xy 248.317514 -11.64771)
			(xy 248.509325 -11.585387) (xy 248.703435 -11.530642) (xy 248.899544 -11.48356) (xy 249.097351 -11.444214)
			(xy 249.29655 -11.412664) (xy 249.496834 -11.388959) (xy 249.697894 -11.373135) (xy 249.899421 -11.365217)
			(xy 250.101103 -11.365217) (xy 250.30263 -11.373135) (xy 250.50369 -11.388959) (xy 250.703974 -11.412664)
			(xy 250.903173 -11.444214) (xy 251.10098 -11.48356) (xy 251.297089 -11.530642) (xy 251.491199 -11.585387)
			(xy 251.68301 -11.64771) (xy 251.872227 -11.717515) (xy 252.058556 -11.794696) (xy 252.241713 -11.879132)
			(xy 252.421413 -11.970694) (xy 252.597379 -12.06924) (xy 252.769342 -12.174618) (xy 252.937034 -12.286667)
			(xy 253.100198 -12.405213) (xy 253.258583 -12.530073) (xy 253.411943 -12.661055) (xy 253.560043 -12.797957)
			(xy 253.702653 -12.940567) (xy 253.839555 -13.088667) (xy 253.970537 -13.242027) (xy 254.095397 -13.400412)
			(xy 254.213943 -13.563576) (xy 254.325992 -13.731268) (xy 254.43137 -13.903231) (xy 254.529916 -14.079197)
			(xy 254.621478 -14.258897) (xy 254.705914 -14.442054) (xy 254.783095 -14.628383) (xy 254.8529 -14.8176)
			(xy 254.915223 -15.009411) (xy 254.969968 -15.203521) (xy 255.01705 -15.39963) (xy 255.056396 -15.597437)
			(xy 255.087946 -15.796636) (xy 255.111651 -15.99692) (xy 255.127475 -16.19798) (xy 255.135393 -16.399507)
			(xy 255.135888 -16.500348) (xy 255.135888 -21.500338) (xy 255.13538 -21.602417) (xy 255.127266 -21.806414)
			(xy 255.111051 -22.009927) (xy 255.086761 -22.212635) (xy 255.054435 -22.414217) (xy 255.014124 -22.614356)
			(xy 254.965891 -22.812735) (xy 254.909813 -23.00904) (xy 254.845978 -23.202962) (xy 254.774487 -23.394193)
			(xy 254.695453 -23.582433) (xy 254.609001 -23.767383) (xy 254.515268 -23.948752) (xy 254.414401 -24.126252)
			(xy 254.30656 -24.299604) (xy 254.191915 -24.468533) (xy 254.070648 -24.632773) (xy 253.942949 -24.792064)
			(xy 253.809022 -24.946154) (xy 253.669076 -25.094801) (xy 253.616884 -25.146) (xy 272.541492 -25.146)
			(xy 272.541975 -25.117081) (xy 272.550707 -25.059907) (xy 272.567969 -25.004706) (xy 272.593367 -24.952744)
			(xy 272.626319 -24.905211) (xy 272.666068 -24.863197) (xy 272.688558 -24.84501) (xy 272.697321 -24.837449)
			(xy 272.707501 -24.816689) (xy 272.708116 -24.805132) (xy 272.708116 -24.724868) (xy 272.707501 -24.713306)
			(xy 272.697337 -24.692535) (xy 272.688558 -24.68499) (xy 272.666061 -24.666815) (xy 272.626329 -24.624791)
			(xy 272.593392 -24.577252) (xy 272.568007 -24.525288) (xy 272.550753 -24.470088) (xy 272.542026 -24.412917)
			(xy 272.541492 -24.384) (xy 272.541978 -24.356749) (xy 272.549734 -24.302801) (xy 272.565089 -24.250506)
			(xy 272.587731 -24.200929) (xy 272.617197 -24.155079) (xy 272.652888 -24.113888) (xy 272.694079 -24.078197)
			(xy 272.739929 -24.048731) (xy 272.789506 -24.026089) (xy 272.841801 -24.010734) (xy 272.895749 -24.002978)
			(xy 272.923 -24.002492) (xy 272.951919 -24.002975) (xy 273.009093 -24.011707) (xy 273.064294 -24.028969)
			(xy 273.116256 -24.054367) (xy 273.163789 -24.087319) (xy 273.205803 -24.127068) (xy 273.22399 -24.149558)
			(xy 273.231551 -24.158321) (xy 273.252311 -24.168501) (xy 273.263868 -24.169116) (xy 273.344132 -24.169116)
			(xy 273.355694 -24.168501) (xy 273.376465 -24.158337) (xy 273.38401 -24.149558) (xy 273.400763 -24.128775)
			(xy 273.439117 -24.091645) (xy 273.482271 -24.060223) (xy 273.529385 -24.035124) (xy 273.579537 -24.016838)
			(xy 273.631748 -24.005721) (xy 273.685 -24.001991) (xy 273.738252 -24.005721) (xy 273.790463 -24.016838)
			(xy 273.840615 -24.035124) (xy 273.887729 -24.060223) (xy 273.930883 -24.091645) (xy 273.969237 -24.128775)
			(xy 273.98599 -24.149558) (xy 273.993551 -24.158321) (xy 274.014311 -24.168501) (xy 274.025868 -24.169116)
			(xy 274.106132 -24.169116) (xy 274.117694 -24.168501) (xy 274.138465 -24.158337) (xy 274.14601 -24.149558)
			(xy 274.162763 -24.128775) (xy 274.201117 -24.091645) (xy 274.244271 -24.060223) (xy 274.291385 -24.035124)
			(xy 274.341537 -24.016838) (xy 274.393748 -24.005721) (xy 274.447 -24.001991) (xy 274.500252 -24.005721)
			(xy 274.552463 -24.016838) (xy 274.602615 -24.035124) (xy 274.649729 -24.060223) (xy 274.692883 -24.091645)
			(xy 274.731237 -24.128775) (xy 274.74799 -24.149558) (xy 274.755551 -24.158321) (xy 274.776311 -24.168501)
			(xy 274.787868 -24.169116) (xy 274.868132 -24.169116) (xy 274.879694 -24.168501) (xy 274.900465 -24.158337)
			(xy 274.90801 -24.149558) (xy 274.924763 -24.128775) (xy 274.963117 -24.091645) (xy 275.006271 -24.060223)
			(xy 275.053385 -24.035124) (xy 275.103537 -24.016838) (xy 275.155748 -24.005721) (xy 275.209 -24.001991)
			(xy 275.262252 -24.005721) (xy 275.314463 -24.016838) (xy 275.364615 -24.035124) (xy 275.411729 -24.060223)
			(xy 275.454883 -24.091645) (xy 275.493237 -24.128775) (xy 275.50999 -24.149558) (xy 275.517551 -24.158321)
			(xy 275.538311 -24.168501) (xy 275.549868 -24.169116) (xy 275.630132 -24.169116) (xy 275.641694 -24.168501)
			(xy 275.662465 -24.158337) (xy 275.67001 -24.149558) (xy 275.688185 -24.127061) (xy 275.730209 -24.087329)
			(xy 275.777748 -24.054392) (xy 275.829712 -24.029007) (xy 275.884912 -24.011753) (xy 275.942083 -24.003026)
			(xy 275.971 -24.002492) (xy 275.998251 -24.002978) (xy 276.052199 -24.010734) (xy 276.104494 -24.026089)
			(xy 276.154071 -24.048731) (xy 276.199921 -24.078197) (xy 276.241112 -24.113888) (xy 276.276803 -24.155079)
			(xy 276.306269 -24.200929) (xy 276.328911 -24.250506) (xy 276.344266 -24.302801) (xy 276.352022 -24.356749)
			(xy 276.352508 -24.384) (xy 276.352025 -24.412919) (xy 276.343293 -24.470093) (xy 276.326031 -24.525294)
			(xy 276.300633 -24.577256) (xy 276.267681 -24.624789) (xy 276.227932 -24.666803) (xy 276.205442 -24.68499)
			(xy 276.196679 -24.692551) (xy 276.186499 -24.713311) (xy 276.185884 -24.724868) (xy 276.185884 -24.805132)
			(xy 276.186499 -24.816694) (xy 276.196663 -24.837465) (xy 276.205442 -24.84501) (xy 276.227939 -24.863185)
			(xy 276.267671 -24.905209) (xy 276.300608 -24.952748) (xy 276.325993 -25.004712) (xy 276.343247 -25.059912)
			(xy 276.351974 -25.117083) (xy 276.352508 -25.146) (xy 276.352022 -25.173251) (xy 276.344266 -25.227199)
			(xy 276.328911 -25.279494) (xy 276.306269 -25.329071) (xy 276.276803 -25.374921) (xy 276.241112 -25.416112)
			(xy 276.199921 -25.451803) (xy 276.154071 -25.481269) (xy 276.104494 -25.503911) (xy 276.052199 -25.519266)
			(xy 275.998251 -25.527022) (xy 275.971 -25.527508) (xy 275.942081 -25.527025) (xy 275.884907 -25.518293)
			(xy 275.829706 -25.501031) (xy 275.777744 -25.475633) (xy 275.730211 -25.442681) (xy 275.688197 -25.402932)
			(xy 275.67001 -25.380442) (xy 275.662449 -25.371679) (xy 275.641689 -25.361499) (xy 275.630132 -25.360884)
			(xy 275.549868 -25.360884) (xy 275.538306 -25.361499) (xy 275.517535 -25.371663) (xy 275.50999 -25.380442)
			(xy 275.493237 -25.401225) (xy 275.454883 -25.438355) (xy 275.411729 -25.469777) (xy 275.364615 -25.494876)
			(xy 275.314463 -25.513162) (xy 275.262252 -25.524279) (xy 275.209 -25.528009) (xy 275.155748 -25.524279)
			(xy 275.103537 -25.513162) (xy 275.053385 -25.494876) (xy 275.006271 -25.469777) (xy 274.963117 -25.438355)
			(xy 274.924763 -25.401225) (xy 274.90801 -25.380442) (xy 274.900449 -25.371679) (xy 274.879689 -25.361499)
			(xy 274.868132 -25.360884) (xy 274.787868 -25.360884) (xy 274.776306 -25.361499) (xy 274.755535 -25.371663)
			(xy 274.74799 -25.380442) (xy 274.731237 -25.401225) (xy 274.692883 -25.438355) (xy 274.649729 -25.469777)
			(xy 274.602615 -25.494876) (xy 274.552463 -25.513162) (xy 274.500252 -25.524279) (xy 274.447 -25.528009)
			(xy 274.393748 -25.524279) (xy 274.341537 -25.513162) (xy 274.291385 -25.494876) (xy 274.244271 -25.469777)
			(xy 274.201117 -25.438355) (xy 274.162763 -25.401225) (xy 274.14601 -25.380442) (xy 274.138449 -25.371679)
			(xy 274.117689 -25.361499) (xy 274.106132 -25.360884) (xy 274.025868 -25.360884) (xy 274.014306 -25.361499)
			(xy 273.993535 -25.371663) (xy 273.98599 -25.380442) (xy 273.969237 -25.401225) (xy 273.930883 -25.438355)
			(xy 273.887729 -25.469777) (xy 273.840615 -25.494876) (xy 273.790463 -25.513162) (xy 273.738252 -25.524279)
			(xy 273.685 -25.528009) (xy 273.631748 -25.524279) (xy 273.579537 -25.513162) (xy 273.529385 -25.494876)
			(xy 273.482271 -25.469777) (xy 273.439117 -25.438355) (xy 273.400763 -25.401225) (xy 273.38401 -25.380442)
			(xy 273.376449 -25.371679) (xy 273.355689 -25.361499) (xy 273.344132 -25.360884) (xy 273.263868 -25.360884)
			(xy 273.252306 -25.361499) (xy 273.231535 -25.371663) (xy 273.22399 -25.380442) (xy 273.205815 -25.402939)
			(xy 273.163791 -25.442671) (xy 273.116252 -25.475608) (xy 273.064288 -25.500993) (xy 273.009088 -25.518247)
			(xy 272.951917 -25.526974) (xy 272.923 -25.527508) (xy 272.895749 -25.527022) (xy 272.841801 -25.519266)
			(xy 272.789506 -25.503911) (xy 272.739929 -25.481269) (xy 272.694079 -25.451803) (xy 272.652888 -25.416112)
			(xy 272.617197 -25.374921) (xy 272.587731 -25.329071) (xy 272.565089 -25.279494) (xy 272.549734 -25.227199)
			(xy 272.541978 -25.173251) (xy 272.541492 -25.146) (xy 253.616884 -25.146) (xy 253.523334 -25.237769)
			(xy 253.372026 -25.374832) (xy 253.215391 -25.505774) (xy 253.053675 -25.630388) (xy 252.887135 -25.748477)
			(xy 252.801882 -25.804622) (xy 252.801628 -25.804876) (xy 252.799342 -25.8064) (xy 252.79604 -25.80894)
			(xy 252.788166 -25.815552) (xy 252.77804 -25.833427) (xy 252.775727 -25.85384) (xy 252.77826 -25.863804)
			(xy 252.805946 -25.956514) (xy 252.809529 -25.966802) (xy 252.823792 -25.98324) (xy 252.84358 -25.992301)
			(xy 252.85446 -25.992836) (xy 276.779482 -25.992836) (xy 276.788118 -25.992074) (xy 276.795637 -25.990474)
			(xy 276.809326 -25.983498) (xy 276.815042 -25.978358) (xy 277.29815 -25.49525) (xy 277.304994 -25.487851)
			(xy 277.312718 -25.469252) (xy 277.313136 -25.459182) (xy 277.313136 -15.673578) (xy 277.313564 -15.66351)
			(xy 277.321288 -15.644915) (xy 277.328122 -15.63751) (xy 281.520646 -11.444986) (xy 281.528043 -11.438137)
			(xy 281.546642 -11.430406) (xy 281.556714 -11.43) (xy 335.487518 -11.43) (xy 335.497587 -11.430427)
			(xy 335.516186 -11.438146) (xy 335.523586 -11.444986) (xy 339.287866 -15.209266) (xy 339.295266 -15.216106)
			(xy 339.313865 -15.223821) (xy 339.323934 -15.224252) (xy 354.966016 -15.224252) (xy 354.976084 -15.22468)
			(xy 354.994679 -15.232404) (xy 355.002084 -15.239238) (xy 357.155496 -17.39265) (xy 357.167434 -17.399254)
			(xy 357.174292 -17.401032) (xy 357.181063 -17.402865) (xy 357.193311 -17.40969) (xy 357.198422 -17.414494)
			(xy 358.284018 -18.50009) (xy 363.864652 -18.50009) (xy 363.864652 -13.5001) (xy 363.865147 -13.399259)
			(xy 363.873065 -13.197732) (xy 363.888889 -12.996672) (xy 363.912594 -12.796388) (xy 363.944144 -12.597189)
			(xy 363.98349 -12.399382) (xy 364.030572 -12.203273) (xy 364.085317 -12.009163) (xy 364.14764 -11.817352)
			(xy 364.217445 -11.628135) (xy 364.294626 -11.441806) (xy 364.379062 -11.258649) (xy 364.470624 -11.078949)
			(xy 364.56917 -10.902983) (xy 364.674548 -10.73102) (xy 364.786597 -10.563328) (xy 364.905143 -10.400164)
			(xy 365.030003 -10.241779) (xy 365.160985 -10.088419) (xy 365.297887 -9.940319) (xy 365.440497 -9.797709)
			(xy 365.588597 -9.660807) (xy 365.741957 -9.529825) (xy 365.900342 -9.404965) (xy 366.063506 -9.286419)
			(xy 366.231198 -9.17437) (xy 366.403161 -9.068992) (xy 366.579127 -8.970446) (xy 366.758827 -8.878884)
			(xy 366.941984 -8.794448) (xy 367.128313 -8.717267) (xy 367.31753 -8.647462) (xy 367.509341 -8.585139)
			(xy 367.703451 -8.530394) (xy 367.89956 -8.483312) (xy 368.097367 -8.443966) (xy 368.296566 -8.412416)
			(xy 368.49685 -8.388711) (xy 368.69791 -8.372887) (xy 368.899437 -8.364969) (xy 369.101119 -8.364969)
			(xy 369.302646 -8.372887) (xy 369.503706 -8.388711) (xy 369.70399 -8.412416) (xy 369.903189 -8.443966)
			(xy 370.100996 -8.483312) (xy 370.297105 -8.530394) (xy 370.491215 -8.585139) (xy 370.683026 -8.647462)
			(xy 370.872243 -8.717267) (xy 371.058572 -8.794448) (xy 371.241729 -8.878884) (xy 371.421429 -8.970446)
			(xy 371.597395 -9.068992) (xy 371.769358 -9.17437) (xy 371.93705 -9.286419) (xy 372.100214 -9.404965)
			(xy 372.258599 -9.529825) (xy 372.411959 -9.660807) (xy 372.560059 -9.797709) (xy 372.702669 -9.940319)
			(xy 372.839571 -10.088419) (xy 372.970553 -10.241779) (xy 373.095413 -10.400164) (xy 373.213959 -10.563328)
			(xy 373.326008 -10.73102) (xy 373.431386 -10.902983) (xy 373.529932 -11.078949) (xy 373.621494 -11.258649)
			(xy 373.70593 -11.441806) (xy 373.783111 -11.628135) (xy 373.852916 -11.817352) (xy 373.915239 -12.009163)
			(xy 373.969984 -12.203273) (xy 374.017066 -12.399382) (xy 374.056412 -12.597189) (xy 374.087962 -12.796388)
			(xy 374.111667 -12.996672) (xy 374.127491 -13.197732) (xy 374.135409 -13.399259) (xy 374.135904 -13.5001)
			(xy 374.135904 -16.129) (xy 380.155702 -16.129) (xy 380.159773 -16.073378) (xy 380.171899 -16.018941)
			(xy 380.191822 -15.96685) (xy 380.219118 -15.918215) (xy 380.253204 -15.874072) (xy 380.293353 -15.835363)
			(xy 380.338711 -15.802912) (xy 380.388311 -15.777411) (xy 380.441095 -15.759404) (xy 380.495938 -15.749274)
			(xy 380.551672 -15.747237) (xy 380.607109 -15.753337) (xy 380.661066 -15.767443) (xy 380.712395 -15.789255)
			(xy 380.760001 -15.818309) (xy 380.802869 -15.853984) (xy 380.821699 -15.875) (xy 406.551382 -15.875)
			(xy 406.555453 -15.819378) (xy 406.567579 -15.764941) (xy 406.587502 -15.71285) (xy 406.614798 -15.664215)
			(xy 406.648884 -15.620072) (xy 406.689033 -15.581363) (xy 406.734391 -15.548912) (xy 406.783991 -15.523411)
			(xy 406.836775 -15.505404) (xy 406.891618 -15.495274) (xy 406.947352 -15.493237) (xy 407.002789 -15.499337)
			(xy 407.056746 -15.513443) (xy 407.108075 -15.535255) (xy 407.155681 -15.564309) (xy 407.198549 -15.599984)
			(xy 407.235766 -15.641521) (xy 407.266539 -15.688034) (xy 407.290211 -15.738531) (xy 407.306279 -15.791938)
			(xy 407.314399 -15.847114) (xy 407.314908 -15.875) (xy 407.314411 -15.902251) (xy 407.568378 -15.902251)
			(xy 407.568378 -15.847749) (xy 407.576134 -15.793801) (xy 407.591489 -15.741506) (xy 407.614131 -15.691929)
			(xy 407.643597 -15.646079) (xy 407.679288 -15.604888) (xy 407.720479 -15.569197) (xy 407.766329 -15.539731)
			(xy 407.815906 -15.517089) (xy 407.868201 -15.501734) (xy 407.922149 -15.493978) (xy 407.9494 -15.493492)
			(xy 407.978319 -15.493975) (xy 408.035493 -15.502707) (xy 408.090694 -15.519969) (xy 408.142656 -15.545367)
			(xy 408.190189 -15.578319) (xy 408.232203 -15.618068) (xy 408.25039 -15.640558) (xy 408.257951 -15.649321)
			(xy 408.278711 -15.659501) (xy 408.290268 -15.660116) (xy 408.370532 -15.660116) (xy 408.382094 -15.659501)
			(xy 408.402865 -15.649337) (xy 408.41041 -15.640558) (xy 408.428585 -15.618061) (xy 408.470609 -15.578329)
			(xy 408.518148 -15.545392) (xy 408.570112 -15.520007) (xy 408.625312 -15.502753) (xy 408.682483 -15.494026)
			(xy 408.7114 -15.493492) (xy 408.738651 -15.493978) (xy 408.792599 -15.501734) (xy 408.844894 -15.517089)
			(xy 408.894471 -15.539731) (xy 408.940321 -15.569197) (xy 408.981512 -15.604888) (xy 409.017203 -15.646079)
			(xy 409.046669 -15.691929) (xy 409.069311 -15.741506) (xy 409.084666 -15.793801) (xy 409.092422 -15.847749)
			(xy 409.092422 -15.902251) (xy 409.084666 -15.956199) (xy 409.069311 -16.008494) (xy 409.046669 -16.058071)
			(xy 409.017203 -16.103921) (xy 408.981512 -16.145112) (xy 408.940321 -16.180803) (xy 408.894471 -16.210269)
			(xy 408.844894 -16.232911) (xy 408.792599 -16.248266) (xy 408.738651 -16.256022) (xy 408.7114 -16.256508)
			(xy 408.682481 -16.256025) (xy 408.625307 -16.247293) (xy 408.570106 -16.230031) (xy 408.518144 -16.204633)
			(xy 408.470611 -16.171681) (xy 408.428597 -16.131932) (xy 408.41041 -16.109442) (xy 408.402849 -16.100679)
			(xy 408.382089 -16.090499) (xy 408.370532 -16.089884) (xy 408.290268 -16.089884) (xy 408.278706 -16.090499)
			(xy 408.257935 -16.100663) (xy 408.25039 -16.109442) (xy 408.232215 -16.131939) (xy 408.190191 -16.171671)
			(xy 408.142652 -16.204608) (xy 408.090688 -16.229993) (xy 408.035488 -16.247247) (xy 407.978317 -16.255974)
			(xy 407.9494 -16.256508) (xy 407.922149 -16.256022) (xy 407.868201 -16.248266) (xy 407.815906 -16.232911)
			(xy 407.766329 -16.210269) (xy 407.720479 -16.180803) (xy 407.679288 -16.145112) (xy 407.643597 -16.103921)
			(xy 407.614131 -16.058071) (xy 407.591489 -16.008494) (xy 407.576134 -15.956199) (xy 407.568378 -15.902251)
			(xy 407.314411 -15.902251) (xy 407.314399 -15.902886) (xy 407.306279 -15.958062) (xy 407.290211 -16.011469)
			(xy 407.266539 -16.061966) (xy 407.235766 -16.108479) (xy 407.198549 -16.150016) (xy 407.155681 -16.185691)
			(xy 407.108075 -16.214745) (xy 407.056746 -16.236557) (xy 407.002789 -16.250663) (xy 406.947352 -16.256763)
			(xy 406.891618 -16.254726) (xy 406.836775 -16.244596) (xy 406.783991 -16.226589) (xy 406.734391 -16.201088)
			(xy 406.689033 -16.168637) (xy 406.648884 -16.129928) (xy 406.614798 -16.085785) (xy 406.587502 -16.03715)
			(xy 406.567579 -15.985059) (xy 406.555453 -15.930622) (xy 406.551382 -15.875) (xy 380.821699 -15.875)
			(xy 380.840086 -15.895521) (xy 380.870859 -15.942034) (xy 380.894531 -15.992531) (xy 380.910599 -16.045938)
			(xy 380.918719 -16.101114) (xy 380.919228 -16.129) (xy 380.918719 -16.156886) (xy 380.910599 -16.212062)
			(xy 380.894531 -16.265469) (xy 380.870859 -16.315966) (xy 380.840086 -16.362479) (xy 380.821699 -16.383)
			(xy 381.913382 -16.383) (xy 381.917453 -16.327378) (xy 381.929579 -16.272941) (xy 381.949502 -16.22085)
			(xy 381.976798 -16.172215) (xy 382.010884 -16.128072) (xy 382.051033 -16.089363) (xy 382.096391 -16.056912)
			(xy 382.145991 -16.031411) (xy 382.198775 -16.013404) (xy 382.253618 -16.003274) (xy 382.309352 -16.001237)
			(xy 382.364789 -16.007337) (xy 382.418746 -16.021443) (xy 382.470075 -16.043255) (xy 382.517681 -16.072309)
			(xy 382.560549 -16.107984) (xy 382.597766 -16.149521) (xy 382.628539 -16.196034) (xy 382.652211 -16.246531)
			(xy 382.668279 -16.299938) (xy 382.676399 -16.355114) (xy 382.676908 -16.383) (xy 382.676399 -16.410886)
			(xy 382.668279 -16.466062) (xy 382.652211 -16.519469) (xy 382.628539 -16.569966) (xy 382.597766 -16.616479)
			(xy 382.560549 -16.658016) (xy 382.517681 -16.693691) (xy 382.470075 -16.722745) (xy 382.418746 -16.744557)
			(xy 382.364789 -16.758663) (xy 382.309352 -16.764763) (xy 382.253618 -16.762726) (xy 382.198775 -16.752596)
			(xy 382.145991 -16.734589) (xy 382.096391 -16.709088) (xy 382.051033 -16.676637) (xy 382.010884 -16.637928)
			(xy 381.976798 -16.593785) (xy 381.949502 -16.54515) (xy 381.929579 -16.493059) (xy 381.917453 -16.438622)
			(xy 381.913382 -16.383) (xy 380.821699 -16.383) (xy 380.802869 -16.404016) (xy 380.760001 -16.439691)
			(xy 380.712395 -16.468745) (xy 380.661066 -16.490557) (xy 380.607109 -16.504663) (xy 380.551672 -16.510763)
			(xy 380.495938 -16.508726) (xy 380.441095 -16.498596) (xy 380.388311 -16.480589) (xy 380.338711 -16.455088)
			(xy 380.293353 -16.422637) (xy 380.253204 -16.383928) (xy 380.219118 -16.339785) (xy 380.191822 -16.29115)
			(xy 380.171899 -16.239059) (xy 380.159773 -16.184622) (xy 380.155702 -16.129) (xy 374.135904 -16.129)
			(xy 374.135904 -16.891) (xy 378.135894 -16.891) (xy 378.139965 -16.835378) (xy 378.152091 -16.780941)
			(xy 378.172014 -16.72885) (xy 378.19931 -16.680215) (xy 378.233396 -16.636072) (xy 378.273545 -16.597363)
			(xy 378.318903 -16.564912) (xy 378.368503 -16.539411) (xy 378.421287 -16.521404) (xy 378.47613 -16.511274)
			(xy 378.531864 -16.509237) (xy 378.587301 -16.515337) (xy 378.641258 -16.529443) (xy 378.692587 -16.551255)
			(xy 378.740193 -16.580309) (xy 378.783061 -16.615984) (xy 378.820278 -16.657521) (xy 378.851051 -16.704034)
			(xy 378.874723 -16.754531) (xy 378.890791 -16.807938) (xy 378.898911 -16.863114) (xy 378.89942 -16.891)
			(xy 379.278894 -16.891) (xy 379.282965 -16.835378) (xy 379.295091 -16.780941) (xy 379.315014 -16.72885)
			(xy 379.34231 -16.680215) (xy 379.376396 -16.636072) (xy 379.416545 -16.597363) (xy 379.461903 -16.564912)
			(xy 379.511503 -16.539411) (xy 379.564287 -16.521404) (xy 379.61913 -16.511274) (xy 379.674864 -16.509237)
			(xy 379.730301 -16.515337) (xy 379.784258 -16.529443) (xy 379.835587 -16.551255) (xy 379.883193 -16.580309)
			(xy 379.926061 -16.615984) (xy 379.963278 -16.657521) (xy 379.994051 -16.704034) (xy 380.017723 -16.754531)
			(xy 380.033791 -16.807938) (xy 380.041911 -16.863114) (xy 380.04242 -16.891) (xy 380.041911 -16.918886)
			(xy 380.033791 -16.974062) (xy 380.017723 -17.027469) (xy 380.00231 -17.060348) (xy 397.255996 -17.060348)
			(xy 397.255996 -16.975652) (xy 397.264047 -16.891338) (xy 397.280076 -16.808172) (xy 397.303937 -16.726905)
			(xy 397.335416 -16.648275) (xy 397.374227 -16.572994) (xy 397.420017 -16.501742) (xy 397.472373 -16.435166)
			(xy 397.530821 -16.373868) (xy 397.594831 -16.318403) (xy 397.663823 -16.269274) (xy 397.737173 -16.226925)
			(xy 397.814216 -16.191741) (xy 397.894255 -16.164039) (xy 397.976564 -16.144071) (xy 398.060399 -16.132018)
			(xy 398.145 -16.127988) (xy 398.229601 -16.132018) (xy 398.313436 -16.144071) (xy 398.395745 -16.164039)
			(xy 398.475784 -16.191741) (xy 398.552827 -16.226925) (xy 398.626177 -16.269274) (xy 398.695169 -16.318403)
			(xy 398.759179 -16.373868) (xy 398.817627 -16.435166) (xy 398.869983 -16.501742) (xy 398.915773 -16.572994)
			(xy 398.954584 -16.648275) (xy 398.986063 -16.726905) (xy 398.996955 -16.764) (xy 406.551382 -16.764)
			(xy 406.555453 -16.708378) (xy 406.567579 -16.653941) (xy 406.587502 -16.60185) (xy 406.614798 -16.553215)
			(xy 406.648884 -16.509072) (xy 406.689033 -16.470363) (xy 406.734391 -16.437912) (xy 406.783991 -16.412411)
			(xy 406.836775 -16.394404) (xy 406.891618 -16.384274) (xy 406.947352 -16.382237) (xy 407.002789 -16.388337)
			(xy 407.056746 -16.402443) (xy 407.108075 -16.424255) (xy 407.155681 -16.453309) (xy 407.198549 -16.488984)
			(xy 407.235766 -16.530521) (xy 407.266539 -16.577034) (xy 407.290211 -16.627531) (xy 407.306279 -16.680938)
			(xy 407.314399 -16.736114) (xy 407.314908 -16.764) (xy 407.314411 -16.791251) (xy 407.568378 -16.791251)
			(xy 407.568378 -16.736749) (xy 407.576134 -16.682801) (xy 407.591489 -16.630506) (xy 407.614131 -16.580929)
			(xy 407.643597 -16.535079) (xy 407.679288 -16.493888) (xy 407.720479 -16.458197) (xy 407.766329 -16.428731)
			(xy 407.815906 -16.406089) (xy 407.868201 -16.390734) (xy 407.922149 -16.382978) (xy 407.9494 -16.382492)
			(xy 407.978319 -16.382975) (xy 408.035493 -16.391707) (xy 408.090694 -16.408969) (xy 408.142656 -16.434367)
			(xy 408.190189 -16.467319) (xy 408.232203 -16.507068) (xy 408.25039 -16.529558) (xy 408.257951 -16.538321)
			(xy 408.278711 -16.548501) (xy 408.290268 -16.549116) (xy 408.370532 -16.549116) (xy 408.382094 -16.548501)
			(xy 408.402865 -16.538337) (xy 408.41041 -16.529558) (xy 408.428585 -16.507061) (xy 408.470609 -16.467329)
			(xy 408.518148 -16.434392) (xy 408.570112 -16.409007) (xy 408.625312 -16.391753) (xy 408.682483 -16.383026)
			(xy 408.7114 -16.382492) (xy 408.738651 -16.382978) (xy 408.792599 -16.390734) (xy 408.844894 -16.406089)
			(xy 408.894471 -16.428731) (xy 408.940321 -16.458197) (xy 408.981512 -16.493888) (xy 409.017203 -16.535079)
			(xy 409.046669 -16.580929) (xy 409.069311 -16.630506) (xy 409.084666 -16.682801) (xy 409.092422 -16.736749)
			(xy 409.092422 -16.791251) (xy 409.084666 -16.845199) (xy 409.069311 -16.897494) (xy 409.046669 -16.947071)
			(xy 409.017203 -16.992921) (xy 408.981512 -17.034112) (xy 408.940321 -17.069803) (xy 408.894471 -17.099269)
			(xy 408.844894 -17.121911) (xy 408.792599 -17.137266) (xy 408.738651 -17.145022) (xy 408.7114 -17.145508)
			(xy 408.682481 -17.145025) (xy 408.625307 -17.136293) (xy 408.570106 -17.119031) (xy 408.518144 -17.093633)
			(xy 408.470611 -17.060681) (xy 408.428597 -17.020932) (xy 408.41041 -16.998442) (xy 408.402849 -16.989679)
			(xy 408.382089 -16.979499) (xy 408.370532 -16.978884) (xy 408.290268 -16.978884) (xy 408.278706 -16.979499)
			(xy 408.257935 -16.989663) (xy 408.25039 -16.998442) (xy 408.232215 -17.020939) (xy 408.190191 -17.060671)
			(xy 408.142652 -17.093608) (xy 408.090688 -17.118993) (xy 408.035488 -17.136247) (xy 407.978317 -17.144974)
			(xy 407.9494 -17.145508) (xy 407.922149 -17.145022) (xy 407.868201 -17.137266) (xy 407.815906 -17.121911)
			(xy 407.766329 -17.099269) (xy 407.720479 -17.069803) (xy 407.679288 -17.034112) (xy 407.643597 -16.992921)
			(xy 407.614131 -16.947071) (xy 407.591489 -16.897494) (xy 407.576134 -16.845199) (xy 407.568378 -16.791251)
			(xy 407.314411 -16.791251) (xy 407.314399 -16.791886) (xy 407.306279 -16.847062) (xy 407.290211 -16.900469)
			(xy 407.266539 -16.950966) (xy 407.235766 -16.997479) (xy 407.198549 -17.039016) (xy 407.155681 -17.074691)
			(xy 407.108075 -17.103745) (xy 407.056746 -17.125557) (xy 407.002789 -17.139663) (xy 406.947352 -17.145763)
			(xy 406.891618 -17.143726) (xy 406.836775 -17.133596) (xy 406.783991 -17.115589) (xy 406.734391 -17.090088)
			(xy 406.689033 -17.057637) (xy 406.648884 -17.018928) (xy 406.614798 -16.974785) (xy 406.587502 -16.92615)
			(xy 406.567579 -16.874059) (xy 406.555453 -16.819622) (xy 406.551382 -16.764) (xy 398.996955 -16.764)
			(xy 399.009924 -16.808172) (xy 399.025953 -16.891338) (xy 399.034004 -16.975652) (xy 399.034508 -17.018)
			(xy 399.034004 -17.060348) (xy 399.025953 -17.144662) (xy 399.009924 -17.227828) (xy 398.986063 -17.309095)
			(xy 398.954584 -17.387725) (xy 398.915773 -17.463006) (xy 398.869983 -17.534258) (xy 398.817627 -17.600834)
			(xy 398.767886 -17.653) (xy 406.551382 -17.653) (xy 406.555453 -17.597378) (xy 406.567579 -17.542941)
			(xy 406.587502 -17.49085) (xy 406.614798 -17.442215) (xy 406.648884 -17.398072) (xy 406.689033 -17.359363)
			(xy 406.734391 -17.326912) (xy 406.783991 -17.301411) (xy 406.836775 -17.283404) (xy 406.891618 -17.273274)
			(xy 406.947352 -17.271237) (xy 407.002789 -17.277337) (xy 407.056746 -17.291443) (xy 407.108075 -17.313255)
			(xy 407.155681 -17.342309) (xy 407.198549 -17.377984) (xy 407.235766 -17.419521) (xy 407.266539 -17.466034)
			(xy 407.290211 -17.516531) (xy 407.306279 -17.569938) (xy 407.314399 -17.625114) (xy 407.314908 -17.653)
			(xy 407.314411 -17.680251) (xy 407.568378 -17.680251) (xy 407.568378 -17.625749) (xy 407.576134 -17.571801)
			(xy 407.591489 -17.519506) (xy 407.614131 -17.469929) (xy 407.643597 -17.424079) (xy 407.679288 -17.382888)
			(xy 407.720479 -17.347197) (xy 407.766329 -17.317731) (xy 407.815906 -17.295089) (xy 407.868201 -17.279734)
			(xy 407.922149 -17.271978) (xy 407.9494 -17.271492) (xy 407.978319 -17.271975) (xy 408.035493 -17.280707)
			(xy 408.090694 -17.297969) (xy 408.142656 -17.323367) (xy 408.190189 -17.356319) (xy 408.232203 -17.396068)
			(xy 408.25039 -17.418558) (xy 408.257951 -17.427321) (xy 408.278711 -17.437501) (xy 408.290268 -17.438116)
			(xy 408.370532 -17.438116) (xy 408.382094 -17.437501) (xy 408.402865 -17.427337) (xy 408.41041 -17.418558)
			(xy 408.428585 -17.396061) (xy 408.470609 -17.356329) (xy 408.518148 -17.323392) (xy 408.570112 -17.298007)
			(xy 408.625312 -17.280753) (xy 408.682483 -17.272026) (xy 408.7114 -17.271492) (xy 408.738651 -17.271978)
			(xy 408.792599 -17.279734) (xy 408.844894 -17.295089) (xy 408.894471 -17.317731) (xy 408.940321 -17.347197)
			(xy 408.981512 -17.382888) (xy 409.017203 -17.424079) (xy 409.046669 -17.469929) (xy 409.069311 -17.519506)
			(xy 409.084666 -17.571801) (xy 409.092422 -17.625749) (xy 409.092422 -17.680251) (xy 409.084666 -17.734199)
			(xy 409.069311 -17.786494) (xy 409.046669 -17.836071) (xy 409.017203 -17.881921) (xy 408.981512 -17.923112)
			(xy 408.940321 -17.958803) (xy 408.894471 -17.988269) (xy 408.844894 -18.010911) (xy 408.792599 -18.026266)
			(xy 408.738651 -18.034022) (xy 408.7114 -18.034508) (xy 408.682481 -18.034025) (xy 408.625307 -18.025293)
			(xy 408.570106 -18.008031) (xy 408.518144 -17.982633) (xy 408.470611 -17.949681) (xy 408.428597 -17.909932)
			(xy 408.41041 -17.887442) (xy 408.402849 -17.878679) (xy 408.382089 -17.868499) (xy 408.370532 -17.867884)
			(xy 408.290268 -17.867884) (xy 408.278706 -17.868499) (xy 408.257935 -17.878663) (xy 408.25039 -17.887442)
			(xy 408.232215 -17.909939) (xy 408.190191 -17.949671) (xy 408.142652 -17.982608) (xy 408.090688 -18.007993)
			(xy 408.035488 -18.025247) (xy 407.978317 -18.033974) (xy 407.9494 -18.034508) (xy 407.922149 -18.034022)
			(xy 407.868201 -18.026266) (xy 407.815906 -18.010911) (xy 407.766329 -17.988269) (xy 407.720479 -17.958803)
			(xy 407.679288 -17.923112) (xy 407.643597 -17.881921) (xy 407.614131 -17.836071) (xy 407.591489 -17.786494)
			(xy 407.576134 -17.734199) (xy 407.568378 -17.680251) (xy 407.314411 -17.680251) (xy 407.314399 -17.680886)
			(xy 407.306279 -17.736062) (xy 407.290211 -17.789469) (xy 407.266539 -17.839966) (xy 407.235766 -17.886479)
			(xy 407.198549 -17.928016) (xy 407.155681 -17.963691) (xy 407.108075 -17.992745) (xy 407.056746 -18.014557)
			(xy 407.002789 -18.028663) (xy 406.947352 -18.034763) (xy 406.891618 -18.032726) (xy 406.836775 -18.022596)
			(xy 406.783991 -18.004589) (xy 406.734391 -17.979088) (xy 406.689033 -17.946637) (xy 406.648884 -17.907928)
			(xy 406.614798 -17.863785) (xy 406.587502 -17.81515) (xy 406.567579 -17.763059) (xy 406.555453 -17.708622)
			(xy 406.551382 -17.653) (xy 398.767886 -17.653) (xy 398.759179 -17.662132) (xy 398.695169 -17.717597)
			(xy 398.626177 -17.766726) (xy 398.552827 -17.809075) (xy 398.475784 -17.844259) (xy 398.395745 -17.871961)
			(xy 398.313436 -17.891929) (xy 398.229601 -17.903982) (xy 398.145 -17.908013) (xy 398.060399 -17.903982)
			(xy 397.976564 -17.891929) (xy 397.894255 -17.871961) (xy 397.814216 -17.844259) (xy 397.737173 -17.809075)
			(xy 397.663823 -17.766726) (xy 397.594831 -17.717597) (xy 397.530821 -17.662132) (xy 397.472373 -17.600834)
			(xy 397.420017 -17.534258) (xy 397.374227 -17.463006) (xy 397.335416 -17.387725) (xy 397.303937 -17.309095)
			(xy 397.280076 -17.227828) (xy 397.264047 -17.144662) (xy 397.255996 -17.060348) (xy 380.00231 -17.060348)
			(xy 379.994051 -17.077966) (xy 379.963278 -17.124479) (xy 379.926061 -17.166016) (xy 379.883193 -17.201691)
			(xy 379.835587 -17.230745) (xy 379.784258 -17.252557) (xy 379.730301 -17.266663) (xy 379.674864 -17.272763)
			(xy 379.61913 -17.270726) (xy 379.564287 -17.260596) (xy 379.511503 -17.242589) (xy 379.461903 -17.217088)
			(xy 379.416545 -17.184637) (xy 379.376396 -17.145928) (xy 379.34231 -17.101785) (xy 379.315014 -17.05315)
			(xy 379.295091 -17.001059) (xy 379.282965 -16.946622) (xy 379.278894 -16.891) (xy 378.89942 -16.891)
			(xy 378.898911 -16.918886) (xy 378.890791 -16.974062) (xy 378.874723 -17.027469) (xy 378.851051 -17.077966)
			(xy 378.820278 -17.124479) (xy 378.783061 -17.166016) (xy 378.740193 -17.201691) (xy 378.692587 -17.230745)
			(xy 378.641258 -17.252557) (xy 378.587301 -17.266663) (xy 378.531864 -17.272763) (xy 378.47613 -17.270726)
			(xy 378.421287 -17.260596) (xy 378.368503 -17.242589) (xy 378.318903 -17.217088) (xy 378.273545 -17.184637)
			(xy 378.233396 -17.145928) (xy 378.19931 -17.101785) (xy 378.172014 -17.05315) (xy 378.152091 -17.001059)
			(xy 378.139965 -16.946622) (xy 378.135894 -16.891) (xy 374.135904 -16.891) (xy 374.135904 -18.50009)
			(xy 374.135409 -18.600931) (xy 374.127491 -18.802458) (xy 374.118004 -18.923) (xy 380.421894 -18.923)
			(xy 380.425965 -18.867378) (xy 380.438091 -18.812941) (xy 380.458014 -18.76085) (xy 380.48531 -18.712215)
			(xy 380.519396 -18.668072) (xy 380.559545 -18.629363) (xy 380.604903 -18.596912) (xy 380.654503 -18.571411)
			(xy 380.707287 -18.553404) (xy 380.76213 -18.543274) (xy 380.817864 -18.541237) (xy 380.873301 -18.547337)
			(xy 380.927258 -18.561443) (xy 380.978587 -18.583255) (xy 381.026193 -18.612309) (xy 381.069061 -18.647984)
			(xy 381.106278 -18.689521) (xy 381.137051 -18.736034) (xy 381.160723 -18.786531) (xy 381.176791 -18.839938)
			(xy 381.184911 -18.895114) (xy 381.185313 -18.917158) (xy 381.564894 -18.917158) (xy 381.568965 -18.861536)
			(xy 381.581091 -18.807099) (xy 381.601014 -18.755008) (xy 381.62831 -18.706373) (xy 381.662396 -18.66223)
			(xy 381.702545 -18.623521) (xy 381.747903 -18.59107) (xy 381.797503 -18.565569) (xy 381.850287 -18.547562)
			(xy 381.90513 -18.537432) (xy 381.960864 -18.535395) (xy 382.016301 -18.541495) (xy 382.070258 -18.555601)
			(xy 382.121587 -18.577413) (xy 382.169193 -18.606467) (xy 382.212061 -18.642142) (xy 382.249278 -18.683679)
			(xy 382.280051 -18.730192) (xy 382.303723 -18.780689) (xy 382.319791 -18.834096) (xy 382.327911 -18.889272)
			(xy 382.32842 -18.917158) (xy 382.327911 -18.945044) (xy 382.319791 -19.00022) (xy 382.303723 -19.053627)
			(xy 382.280051 -19.104124) (xy 382.249278 -19.150637) (xy 382.212061 -19.192174) (xy 382.169193 -19.227849)
			(xy 382.121587 -19.256903) (xy 382.070258 -19.278715) (xy 382.016301 -19.292821) (xy 381.960864 -19.298921)
			(xy 381.90513 -19.296884) (xy 381.850287 -19.286754) (xy 381.797503 -19.268747) (xy 381.747903 -19.243246)
			(xy 381.702545 -19.210795) (xy 381.662396 -19.172086) (xy 381.62831 -19.127943) (xy 381.601014 -19.079308)
			(xy 381.581091 -19.027217) (xy 381.568965 -18.97278) (xy 381.564894 -18.917158) (xy 381.185313 -18.917158)
			(xy 381.18542 -18.923) (xy 381.184911 -18.950886) (xy 381.176791 -19.006062) (xy 381.160723 -19.059469)
			(xy 381.137051 -19.109966) (xy 381.106278 -19.156479) (xy 381.069061 -19.198016) (xy 381.026193 -19.233691)
			(xy 380.978587 -19.262745) (xy 380.927258 -19.284557) (xy 380.873301 -19.298663) (xy 380.817864 -19.304763)
			(xy 380.76213 -19.302726) (xy 380.707287 -19.292596) (xy 380.654503 -19.274589) (xy 380.604903 -19.249088)
			(xy 380.559545 -19.216637) (xy 380.519396 -19.177928) (xy 380.48531 -19.133785) (xy 380.458014 -19.08515)
			(xy 380.438091 -19.033059) (xy 380.425965 -18.978622) (xy 380.421894 -18.923) (xy 374.118004 -18.923)
			(xy 374.111667 -19.003518) (xy 374.087962 -19.203802) (xy 374.056412 -19.403001) (xy 374.017066 -19.600808)
			(xy 373.969984 -19.796917) (xy 373.915239 -19.991027) (xy 373.911164 -20.00357) (xy 386.295635 -20.00357)
			(xy 386.295635 -19.87443) (xy 386.303585 -19.745535) (xy 386.319455 -19.617375) (xy 386.343184 -19.490434)
			(xy 386.374683 -19.365195) (xy 386.413832 -19.242132) (xy 386.460483 -19.121713) (xy 386.514458 -19.004394)
			(xy 386.575553 -18.89062) (xy 386.643536 -18.780823) (xy 386.71815 -18.67542) (xy 386.799111 -18.57481)
			(xy 386.886111 -18.479375) (xy 386.978822 -18.389476) (xy 387.076892 -18.305455) (xy 387.179947 -18.227631)
			(xy 387.287598 -18.156299) (xy 387.399437 -18.091729) (xy 387.515038 -18.034167) (xy 387.633963 -17.98383)
			(xy 387.755762 -17.94091) (xy 387.879972 -17.905569) (xy 388.006121 -17.877942) (xy 388.133733 -17.858133)
			(xy 388.262322 -17.846217) (xy 388.3914 -17.842241) (xy 388.520478 -17.846217) (xy 388.649067 -17.858133)
			(xy 388.776679 -17.877942) (xy 388.902828 -17.905569) (xy 389.027038 -17.94091) (xy 389.148837 -17.98383)
			(xy 389.267762 -18.034167) (xy 389.383363 -18.091729) (xy 389.495202 -18.156299) (xy 389.602853 -18.227631)
			(xy 389.705908 -18.305455) (xy 389.803978 -18.389476) (xy 389.896689 -18.479375) (xy 389.983689 -18.57481)
			(xy 390.06465 -18.67542) (xy 390.139264 -18.780823) (xy 390.207247 -18.89062) (xy 390.268342 -19.004394)
			(xy 390.322317 -19.121713) (xy 390.368968 -19.242132) (xy 390.408117 -19.365195) (xy 390.439616 -19.490434)
			(xy 390.463345 -19.617375) (xy 390.479215 -19.745535) (xy 390.487165 -19.87443) (xy 390.487662 -19.939)
			(xy 390.487165 -20.00357) (xy 390.479215 -20.132465) (xy 390.463345 -20.260625) (xy 390.439616 -20.387566)
			(xy 390.408117 -20.512805) (xy 390.368968 -20.635868) (xy 390.322317 -20.756287) (xy 390.289324 -20.828)
			(xy 406.551382 -20.828) (xy 406.555453 -20.772378) (xy 406.567579 -20.717941) (xy 406.587502 -20.66585)
			(xy 406.614798 -20.617215) (xy 406.648884 -20.573072) (xy 406.689033 -20.534363) (xy 406.734391 -20.501912)
			(xy 406.783991 -20.476411) (xy 406.836775 -20.458404) (xy 406.891618 -20.448274) (xy 406.947352 -20.446237)
			(xy 407.002789 -20.452337) (xy 407.056746 -20.466443) (xy 407.108075 -20.488255) (xy 407.155681 -20.517309)
			(xy 407.198549 -20.552984) (xy 407.235766 -20.594521) (xy 407.266539 -20.641034) (xy 407.290211 -20.691531)
			(xy 407.306279 -20.744938) (xy 407.314399 -20.800114) (xy 407.314908 -20.828) (xy 407.314411 -20.855251)
			(xy 407.568378 -20.855251) (xy 407.568378 -20.800749) (xy 407.576134 -20.746801) (xy 407.591489 -20.694506)
			(xy 407.614131 -20.644929) (xy 407.643597 -20.599079) (xy 407.679288 -20.557888) (xy 407.720479 -20.522197)
			(xy 407.766329 -20.492731) (xy 407.815906 -20.470089) (xy 407.868201 -20.454734) (xy 407.922149 -20.446978)
			(xy 407.9494 -20.446492) (xy 407.978319 -20.446975) (xy 408.035493 -20.455707) (xy 408.090694 -20.472969)
			(xy 408.142656 -20.498367) (xy 408.190189 -20.531319) (xy 408.232203 -20.571068) (xy 408.25039 -20.593558)
			(xy 408.257951 -20.602321) (xy 408.278711 -20.612501) (xy 408.290268 -20.613116) (xy 408.370532 -20.613116)
			(xy 408.382094 -20.612501) (xy 408.402865 -20.602337) (xy 408.41041 -20.593558) (xy 408.428585 -20.571061)
			(xy 408.470609 -20.531329) (xy 408.518148 -20.498392) (xy 408.570112 -20.473007) (xy 408.625312 -20.455753)
			(xy 408.682483 -20.447026) (xy 408.7114 -20.446492) (xy 408.738651 -20.446978) (xy 408.792599 -20.454734)
			(xy 408.844894 -20.470089) (xy 408.894471 -20.492731) (xy 408.940321 -20.522197) (xy 408.981512 -20.557888)
			(xy 409.017203 -20.599079) (xy 409.046669 -20.644929) (xy 409.069311 -20.694506) (xy 409.084666 -20.746801)
			(xy 409.092422 -20.800749) (xy 409.092422 -20.855251) (xy 409.084666 -20.909199) (xy 409.069311 -20.961494)
			(xy 409.046669 -21.011071) (xy 409.037487 -21.025358) (xy 410.0322 -21.025358) (xy 410.0322 -20.986242)
			(xy 410.034074 -20.959018) (xy 410.044596 -20.905475) (xy 410.062642 -20.853978) (xy 410.087844 -20.805579)
			(xy 410.119686 -20.761265) (xy 410.157519 -20.721942) (xy 410.178758 -20.70481) (xy 410.187521 -20.697249)
			(xy 410.197701 -20.676489) (xy 410.198316 -20.664932) (xy 410.198316 -20.584668) (xy 410.197701 -20.573106)
			(xy 410.187537 -20.552335) (xy 410.178758 -20.54479) (xy 410.15751 -20.527668) (xy 410.119684 -20.488338)
			(xy 410.087845 -20.444021) (xy 410.062644 -20.395621) (xy 410.044593 -20.344125) (xy 410.034063 -20.290582)
			(xy 410.0322 -20.263358) (xy 410.0322 -20.224242) (xy 410.034074 -20.197018) (xy 410.044596 -20.143475)
			(xy 410.062642 -20.091978) (xy 410.087844 -20.043579) (xy 410.119686 -19.999265) (xy 410.157519 -19.959942)
			(xy 410.178758 -19.94281) (xy 410.187521 -19.935249) (xy 410.197701 -19.914489) (xy 410.198316 -19.902932)
			(xy 410.198316 -19.822668) (xy 410.197701 -19.811106) (xy 410.187537 -19.790335) (xy 410.178758 -19.78279)
			(xy 410.15751 -19.765668) (xy 410.119684 -19.726338) (xy 410.087845 -19.682021) (xy 410.062644 -19.633621)
			(xy 410.044593 -19.582125) (xy 410.034063 -19.528582) (xy 410.0322 -19.501358) (xy 410.0322 -19.462242)
			(xy 410.03422 -19.433308) (xy 410.045927 -19.376501) (xy 410.066098 -19.322122) (xy 410.094267 -19.271422)
			(xy 410.129786 -19.22557) (xy 410.171837 -19.185623) (xy 410.219449 -19.152501) (xy 410.271526 -19.126968)
			(xy 410.326868 -19.109612) (xy 410.3842 -19.100833) (xy 410.4132 -19.100292) (xy 410.442119 -19.100775)
			(xy 410.499293 -19.109507) (xy 410.554494 -19.126769) (xy 410.606456 -19.152167) (xy 410.653989 -19.185119)
			(xy 410.696003 -19.224868) (xy 410.71419 -19.247358) (xy 410.721751 -19.256121) (xy 410.742511 -19.266301)
			(xy 410.754068 -19.266916) (xy 410.834332 -19.266916) (xy 410.845894 -19.266301) (xy 410.866665 -19.256137)
			(xy 410.87421 -19.247358) (xy 410.892385 -19.224861) (xy 410.934409 -19.185129) (xy 410.981948 -19.152192)
			(xy 411.033912 -19.126807) (xy 411.089112 -19.109553) (xy 411.146283 -19.100826) (xy 411.1752 -19.100292)
			(xy 411.202451 -19.100778) (xy 411.256399 -19.108534) (xy 411.308694 -19.123889) (xy 411.358271 -19.146531)
			(xy 411.404121 -19.175997) (xy 411.445312 -19.211688) (xy 411.481003 -19.252879) (xy 411.510469 -19.298729)
			(xy 411.533111 -19.348306) (xy 411.548466 -19.400601) (xy 411.556222 -19.454549) (xy 411.556708 -19.4818)
			(xy 411.556225 -19.510719) (xy 411.547493 -19.567893) (xy 411.530231 -19.623094) (xy 411.504833 -19.675056)
			(xy 411.471881 -19.722589) (xy 411.432132 -19.764603) (xy 411.409642 -19.78279) (xy 411.400879 -19.790351)
			(xy 411.390699 -19.811111) (xy 411.390084 -19.822668) (xy 411.390084 -19.902932) (xy 411.390699 -19.914494)
			(xy 411.400863 -19.935265) (xy 411.409642 -19.94281) (xy 411.430425 -19.959563) (xy 411.467555 -19.997917)
			(xy 411.498977 -20.041071) (xy 411.524076 -20.088185) (xy 411.542362 -20.138337) (xy 411.553478 -20.190549)
			(xy 411.557208 -20.2438) (xy 411.553478 -20.297051) (xy 411.542362 -20.349263) (xy 411.524076 -20.399415)
			(xy 411.498977 -20.446529) (xy 411.467555 -20.489683) (xy 411.430425 -20.528037) (xy 411.409642 -20.54479)
			(xy 411.400879 -20.552351) (xy 411.390699 -20.573111) (xy 411.390084 -20.584668) (xy 411.390084 -20.664932)
			(xy 411.390699 -20.676494) (xy 411.400863 -20.697265) (xy 411.409642 -20.70481) (xy 411.432139 -20.722985)
			(xy 411.471871 -20.765009) (xy 411.504808 -20.812548) (xy 411.530193 -20.864512) (xy 411.547447 -20.919712)
			(xy 411.556174 -20.976883) (xy 411.556708 -21.0058) (xy 411.556222 -21.033051) (xy 411.548466 -21.086999)
			(xy 411.535018 -21.1328) (xy 417.651692 -21.1328) (xy 417.651692 -21.132292) (xy 417.652298 -21.08596)
			(xy 417.661969 -20.993802) (xy 417.681165 -20.903148) (xy 417.709677 -20.814979) (xy 417.727892 -20.772374)
			(xy 417.731698 -20.762432) (xy 417.731698 -20.741168) (xy 417.727892 -20.731226) (xy 417.709659 -20.688593)
			(xy 417.681128 -20.600364) (xy 417.661935 -20.509643) (xy 417.652288 -20.417418) (xy 417.651692 -20.371054)
			(xy 417.651692 -20.370546) (xy 417.652286 -20.324182) (xy 417.661945 -20.231959) (xy 417.68114 -20.14124)
			(xy 417.709666 -20.053009) (xy 417.727892 -20.010374) (xy 417.731698 -20.000432) (xy 417.731698 -19.979168)
			(xy 417.727892 -19.969226) (xy 417.70967 -19.926623) (xy 417.681152 -19.838456) (xy 417.66196 -19.7478)
			(xy 417.6523 -19.65564) (xy 417.651692 -19.609308) (xy 417.651692 -19.6088) (xy 417.652196 -19.566452)
			(xy 417.660247 -19.482138) (xy 417.676276 -19.398972) (xy 417.700137 -19.317705) (xy 417.731616 -19.239075)
			(xy 417.770427 -19.163794) (xy 417.816217 -19.092542) (xy 417.868573 -19.025966) (xy 417.927021 -18.964668)
			(xy 417.991031 -18.909203) (xy 418.060023 -18.860074) (xy 418.133373 -18.817725) (xy 418.210416 -18.782541)
			(xy 418.290455 -18.754839) (xy 418.372764 -18.734871) (xy 418.456599 -18.722818) (xy 418.5412 -18.718788)
			(xy 418.625801 -18.722818) (xy 418.709636 -18.734871) (xy 418.791945 -18.754839) (xy 418.871984 -18.782541)
			(xy 418.949027 -18.817725) (xy 419.022377 -18.860074) (xy 419.091369 -18.909203) (xy 419.155379 -18.964668)
			(xy 419.213827 -19.025966) (xy 419.266183 -19.092542) (xy 419.311973 -19.163794) (xy 419.350784 -19.239075)
			(xy 419.382263 -19.317705) (xy 419.406124 -19.398972) (xy 419.415724 -19.44878) (xy 429.385728 -19.44878)
			(xy 429.389801 -19.393121) (xy 429.401936 -19.338648) (xy 429.421872 -19.286522) (xy 429.449186 -19.237854)
			(xy 429.483294 -19.193682) (xy 429.523471 -19.154947) (xy 429.568859 -19.122475) (xy 429.618491 -19.096957)
			(xy 429.671311 -19.078938) (xy 429.72619 -19.068801) (xy 429.781961 -19.066763) (xy 429.837435 -19.072866)
			(xy 429.891428 -19.086982) (xy 429.942791 -19.108809) (xy 429.990429 -19.137882) (xy 430.033325 -19.173581)
			(xy 430.070567 -19.215145) (xy 430.101361 -19.261689) (xy 430.125049 -19.31222) (xy 430.141127 -19.365662)
			(xy 430.149253 -19.420876) (xy 430.149438 -19.431) (xy 430.274728 -19.431) (xy 430.278801 -19.375341)
			(xy 430.290936 -19.320868) (xy 430.310872 -19.268742) (xy 430.338186 -19.220074) (xy 430.372294 -19.175902)
			(xy 430.412471 -19.137167) (xy 430.457859 -19.104695) (xy 430.507491 -19.079177) (xy 430.560311 -19.061158)
			(xy 430.61519 -19.051021) (xy 430.670961 -19.048983) (xy 430.726435 -19.055086) (xy 430.780428 -19.069202)
			(xy 430.831791 -19.091029) (xy 430.879429 -19.120102) (xy 430.922325 -19.155801) (xy 430.959567 -19.197365)
			(xy 430.990361 -19.243909) (xy 431.014049 -19.29444) (xy 431.030127 -19.347882) (xy 431.038253 -19.403096)
			(xy 431.038762 -19.431) (xy 431.038253 -19.458904) (xy 431.030127 -19.514118) (xy 431.014049 -19.56756)
			(xy 430.990361 -19.618091) (xy 430.959567 -19.664635) (xy 430.922325 -19.706199) (xy 430.879429 -19.741898)
			(xy 430.831791 -19.770971) (xy 430.780428 -19.792798) (xy 430.726435 -19.806914) (xy 430.670961 -19.813017)
			(xy 430.61519 -19.810979) (xy 430.560311 -19.800842) (xy 430.507491 -19.782823) (xy 430.457859 -19.757305)
			(xy 430.412471 -19.724833) (xy 430.372294 -19.686098) (xy 430.338186 -19.641926) (xy 430.310872 -19.593258)
			(xy 430.290936 -19.541132) (xy 430.278801 -19.486659) (xy 430.274728 -19.431) (xy 430.149438 -19.431)
			(xy 430.149762 -19.44878) (xy 430.149253 -19.476684) (xy 430.141127 -19.531898) (xy 430.125049 -19.58534)
			(xy 430.101361 -19.635871) (xy 430.070567 -19.682415) (xy 430.033325 -19.723979) (xy 429.990429 -19.759678)
			(xy 429.942791 -19.788751) (xy 429.891428 -19.810578) (xy 429.837435 -19.824694) (xy 429.781961 -19.830797)
			(xy 429.72619 -19.828759) (xy 429.671311 -19.818622) (xy 429.618491 -19.800603) (xy 429.568859 -19.775085)
			(xy 429.523471 -19.742613) (xy 429.483294 -19.703878) (xy 429.449186 -19.659706) (xy 429.421872 -19.611038)
			(xy 429.401936 -19.558912) (xy 429.389801 -19.504439) (xy 429.385728 -19.44878) (xy 419.415724 -19.44878)
			(xy 419.422153 -19.482138) (xy 419.430204 -19.566452) (xy 419.430708 -19.6088) (xy 419.430708 -19.609308)
			(xy 419.430102 -19.65564) (xy 419.420431 -19.747798) (xy 419.401235 -19.838452) (xy 419.372723 -19.926621)
			(xy 419.354508 -19.969226) (xy 419.350702 -19.979168) (xy 419.350702 -20.000432) (xy 419.354508 -20.010374)
			(xy 419.372741 -20.053007) (xy 419.401272 -20.141236) (xy 419.420465 -20.231957) (xy 419.430112 -20.324182)
			(xy 419.430708 -20.370546) (xy 419.430708 -20.371054) (xy 419.430114 -20.417418) (xy 419.420455 -20.509641)
			(xy 419.40126 -20.60036) (xy 419.372734 -20.688591) (xy 419.354508 -20.731226) (xy 419.350702 -20.741168)
			(xy 419.350702 -20.762432) (xy 419.354508 -20.772374) (xy 419.37273 -20.814977) (xy 419.401248 -20.903144)
			(xy 419.42044 -20.9938) (xy 419.4301 -21.08596) (xy 419.430708 -21.132292) (xy 419.430708 -21.1328)
			(xy 419.430204 -21.175148) (xy 419.422153 -21.259462) (xy 419.406124 -21.342628) (xy 419.382263 -21.423895)
			(xy 419.350784 -21.502525) (xy 419.311973 -21.577806) (xy 419.266183 -21.649058) (xy 419.213827 -21.715634)
			(xy 419.155379 -21.776932) (xy 419.091369 -21.832397) (xy 419.022377 -21.881526) (xy 418.949027 -21.923875)
			(xy 418.871984 -21.959059) (xy 418.791945 -21.986761) (xy 418.709636 -22.006729) (xy 418.625801 -22.018782)
			(xy 418.5412 -22.022813) (xy 418.456599 -22.018782) (xy 418.372764 -22.006729) (xy 418.290455 -21.986761)
			(xy 418.210416 -21.959059) (xy 418.133373 -21.923875) (xy 418.060023 -21.881526) (xy 417.991031 -21.832397)
			(xy 417.927021 -21.776932) (xy 417.868573 -21.715634) (xy 417.816217 -21.649058) (xy 417.770427 -21.577806)
			(xy 417.731616 -21.502525) (xy 417.700137 -21.423895) (xy 417.676276 -21.342628) (xy 417.660247 -21.259462)
			(xy 417.652196 -21.175148) (xy 417.651692 -21.1328) (xy 411.535018 -21.1328) (xy 411.533111 -21.139294)
			(xy 411.510469 -21.188871) (xy 411.481003 -21.234721) (xy 411.445312 -21.275912) (xy 411.404121 -21.311603)
			(xy 411.358271 -21.341069) (xy 411.308694 -21.363711) (xy 411.256399 -21.379066) (xy 411.202451 -21.386822)
			(xy 411.1752 -21.387308) (xy 411.146281 -21.386825) (xy 411.089107 -21.378093) (xy 411.033906 -21.360831)
			(xy 410.981944 -21.335433) (xy 410.934411 -21.302481) (xy 410.892397 -21.262732) (xy 410.87421 -21.240242)
			(xy 410.866649 -21.231479) (xy 410.845889 -21.221299) (xy 410.834332 -21.220684) (xy 410.754068 -21.220684)
			(xy 410.742506 -21.221299) (xy 410.721735 -21.231463) (xy 410.71419 -21.240242) (xy 410.696015 -21.262739)
			(xy 410.653991 -21.302471) (xy 410.606452 -21.335408) (xy 410.554488 -21.360793) (xy 410.499288 -21.378047)
			(xy 410.442117 -21.386774) (xy 410.4132 -21.387308) (xy 410.384201 -21.386761) (xy 410.32687 -21.377982)
			(xy 410.271529 -21.360626) (xy 410.219452 -21.335093) (xy 410.171841 -21.301972) (xy 410.129791 -21.262026)
			(xy 410.094272 -21.216175) (xy 410.066104 -21.165476) (xy 410.045933 -21.111097) (xy 410.034227 -21.054292)
			(xy 410.0322 -21.025358) (xy 409.037487 -21.025358) (xy 409.017203 -21.056921) (xy 408.981512 -21.098112)
			(xy 408.940321 -21.133803) (xy 408.894471 -21.163269) (xy 408.844894 -21.185911) (xy 408.792599 -21.201266)
			(xy 408.738651 -21.209022) (xy 408.7114 -21.209508) (xy 408.682481 -21.209025) (xy 408.625307 -21.200293)
			(xy 408.570106 -21.183031) (xy 408.518144 -21.157633) (xy 408.470611 -21.124681) (xy 408.428597 -21.084932)
			(xy 408.41041 -21.062442) (xy 408.402849 -21.053679) (xy 408.382089 -21.043499) (xy 408.370532 -21.042884)
			(xy 408.290268 -21.042884) (xy 408.278706 -21.043499) (xy 408.257935 -21.053663) (xy 408.25039 -21.062442)
			(xy 408.232215 -21.084939) (xy 408.190191 -21.124671) (xy 408.142652 -21.157608) (xy 408.090688 -21.182993)
			(xy 408.035488 -21.200247) (xy 407.978317 -21.208974) (xy 407.9494 -21.209508) (xy 407.922149 -21.209022)
			(xy 407.868201 -21.201266) (xy 407.815906 -21.185911) (xy 407.766329 -21.163269) (xy 407.720479 -21.133803)
			(xy 407.679288 -21.098112) (xy 407.643597 -21.056921) (xy 407.614131 -21.011071) (xy 407.591489 -20.961494)
			(xy 407.576134 -20.909199) (xy 407.568378 -20.855251) (xy 407.314411 -20.855251) (xy 407.314399 -20.855886)
			(xy 407.306279 -20.911062) (xy 407.290211 -20.964469) (xy 407.266539 -21.014966) (xy 407.235766 -21.061479)
			(xy 407.198549 -21.103016) (xy 407.155681 -21.138691) (xy 407.108075 -21.167745) (xy 407.056746 -21.189557)
			(xy 407.002789 -21.203663) (xy 406.947352 -21.209763) (xy 406.891618 -21.207726) (xy 406.836775 -21.197596)
			(xy 406.783991 -21.179589) (xy 406.734391 -21.154088) (xy 406.689033 -21.121637) (xy 406.648884 -21.082928)
			(xy 406.614798 -21.038785) (xy 406.587502 -20.99015) (xy 406.567579 -20.938059) (xy 406.555453 -20.883622)
			(xy 406.551382 -20.828) (xy 390.289324 -20.828) (xy 390.268342 -20.873606) (xy 390.207247 -20.98738)
			(xy 390.139264 -21.097177) (xy 390.06465 -21.20258) (xy 389.983689 -21.30319) (xy 389.896689 -21.398625)
			(xy 389.803978 -21.488524) (xy 389.705908 -21.572545) (xy 389.602853 -21.650369) (xy 389.502297 -21.717)
			(xy 406.551382 -21.717) (xy 406.555453 -21.661378) (xy 406.567579 -21.606941) (xy 406.587502 -21.55485)
			(xy 406.614798 -21.506215) (xy 406.648884 -21.462072) (xy 406.689033 -21.423363) (xy 406.734391 -21.390912)
			(xy 406.783991 -21.365411) (xy 406.836775 -21.347404) (xy 406.891618 -21.337274) (xy 406.947352 -21.335237)
			(xy 407.002789 -21.341337) (xy 407.056746 -21.355443) (xy 407.108075 -21.377255) (xy 407.155681 -21.406309)
			(xy 407.198549 -21.441984) (xy 407.235766 -21.483521) (xy 407.266539 -21.530034) (xy 407.290211 -21.580531)
			(xy 407.306279 -21.633938) (xy 407.314399 -21.689114) (xy 407.314908 -21.717) (xy 407.314411 -21.744251)
			(xy 407.568378 -21.744251) (xy 407.568378 -21.689749) (xy 407.576134 -21.635801) (xy 407.591489 -21.583506)
			(xy 407.614131 -21.533929) (xy 407.643597 -21.488079) (xy 407.679288 -21.446888) (xy 407.720479 -21.411197)
			(xy 407.766329 -21.381731) (xy 407.815906 -21.359089) (xy 407.868201 -21.343734) (xy 407.922149 -21.335978)
			(xy 407.9494 -21.335492) (xy 407.978319 -21.335975) (xy 408.035493 -21.344707) (xy 408.090694 -21.361969)
			(xy 408.142656 -21.387367) (xy 408.190189 -21.420319) (xy 408.232203 -21.460068) (xy 408.25039 -21.482558)
			(xy 408.257951 -21.491321) (xy 408.278711 -21.501501) (xy 408.290268 -21.502116) (xy 408.370532 -21.502116)
			(xy 408.382094 -21.501501) (xy 408.402865 -21.491337) (xy 408.41041 -21.482558) (xy 408.428585 -21.460061)
			(xy 408.470609 -21.420329) (xy 408.518148 -21.387392) (xy 408.570112 -21.362007) (xy 408.625312 -21.344753)
			(xy 408.682483 -21.336026) (xy 408.7114 -21.335492) (xy 408.738651 -21.335978) (xy 408.792599 -21.343734)
			(xy 408.844894 -21.359089) (xy 408.894471 -21.381731) (xy 408.940321 -21.411197) (xy 408.981512 -21.446888)
			(xy 409.017203 -21.488079) (xy 409.046669 -21.533929) (xy 409.069311 -21.583506) (xy 409.084666 -21.635801)
			(xy 409.092422 -21.689749) (xy 409.092422 -21.744251) (xy 409.084666 -21.798199) (xy 409.069311 -21.850494)
			(xy 409.046669 -21.900071) (xy 409.017203 -21.945921) (xy 408.981512 -21.987112) (xy 408.940321 -22.022803)
			(xy 408.894471 -22.052269) (xy 408.844894 -22.074911) (xy 408.792599 -22.090266) (xy 408.738651 -22.098022)
			(xy 408.7114 -22.098508) (xy 408.682481 -22.098025) (xy 408.625307 -22.089293) (xy 408.570106 -22.072031)
			(xy 408.518144 -22.046633) (xy 408.470611 -22.013681) (xy 408.428597 -21.973932) (xy 408.41041 -21.951442)
			(xy 408.402849 -21.942679) (xy 408.382089 -21.932499) (xy 408.370532 -21.931884) (xy 408.290268 -21.931884)
			(xy 408.278706 -21.932499) (xy 408.257935 -21.942663) (xy 408.25039 -21.951442) (xy 408.232215 -21.973939)
			(xy 408.190191 -22.013671) (xy 408.142652 -22.046608) (xy 408.090688 -22.071993) (xy 408.035488 -22.089247)
			(xy 407.978317 -22.097974) (xy 407.9494 -22.098508) (xy 407.922149 -22.098022) (xy 407.868201 -22.090266)
			(xy 407.815906 -22.074911) (xy 407.766329 -22.052269) (xy 407.720479 -22.022803) (xy 407.679288 -21.987112)
			(xy 407.643597 -21.945921) (xy 407.614131 -21.900071) (xy 407.591489 -21.850494) (xy 407.576134 -21.798199)
			(xy 407.568378 -21.744251) (xy 407.314411 -21.744251) (xy 407.314399 -21.744886) (xy 407.306279 -21.800062)
			(xy 407.290211 -21.853469) (xy 407.266539 -21.903966) (xy 407.235766 -21.950479) (xy 407.198549 -21.992016)
			(xy 407.155681 -22.027691) (xy 407.108075 -22.056745) (xy 407.056746 -22.078557) (xy 407.002789 -22.092663)
			(xy 406.947352 -22.098763) (xy 406.891618 -22.096726) (xy 406.836775 -22.086596) (xy 406.783991 -22.068589)
			(xy 406.734391 -22.043088) (xy 406.689033 -22.010637) (xy 406.648884 -21.971928) (xy 406.614798 -21.927785)
			(xy 406.587502 -21.87915) (xy 406.567579 -21.827059) (xy 406.555453 -21.772622) (xy 406.551382 -21.717)
			(xy 389.502297 -21.717) (xy 389.495202 -21.721701) (xy 389.383363 -21.786271) (xy 389.267762 -21.843833)
			(xy 389.148837 -21.89417) (xy 389.027038 -21.93709) (xy 388.902828 -21.972431) (xy 388.776679 -22.000058)
			(xy 388.649067 -22.019867) (xy 388.520478 -22.031783) (xy 388.3914 -22.03576) (xy 388.262322 -22.031783)
			(xy 388.133733 -22.019867) (xy 388.006121 -22.000058) (xy 387.879972 -21.972431) (xy 387.755762 -21.93709)
			(xy 387.633963 -21.89417) (xy 387.515038 -21.843833) (xy 387.399437 -21.786271) (xy 387.287598 -21.721701)
			(xy 387.179947 -21.650369) (xy 387.076892 -21.572545) (xy 386.978822 -21.488524) (xy 386.886111 -21.398625)
			(xy 386.799111 -21.30319) (xy 386.71815 -21.20258) (xy 386.643536 -21.097177) (xy 386.575553 -20.98738)
			(xy 386.514458 -20.873606) (xy 386.460483 -20.756287) (xy 386.413832 -20.635868) (xy 386.374683 -20.512805)
			(xy 386.343184 -20.387566) (xy 386.319455 -20.260625) (xy 386.303585 -20.132465) (xy 386.295635 -20.00357)
			(xy 373.911164 -20.00357) (xy 373.852916 -20.182838) (xy 373.783111 -20.372055) (xy 373.752067 -20.447)
			(xy 378.077982 -20.447) (xy 378.082053 -20.391378) (xy 378.094179 -20.336941) (xy 378.114102 -20.28485)
			(xy 378.141398 -20.236215) (xy 378.175484 -20.192072) (xy 378.215633 -20.153363) (xy 378.260991 -20.120912)
			(xy 378.310591 -20.095411) (xy 378.363375 -20.077404) (xy 378.418218 -20.067274) (xy 378.473952 -20.065237)
			(xy 378.529389 -20.071337) (xy 378.583346 -20.085443) (xy 378.634675 -20.107255) (xy 378.682281 -20.136309)
			(xy 378.725149 -20.171984) (xy 378.762366 -20.213521) (xy 378.793139 -20.260034) (xy 378.816811 -20.310531)
			(xy 378.832879 -20.363938) (xy 378.840999 -20.419114) (xy 378.841508 -20.447) (xy 378.840999 -20.474886)
			(xy 378.832879 -20.530062) (xy 378.816811 -20.583469) (xy 378.793139 -20.633966) (xy 378.762366 -20.680479)
			(xy 378.725149 -20.722016) (xy 378.682281 -20.757691) (xy 378.634675 -20.786745) (xy 378.583346 -20.808557)
			(xy 378.529389 -20.822663) (xy 378.473952 -20.828763) (xy 378.418218 -20.826726) (xy 378.363375 -20.816596)
			(xy 378.310591 -20.798589) (xy 378.260991 -20.773088) (xy 378.215633 -20.740637) (xy 378.175484 -20.701928)
			(xy 378.141398 -20.657785) (xy 378.114102 -20.60915) (xy 378.094179 -20.557059) (xy 378.082053 -20.502622)
			(xy 378.077982 -20.447) (xy 373.752067 -20.447) (xy 373.70593 -20.558384) (xy 373.621494 -20.741541)
			(xy 373.529932 -20.921241) (xy 373.431386 -21.097207) (xy 373.326008 -21.26917) (xy 373.281353 -21.336)
			(xy 378.077728 -21.336) (xy 378.081801 -21.280341) (xy 378.093936 -21.225868) (xy 378.113872 -21.173742)
			(xy 378.141186 -21.125074) (xy 378.175294 -21.080902) (xy 378.215471 -21.042167) (xy 378.260859 -21.009695)
			(xy 378.310491 -20.984177) (xy 378.363311 -20.966158) (xy 378.41819 -20.956021) (xy 378.473961 -20.953983)
			(xy 378.529435 -20.960086) (xy 378.583428 -20.974202) (xy 378.634791 -20.996029) (xy 378.682429 -21.025102)
			(xy 378.725325 -21.060801) (xy 378.762567 -21.102365) (xy 378.793361 -21.148909) (xy 378.817049 -21.19944)
			(xy 378.819925 -21.209) (xy 379.278894 -21.209) (xy 379.282965 -21.153378) (xy 379.295091 -21.098941)
			(xy 379.315014 -21.04685) (xy 379.34231 -20.998215) (xy 379.376396 -20.954072) (xy 379.416545 -20.915363)
			(xy 379.461903 -20.882912) (xy 379.511503 -20.857411) (xy 379.564287 -20.839404) (xy 379.61913 -20.829274)
			(xy 379.674864 -20.827237) (xy 379.730301 -20.833337) (xy 379.784258 -20.847443) (xy 379.835587 -20.869255)
			(xy 379.883193 -20.898309) (xy 379.926061 -20.933984) (xy 379.963278 -20.975521) (xy 379.994051 -21.022034)
			(xy 380.017723 -21.072531) (xy 380.033791 -21.125938) (xy 380.041911 -21.181114) (xy 380.04242 -21.209)
			(xy 380.041911 -21.236886) (xy 380.033791 -21.292062) (xy 380.017723 -21.345469) (xy 379.994051 -21.395966)
			(xy 379.963278 -21.442479) (xy 379.926061 -21.484016) (xy 379.883193 -21.519691) (xy 379.835587 -21.548745)
			(xy 379.784258 -21.570557) (xy 379.730301 -21.584663) (xy 379.674864 -21.590763) (xy 379.61913 -21.588726)
			(xy 379.564287 -21.578596) (xy 379.511503 -21.560589) (xy 379.461903 -21.535088) (xy 379.416545 -21.502637)
			(xy 379.376396 -21.463928) (xy 379.34231 -21.419785) (xy 379.315014 -21.37115) (xy 379.295091 -21.319059)
			(xy 379.282965 -21.264622) (xy 379.278894 -21.209) (xy 378.819925 -21.209) (xy 378.833127 -21.252882)
			(xy 378.841253 -21.308096) (xy 378.841762 -21.336) (xy 378.841253 -21.363904) (xy 378.833127 -21.419118)
			(xy 378.817049 -21.47256) (xy 378.793361 -21.523091) (xy 378.762567 -21.569635) (xy 378.725325 -21.611199)
			(xy 378.682429 -21.646898) (xy 378.634791 -21.675971) (xy 378.583428 -21.697798) (xy 378.529435 -21.711914)
			(xy 378.473961 -21.718017) (xy 378.41819 -21.715979) (xy 378.363311 -21.705842) (xy 378.310491 -21.687823)
			(xy 378.260859 -21.662305) (xy 378.215471 -21.629833) (xy 378.175294 -21.591098) (xy 378.141186 -21.546926)
			(xy 378.113872 -21.498258) (xy 378.093936 -21.446132) (xy 378.081801 -21.391659) (xy 378.077728 -21.336)
			(xy 373.281353 -21.336) (xy 373.213959 -21.436862) (xy 373.095413 -21.600026) (xy 372.970553 -21.758411)
			(xy 372.839571 -21.911771) (xy 372.702669 -22.059871) (xy 372.560059 -22.202481) (xy 372.411959 -22.339383)
			(xy 372.258599 -22.470365) (xy 372.100214 -22.595225) (xy 372.085384 -22.606) (xy 406.551382 -22.606)
			(xy 406.555453 -22.550378) (xy 406.567579 -22.495941) (xy 406.587502 -22.44385) (xy 406.614798 -22.395215)
			(xy 406.648884 -22.351072) (xy 406.689033 -22.312363) (xy 406.734391 -22.279912) (xy 406.783991 -22.254411)
			(xy 406.836775 -22.236404) (xy 406.891618 -22.226274) (xy 406.947352 -22.224237) (xy 407.002789 -22.230337)
			(xy 407.056746 -22.244443) (xy 407.108075 -22.266255) (xy 407.155681 -22.295309) (xy 407.198549 -22.330984)
			(xy 407.235766 -22.372521) (xy 407.266539 -22.419034) (xy 407.290211 -22.469531) (xy 407.306279 -22.522938)
			(xy 407.314399 -22.578114) (xy 407.314908 -22.606) (xy 407.314411 -22.633251) (xy 407.568378 -22.633251)
			(xy 407.568378 -22.578749) (xy 407.576134 -22.524801) (xy 407.591489 -22.472506) (xy 407.614131 -22.422929)
			(xy 407.643597 -22.377079) (xy 407.679288 -22.335888) (xy 407.720479 -22.300197) (xy 407.766329 -22.270731)
			(xy 407.815906 -22.248089) (xy 407.868201 -22.232734) (xy 407.922149 -22.224978) (xy 407.9494 -22.224492)
			(xy 407.978319 -22.224975) (xy 408.035493 -22.233707) (xy 408.090694 -22.250969) (xy 408.142656 -22.276367)
			(xy 408.190189 -22.309319) (xy 408.232203 -22.349068) (xy 408.25039 -22.371558) (xy 408.257951 -22.380321)
			(xy 408.278711 -22.390501) (xy 408.290268 -22.391116) (xy 408.370532 -22.391116) (xy 408.382094 -22.390501)
			(xy 408.402865 -22.380337) (xy 408.41041 -22.371558) (xy 408.428585 -22.349061) (xy 408.470609 -22.309329)
			(xy 408.518148 -22.276392) (xy 408.570112 -22.251007) (xy 408.625312 -22.233753) (xy 408.682483 -22.225026)
			(xy 408.7114 -22.224492) (xy 408.738651 -22.224978) (xy 408.792599 -22.232734) (xy 408.844894 -22.248089)
			(xy 408.894471 -22.270731) (xy 408.940321 -22.300197) (xy 408.981512 -22.335888) (xy 409.017203 -22.377079)
			(xy 409.046669 -22.422929) (xy 409.069311 -22.472506) (xy 409.084666 -22.524801) (xy 409.092422 -22.578749)
			(xy 409.092422 -22.633251) (xy 409.084666 -22.687199) (xy 409.069311 -22.739494) (xy 409.046669 -22.789071)
			(xy 409.017203 -22.834921) (xy 408.981512 -22.876112) (xy 408.940321 -22.911803) (xy 408.894471 -22.941269)
			(xy 408.844894 -22.963911) (xy 408.792599 -22.979266) (xy 408.738651 -22.987022) (xy 408.7114 -22.987508)
			(xy 408.682481 -22.987025) (xy 408.625307 -22.978293) (xy 408.570106 -22.961031) (xy 408.518144 -22.935633)
			(xy 408.470611 -22.902681) (xy 408.428597 -22.862932) (xy 408.41041 -22.840442) (xy 408.402849 -22.831679)
			(xy 408.382089 -22.821499) (xy 408.370532 -22.820884) (xy 408.290268 -22.820884) (xy 408.278706 -22.821499)
			(xy 408.257935 -22.831663) (xy 408.25039 -22.840442) (xy 408.232215 -22.862939) (xy 408.190191 -22.902671)
			(xy 408.142652 -22.935608) (xy 408.090688 -22.960993) (xy 408.035488 -22.978247) (xy 407.978317 -22.986974)
			(xy 407.9494 -22.987508) (xy 407.922149 -22.987022) (xy 407.868201 -22.979266) (xy 407.815906 -22.963911)
			(xy 407.766329 -22.941269) (xy 407.720479 -22.911803) (xy 407.679288 -22.876112) (xy 407.643597 -22.834921)
			(xy 407.614131 -22.789071) (xy 407.591489 -22.739494) (xy 407.576134 -22.687199) (xy 407.568378 -22.633251)
			(xy 407.314411 -22.633251) (xy 407.314399 -22.633886) (xy 407.306279 -22.689062) (xy 407.290211 -22.742469)
			(xy 407.266539 -22.792966) (xy 407.235766 -22.839479) (xy 407.198549 -22.881016) (xy 407.155681 -22.916691)
			(xy 407.108075 -22.945745) (xy 407.056746 -22.967557) (xy 407.002789 -22.981663) (xy 406.947352 -22.987763)
			(xy 406.891618 -22.985726) (xy 406.836775 -22.975596) (xy 406.783991 -22.957589) (xy 406.734391 -22.932088)
			(xy 406.689033 -22.899637) (xy 406.648884 -22.860928) (xy 406.614798 -22.816785) (xy 406.587502 -22.76815)
			(xy 406.567579 -22.716059) (xy 406.555453 -22.661622) (xy 406.551382 -22.606) (xy 372.085384 -22.606)
			(xy 371.93705 -22.713771) (xy 371.769358 -22.82582) (xy 371.597395 -22.931198) (xy 371.421429 -23.029744)
			(xy 371.241729 -23.121306) (xy 371.058572 -23.205742) (xy 370.872243 -23.282923) (xy 370.683026 -23.352728)
			(xy 370.636023 -23.368) (xy 432.967382 -23.368) (xy 432.971453 -23.312378) (xy 432.983579 -23.257941)
			(xy 433.003502 -23.20585) (xy 433.030798 -23.157215) (xy 433.064884 -23.113072) (xy 433.105033 -23.074363)
			(xy 433.150391 -23.041912) (xy 433.199991 -23.016411) (xy 433.252775 -22.998404) (xy 433.307618 -22.988274)
			(xy 433.363352 -22.986237) (xy 433.418789 -22.992337) (xy 433.472746 -23.006443) (xy 433.524075 -23.028255)
			(xy 433.571681 -23.057309) (xy 433.614549 -23.092984) (xy 433.651766 -23.134521) (xy 433.682539 -23.181034)
			(xy 433.706211 -23.231531) (xy 433.722279 -23.284938) (xy 433.730399 -23.340114) (xy 433.730908 -23.368)
			(xy 433.730399 -23.395886) (xy 433.722279 -23.451062) (xy 433.706211 -23.504469) (xy 433.682539 -23.554966)
			(xy 433.651766 -23.601479) (xy 433.614549 -23.643016) (xy 433.571681 -23.678691) (xy 433.524075 -23.707745)
			(xy 433.472746 -23.729557) (xy 433.418789 -23.743663) (xy 433.363352 -23.749763) (xy 433.307618 -23.747726)
			(xy 433.252775 -23.737596) (xy 433.199991 -23.719589) (xy 433.150391 -23.694088) (xy 433.105033 -23.661637)
			(xy 433.064884 -23.622928) (xy 433.030798 -23.578785) (xy 433.003502 -23.53015) (xy 432.983579 -23.478059)
			(xy 432.971453 -23.423622) (xy 432.967382 -23.368) (xy 370.636023 -23.368) (xy 370.491215 -23.415051)
			(xy 370.297105 -23.469796) (xy 370.100996 -23.516878) (xy 369.903189 -23.556224) (xy 369.70399 -23.587774)
			(xy 369.503706 -23.611479) (xy 369.302646 -23.627303) (xy 369.101119 -23.635221) (xy 368.899437 -23.635221)
			(xy 368.69791 -23.627303) (xy 368.49685 -23.611479) (xy 368.296566 -23.587774) (xy 368.097367 -23.556224)
			(xy 367.89956 -23.516878) (xy 367.703451 -23.469796) (xy 367.509341 -23.415051) (xy 367.31753 -23.352728)
			(xy 367.128313 -23.282923) (xy 366.941984 -23.205742) (xy 366.758827 -23.121306) (xy 366.579127 -23.029744)
			(xy 366.403161 -22.931198) (xy 366.231198 -22.82582) (xy 366.063506 -22.713771) (xy 365.900342 -22.595225)
			(xy 365.741957 -22.470365) (xy 365.588597 -22.339383) (xy 365.440497 -22.202481) (xy 365.297887 -22.059871)
			(xy 365.160985 -21.911771) (xy 365.030003 -21.758411) (xy 364.905143 -21.600026) (xy 364.786597 -21.436862)
			(xy 364.674548 -21.26917) (xy 364.56917 -21.097207) (xy 364.470624 -20.921241) (xy 364.379062 -20.741541)
			(xy 364.294626 -20.558384) (xy 364.217445 -20.372055) (xy 364.14764 -20.182838) (xy 364.085317 -19.991027)
			(xy 364.030572 -19.796917) (xy 363.98349 -19.600808) (xy 363.944144 -19.403001) (xy 363.912594 -19.203802)
			(xy 363.888889 -19.003518) (xy 363.873065 -18.802458) (xy 363.865147 -18.600931) (xy 363.864652 -18.50009)
			(xy 358.284018 -18.50009) (xy 364.406942 -24.623014) (xy 388.644382 -24.623014) (xy 388.648453 -24.567392)
			(xy 388.660579 -24.512955) (xy 388.680502 -24.460864) (xy 388.707798 -24.412229) (xy 388.741884 -24.368086)
			(xy 388.782033 -24.329377) (xy 388.827391 -24.296926) (xy 388.876991 -24.271425) (xy 388.929775 -24.253418)
			(xy 388.984618 -24.243288) (xy 389.040352 -24.241251) (xy 389.095789 -24.247351) (xy 389.149746 -24.261457)
			(xy 389.201075 -24.283269) (xy 389.248681 -24.312323) (xy 389.291549 -24.347998) (xy 389.328766 -24.389535)
			(xy 389.359539 -24.436048) (xy 389.383211 -24.486545) (xy 389.390569 -24.511) (xy 393.571728 -24.511)
			(xy 393.575801 -24.455341) (xy 393.587936 -24.400868) (xy 393.607872 -24.348742) (xy 393.635186 -24.300074)
			(xy 393.669294 -24.255902) (xy 393.709471 -24.217167) (xy 393.754859 -24.184695) (xy 393.804491 -24.159177)
			(xy 393.857311 -24.141158) (xy 393.91219 -24.131021) (xy 393.967961 -24.128983) (xy 394.023435 -24.135086)
			(xy 394.077428 -24.149202) (xy 394.128791 -24.171029) (xy 394.176429 -24.200102) (xy 394.219325 -24.235801)
			(xy 394.256567 -24.277365) (xy 394.287361 -24.323909) (xy 394.308386 -24.36876) (xy 436.925972 -24.36876)
			(xy 436.930043 -24.313138) (xy 436.942169 -24.258701) (xy 436.962092 -24.20661) (xy 436.989388 -24.157975)
			(xy 437.023474 -24.113832) (xy 437.063623 -24.075123) (xy 437.108981 -24.042672) (xy 437.158581 -24.017171)
			(xy 437.211365 -23.999164) (xy 437.266208 -23.989034) (xy 437.321942 -23.986997) (xy 437.377379 -23.993097)
			(xy 437.431336 -24.007203) (xy 437.482665 -24.029015) (xy 437.530271 -24.058069) (xy 437.573139 -24.093744)
			(xy 437.610356 -24.135281) (xy 437.641129 -24.181794) (xy 437.664801 -24.232291) (xy 437.680869 -24.285698)
			(xy 437.688989 -24.340874) (xy 437.689498 -24.36876) (xy 437.688989 -24.396646) (xy 437.680869 -24.451822)
			(xy 437.664801 -24.505229) (xy 437.641129 -24.555726) (xy 437.610356 -24.602239) (xy 437.573139 -24.643776)
			(xy 437.530271 -24.679451) (xy 437.482665 -24.708505) (xy 437.431336 -24.730317) (xy 437.377379 -24.744423)
			(xy 437.321942 -24.750523) (xy 437.266208 -24.748486) (xy 437.211365 -24.738356) (xy 437.158581 -24.720349)
			(xy 437.108981 -24.694848) (xy 437.063623 -24.662397) (xy 437.023474 -24.623688) (xy 436.989388 -24.579545)
			(xy 436.962092 -24.53091) (xy 436.942169 -24.478819) (xy 436.930043 -24.424382) (xy 436.925972 -24.36876)
			(xy 394.308386 -24.36876) (xy 394.311049 -24.37444) (xy 394.327127 -24.427882) (xy 394.335253 -24.483096)
			(xy 394.335762 -24.511) (xy 394.335253 -24.538904) (xy 394.327127 -24.594118) (xy 394.311049 -24.64756)
			(xy 394.287361 -24.698091) (xy 394.256567 -24.744635) (xy 394.219325 -24.786199) (xy 394.176429 -24.821898)
			(xy 394.128791 -24.850971) (xy 394.077428 -24.872798) (xy 394.023435 -24.886914) (xy 393.967961 -24.893017)
			(xy 393.91219 -24.890979) (xy 393.857311 -24.880842) (xy 393.804491 -24.862823) (xy 393.754859 -24.837305)
			(xy 393.709471 -24.804833) (xy 393.669294 -24.766098) (xy 393.635186 -24.721926) (xy 393.607872 -24.673258)
			(xy 393.587936 -24.621132) (xy 393.575801 -24.566659) (xy 393.571728 -24.511) (xy 389.390569 -24.511)
			(xy 389.399279 -24.539952) (xy 389.407399 -24.595128) (xy 389.407908 -24.623014) (xy 389.407399 -24.6509)
			(xy 389.399279 -24.706076) (xy 389.383211 -24.759483) (xy 389.359539 -24.80998) (xy 389.328766 -24.856493)
			(xy 389.291549 -24.89803) (xy 389.248681 -24.933705) (xy 389.201075 -24.962759) (xy 389.149746 -24.984571)
			(xy 389.095789 -24.998677) (xy 389.040352 -25.004777) (xy 388.984618 -25.00274) (xy 388.929775 -24.99261)
			(xy 388.876991 -24.974603) (xy 388.827391 -24.949102) (xy 388.782033 -24.916651) (xy 388.741884 -24.877942)
			(xy 388.707798 -24.833799) (xy 388.680502 -24.785164) (xy 388.660579 -24.733073) (xy 388.648453 -24.678636)
			(xy 388.644382 -24.623014) (xy 364.406942 -24.623014) (xy 364.910878 -25.12695) (xy 387.501382 -25.12695)
			(xy 387.505453 -25.071328) (xy 387.517579 -25.016891) (xy 387.537502 -24.9648) (xy 387.564798 -24.916165)
			(xy 387.598884 -24.872022) (xy 387.639033 -24.833313) (xy 387.684391 -24.800862) (xy 387.733991 -24.775361)
			(xy 387.786775 -24.757354) (xy 387.841618 -24.747224) (xy 387.897352 -24.745187) (xy 387.952789 -24.751287)
			(xy 388.006746 -24.765393) (xy 388.058075 -24.787205) (xy 388.105681 -24.816259) (xy 388.148549 -24.851934)
			(xy 388.185766 -24.893471) (xy 388.216539 -24.939984) (xy 388.240211 -24.990481) (xy 388.256279 -25.043888)
			(xy 388.264399 -25.099064) (xy 388.264908 -25.12695) (xy 388.264399 -25.154836) (xy 388.256279 -25.210012)
			(xy 388.240211 -25.263419) (xy 388.216539 -25.313916) (xy 388.185766 -25.360429) (xy 388.148549 -25.401966)
			(xy 388.105681 -25.437641) (xy 388.058075 -25.466695) (xy 388.006746 -25.488507) (xy 387.952789 -25.502613)
			(xy 387.897352 -25.508713) (xy 387.841618 -25.506676) (xy 387.786775 -25.496546) (xy 387.733991 -25.478539)
			(xy 387.684391 -25.453038) (xy 387.639033 -25.420587) (xy 387.598884 -25.381878) (xy 387.564798 -25.337735)
			(xy 387.537502 -25.2891) (xy 387.517579 -25.237009) (xy 387.505453 -25.182572) (xy 387.501382 -25.12695)
			(xy 364.910878 -25.12695) (xy 367.920254 -28.136326) (xy 376.278993 -28.136326) (xy 376.282711 -28.083107)
			(xy 376.293799 -28.030924) (xy 376.312041 -27.980791) (xy 376.337082 -27.933685) (xy 376.368435 -27.890522)
			(xy 376.40549 -27.852143) (xy 376.426222 -27.835352) (xy 376.437982 -27.825407) (xy 376.455494 -27.800095)
			(xy 376.464671 -27.770715) (xy 376.464678 -27.739936) (xy 376.455517 -27.710552) (xy 376.438017 -27.685231)
			(xy 376.426222 -27.675332) (xy 376.405529 -27.658492) (xy 376.368469 -27.620117) (xy 376.33711 -27.576959)
			(xy 376.312062 -27.529856) (xy 376.293813 -27.479726) (xy 376.282718 -27.427544) (xy 376.278993 -27.374326)
			(xy 376.282711 -27.321107) (xy 376.293799 -27.268924) (xy 376.312041 -27.218791) (xy 376.337082 -27.171685)
			(xy 376.368435 -27.128522) (xy 376.40549 -27.090143) (xy 376.426222 -27.073352) (xy 376.437982 -27.063407)
			(xy 376.455494 -27.038095) (xy 376.464671 -27.008715) (xy 376.464678 -26.977936) (xy 376.455517 -26.948552)
			(xy 376.438017 -26.923231) (xy 376.426222 -26.913332) (xy 376.403756 -26.895138) (xy 376.364083 -26.85309)
			(xy 376.331201 -26.805543) (xy 376.305861 -26.753583) (xy 376.288642 -26.698397) (xy 376.279937 -26.641247)
			(xy 376.27941 -26.612342) (xy 376.27994 -26.585073) (xy 376.287696 -26.53109) (xy 376.303056 -26.478761)
			(xy 376.325706 -26.429149) (xy 376.355187 -26.383267) (xy 376.390897 -26.342047) (xy 376.432111 -26.306329)
			(xy 376.477988 -26.27684) (xy 376.527595 -26.25418) (xy 376.579922 -26.238811) (xy 376.633903 -26.231045)
			(xy 376.661172 -26.23058) (xy 376.690074 -26.231126) (xy 376.747217 -26.239844) (xy 376.802396 -26.257069)
			(xy 376.85435 -26.282409) (xy 376.901895 -26.315285) (xy 376.943945 -26.354947) (xy 376.962162 -26.377392)
			(xy 376.972059 -26.389197) (xy 376.997383 -26.406716) (xy 377.026776 -26.415892) (xy 377.057568 -26.415892)
			(xy 377.086961 -26.406716) (xy 377.112285 -26.389197) (xy 377.122182 -26.377392) (xy 377.138974 -26.356659)
			(xy 377.177355 -26.3196) (xy 377.22052 -26.288244) (xy 377.267628 -26.263199) (xy 377.317763 -26.244953)
			(xy 377.36995 -26.233862) (xy 377.423172 -26.23014) (xy 377.476394 -26.233862) (xy 377.528581 -26.244953)
			(xy 377.578716 -26.263199) (xy 377.625824 -26.288244) (xy 377.668989 -26.3196) (xy 377.70737 -26.356659)
			(xy 377.724162 -26.377392) (xy 377.734059 -26.389197) (xy 377.759383 -26.406716) (xy 377.788776 -26.415892)
			(xy 377.819568 -26.415892) (xy 377.848961 -26.406716) (xy 377.874285 -26.389197) (xy 377.884182 -26.377392)
			(xy 377.900974 -26.356659) (xy 377.939355 -26.3196) (xy 377.98252 -26.288244) (xy 378.029628 -26.263199)
			(xy 378.079763 -26.244953) (xy 378.13195 -26.233862) (xy 378.185172 -26.23014) (xy 378.238394 -26.233862)
			(xy 378.290581 -26.244953) (xy 378.340716 -26.263199) (xy 378.387824 -26.288244) (xy 378.430989 -26.3196)
			(xy 378.46937 -26.356659) (xy 378.486162 -26.377392) (xy 378.496059 -26.389197) (xy 378.521383 -26.406716)
			(xy 378.550776 -26.415892) (xy 378.581568 -26.415892) (xy 378.610961 -26.406716) (xy 378.636285 -26.389197)
			(xy 378.646182 -26.377392) (xy 378.664361 -26.354913) (xy 378.706413 -26.315242) (xy 378.753963 -26.282363)
			(xy 378.805926 -26.257025) (xy 378.861114 -26.239809) (xy 378.918266 -26.231106) (xy 378.947172 -26.23058)
			(xy 378.974444 -26.231028) (xy 379.028434 -26.238787) (xy 379.080769 -26.254152) (xy 379.130385 -26.276809)
			(xy 379.176271 -26.306298) (xy 379.217493 -26.342017) (xy 379.253211 -26.38324) (xy 379.282697 -26.429127)
			(xy 379.305353 -26.478744) (xy 379.320716 -26.53108) (xy 379.328473 -26.58507) (xy 379.328934 -26.612342)
			(xy 379.328361 -26.641243) (xy 379.319648 -26.698385) (xy 379.302428 -26.753562) (xy 379.277093 -26.805517)
			(xy 379.244222 -26.853062) (xy 379.204565 -26.895114) (xy 379.182122 -26.913332) (xy 379.170274 -26.923183)
			(xy 379.152755 -26.948519) (xy 379.143583 -26.977924) (xy 379.143591 -27.008727) (xy 379.152778 -27.038128)
			(xy 379.17031 -27.063455) (xy 379.182122 -27.073352) (xy 379.202896 -27.090095) (xy 379.239953 -27.128483)
			(xy 379.271308 -27.171654) (xy 379.296351 -27.218768) (xy 379.314594 -27.268908) (xy 379.325682 -27.321099)
			(xy 379.3294 -27.374326) (xy 379.325675 -27.427552) (xy 379.31458 -27.479742) (xy 379.29633 -27.52988)
			(xy 379.271281 -27.57699) (xy 379.23992 -27.620157) (xy 379.202857 -27.65854) (xy 379.182122 -27.675332)
			(xy 379.170274 -27.685183) (xy 379.152755 -27.710519) (xy 379.143583 -27.739924) (xy 379.143591 -27.770727)
			(xy 379.152778 -27.800128) (xy 379.17031 -27.825455) (xy 379.182122 -27.835352) (xy 379.202896 -27.852095)
			(xy 379.239953 -27.890483) (xy 379.271308 -27.933654) (xy 379.296351 -27.980768) (xy 379.314594 -28.030908)
			(xy 379.325682 -28.083099) (xy 379.3294 -28.136326) (xy 379.325675 -28.189552) (xy 379.31458 -28.241742)
			(xy 379.29633 -28.29188) (xy 379.280847 -28.321) (xy 386.358388 -28.321) (xy 386.362418 -28.236399)
			(xy 386.374471 -28.152564) (xy 386.394439 -28.070255) (xy 386.422141 -27.990216) (xy 386.457325 -27.913173)
			(xy 386.499674 -27.839823) (xy 386.548803 -27.770831) (xy 386.604268 -27.706821) (xy 386.665566 -27.648373)
			(xy 386.732142 -27.596017) (xy 386.803394 -27.550227) (xy 386.878675 -27.511416) (xy 386.957305 -27.479937)
			(xy 387.038572 -27.456076) (xy 387.121738 -27.440047) (xy 387.206052 -27.431996) (xy 387.2484 -27.431492)
			(xy 387.294669 -27.432251) (xy 387.386677 -27.442172) (xy 387.432042 -27.451304) (xy 387.437376 -27.45232)
			(xy 387.438138 -27.45232) (xy 387.447282 -27.454098) (xy 387.459474 -27.454098) (xy 387.465197 -27.453937)
			(xy 387.47635 -27.451365) (xy 387.481572 -27.449018) (xy 387.514592 -27.433016) (xy 387.52145 -27.426158)
			(xy 387.524846 -27.422653) (xy 387.530347 -27.414596) (xy 387.532372 -27.410156) (xy 387.533388 -27.407616)
			(xy 387.544853 -27.382363) (xy 387.573978 -27.335168) (xy 387.609633 -27.292692) (xy 387.651067 -27.25583)
			(xy 387.697405 -27.225361) (xy 387.74767 -27.201929) (xy 387.800799 -27.186026) (xy 387.855671 -27.17799)
			(xy 387.8834 -27.177492) (xy 387.910651 -27.177978) (xy 387.964599 -27.185734) (xy 388.016894 -27.201089)
			(xy 388.066471 -27.223731) (xy 388.112321 -27.253197) (xy 388.153512 -27.288888) (xy 388.189203 -27.330079)
			(xy 388.218669 -27.375929) (xy 388.241311 -27.425506) (xy 388.256666 -27.477801) (xy 388.264422 -27.531749)
			(xy 388.264908 -27.559) (xy 388.264444 -27.585968) (xy 388.256836 -27.639365) (xy 388.241784 -27.691159)
			(xy 388.21959 -27.740318) (xy 388.190695 -27.785862) (xy 388.155675 -27.826884) (xy 388.115228 -27.862565)
			(xy 388.09295 -27.87777) (xy 388.085584 -27.882596) (xy 388.07517 -27.896312) (xy 388.06755 -27.920188)
			(xy 388.066461 -27.923903) (xy 388.065312 -27.931557) (xy 388.065264 -27.935428) (xy 388.065264 -27.94)
			(xy 409.599382 -27.94) (xy 409.603453 -27.884378) (xy 409.615579 -27.829941) (xy 409.635502 -27.77785)
			(xy 409.662798 -27.729215) (xy 409.696884 -27.685072) (xy 409.737033 -27.646363) (xy 409.782391 -27.613912)
			(xy 409.831991 -27.588411) (xy 409.884775 -27.570404) (xy 409.939618 -27.560274) (xy 409.995352 -27.558237)
			(xy 410.050789 -27.564337) (xy 410.104746 -27.578443) (xy 410.156075 -27.600255) (xy 410.203681 -27.629309)
			(xy 410.246549 -27.664984) (xy 410.283766 -27.706521) (xy 410.314539 -27.753034) (xy 410.338211 -27.803531)
			(xy 410.354279 -27.856938) (xy 410.362399 -27.912114) (xy 410.362908 -27.94) (xy 410.362399 -27.967886)
			(xy 410.354279 -28.023062) (xy 410.338211 -28.076469) (xy 410.314539 -28.126966) (xy 410.283766 -28.173479)
			(xy 410.246549 -28.215016) (xy 410.203681 -28.250691) (xy 410.156075 -28.279745) (xy 410.104746 -28.301557)
			(xy 410.050789 -28.315663) (xy 409.995352 -28.321763) (xy 409.939618 -28.319726) (xy 409.884775 -28.309596)
			(xy 409.831991 -28.291589) (xy 409.782391 -28.266088) (xy 409.737033 -28.233637) (xy 409.696884 -28.194928)
			(xy 409.662798 -28.150785) (xy 409.635502 -28.10215) (xy 409.615579 -28.050059) (xy 409.603453 -27.995622)
			(xy 409.599382 -27.94) (xy 388.065264 -27.94) (xy 388.065264 -27.974798) (xy 388.069074 -27.984196)
			(xy 388.085305 -28.024291) (xy 388.110785 -28.10696) (xy 388.128103 -28.191714) (xy 388.137098 -28.277751)
			(xy 388.137908 -28.321) (xy 388.137908 -28.321254) (xy 388.137422 -28.362349) (xy 388.129816 -28.444186)
			(xy 388.114694 -28.524973) (xy 388.092183 -28.60402) (xy 388.062475 -28.680654) (xy 388.025825 -28.75422)
			(xy 387.982545 -28.824091) (xy 387.933003 -28.889672) (xy 387.877623 -28.950403) (xy 387.816877 -29.005766)
			(xy 387.751282 -29.055289) (xy 387.681398 -29.098549) (xy 387.607821 -29.135178) (xy 387.531179 -29.164863)
			(xy 387.452126 -29.187352) (xy 387.371335 -29.202452) (xy 387.289862 -29.21) (xy 404.730202 -29.21)
			(xy 404.734273 -29.154378) (xy 404.746399 -29.099941) (xy 404.766322 -29.04785) (xy 404.793618 -28.999215)
			(xy 404.827704 -28.955072) (xy 404.867853 -28.916363) (xy 404.913211 -28.883912) (xy 404.962811 -28.858411)
			(xy 405.015595 -28.840404) (xy 405.070438 -28.830274) (xy 405.126172 -28.828237) (xy 405.181609 -28.834337)
			(xy 405.235566 -28.848443) (xy 405.286895 -28.870255) (xy 405.334501 -28.899309) (xy 405.377369 -28.934984)
			(xy 405.414586 -28.976521) (xy 405.445359 -29.023034) (xy 405.469031 -29.073531) (xy 405.485099 -29.126938)
			(xy 405.493219 -29.182114) (xy 405.493728 -29.21) (xy 409.599382 -29.21) (xy 409.603453 -29.154378)
			(xy 409.615579 -29.099941) (xy 409.635502 -29.04785) (xy 409.662798 -28.999215) (xy 409.696884 -28.955072)
			(xy 409.737033 -28.916363) (xy 409.782391 -28.883912) (xy 409.831991 -28.858411) (xy 409.884775 -28.840404)
			(xy 409.939618 -28.830274) (xy 409.995352 -28.828237) (xy 410.050789 -28.834337) (xy 410.104746 -28.848443)
			(xy 410.156075 -28.870255) (xy 410.203681 -28.899309) (xy 410.246549 -28.934984) (xy 410.283766 -28.976521)
			(xy 410.314539 -29.023034) (xy 410.338211 -29.073531) (xy 410.354279 -29.126938) (xy 410.362399 -29.182114)
			(xy 410.362908 -29.21) (xy 410.362399 -29.237886) (xy 410.354279 -29.293062) (xy 410.338211 -29.346469)
			(xy 410.314539 -29.396966) (xy 410.283766 -29.443479) (xy 410.246549 -29.485016) (xy 410.203681 -29.520691)
			(xy 410.156075 -29.549745) (xy 410.104746 -29.571557) (xy 410.050789 -29.585663) (xy 409.995352 -29.591763)
			(xy 409.939618 -29.589726) (xy 409.884775 -29.579596) (xy 409.831991 -29.561589) (xy 409.782391 -29.536088)
			(xy 409.737033 -29.503637) (xy 409.696884 -29.464928) (xy 409.662798 -29.420785) (xy 409.635502 -29.37215)
			(xy 409.615579 -29.320059) (xy 409.603453 -29.265622) (xy 409.599382 -29.21) (xy 405.493728 -29.21)
			(xy 405.493219 -29.237886) (xy 405.485099 -29.293062) (xy 405.469031 -29.346469) (xy 405.445359 -29.396966)
			(xy 405.414586 -29.443479) (xy 405.377369 -29.485016) (xy 405.334501 -29.520691) (xy 405.286895 -29.549745)
			(xy 405.235566 -29.571557) (xy 405.181609 -29.585663) (xy 405.126172 -29.591763) (xy 405.070438 -29.589726)
			(xy 405.015595 -29.579596) (xy 404.962811 -29.561589) (xy 404.913211 -29.536088) (xy 404.867853 -29.503637)
			(xy 404.827704 -29.464928) (xy 404.793618 -29.420785) (xy 404.766322 -29.37215) (xy 404.746399 -29.320059)
			(xy 404.734273 -29.265622) (xy 404.730202 -29.21) (xy 387.289862 -29.21) (xy 387.289495 -29.210034)
			(xy 387.2484 -29.210508) (xy 387.206052 -29.210004) (xy 387.121738 -29.201953) (xy 387.038572 -29.185924)
			(xy 386.957305 -29.162063) (xy 386.878675 -29.130584) (xy 386.803394 -29.091773) (xy 386.732142 -29.045983)
			(xy 386.665566 -28.993627) (xy 386.604268 -28.935179) (xy 386.548803 -28.871169) (xy 386.499674 -28.802177)
			(xy 386.457325 -28.728827) (xy 386.422141 -28.651784) (xy 386.394439 -28.571745) (xy 386.374471 -28.489436)
			(xy 386.362418 -28.405601) (xy 386.358388 -28.321) (xy 379.280847 -28.321) (xy 379.271281 -28.33899)
			(xy 379.23992 -28.382157) (xy 379.202857 -28.42054) (xy 379.182122 -28.437332) (xy 379.170274 -28.447183)
			(xy 379.152755 -28.472519) (xy 379.143583 -28.501924) (xy 379.143591 -28.532727) (xy 379.152778 -28.562128)
			(xy 379.17031 -28.587455) (xy 379.182122 -28.597352) (xy 379.204589 -28.615544) (xy 379.24426 -28.657594)
			(xy 379.277141 -28.705142) (xy 379.30248 -28.757102) (xy 379.3197 -28.812287) (xy 379.328405 -28.869437)
			(xy 379.328934 -28.898342) (xy 379.328515 -28.925614) (xy 379.320746 -28.979601) (xy 379.305374 -29.031934)
			(xy 379.282711 -29.081546) (xy 379.253218 -29.127428) (xy 379.217496 -29.168646) (xy 379.176272 -29.20436)
			(xy 379.130384 -29.233845) (xy 379.080768 -29.256499) (xy 379.028433 -29.271861) (xy 378.974444 -29.27962)
			(xy 378.947172 -29.280104) (xy 378.918268 -29.279604) (xy 378.861122 -29.270878) (xy 378.805943 -29.253644)
			(xy 378.753989 -29.228296) (xy 378.706445 -29.195411) (xy 378.664397 -29.155741) (xy 378.646182 -29.133292)
			(xy 378.636285 -29.121487) (xy 378.610961 -29.103968) (xy 378.581568 -29.094792) (xy 378.550776 -29.094792)
			(xy 378.521383 -29.103968) (xy 378.496059 -29.121487) (xy 378.486162 -29.133292) (xy 378.46937 -29.154025)
			(xy 378.430989 -29.191084) (xy 378.387824 -29.22244) (xy 378.340716 -29.247485) (xy 378.290581 -29.265731)
			(xy 378.238394 -29.276822) (xy 378.185172 -29.280544) (xy 378.13195 -29.276822) (xy 378.079763 -29.265731)
			(xy 378.029628 -29.247485) (xy 377.98252 -29.22244) (xy 377.939355 -29.191084) (xy 377.900974 -29.154025)
			(xy 377.884182 -29.133292) (xy 377.874285 -29.121487) (xy 377.848961 -29.103968) (xy 377.819568 -29.094792)
			(xy 377.788776 -29.094792) (xy 377.759383 -29.103968) (xy 377.734059 -29.121487) (xy 377.724162 -29.133292)
			(xy 377.70737 -29.154025) (xy 377.668989 -29.191084) (xy 377.625824 -29.22244) (xy 377.578716 -29.247485)
			(xy 377.528581 -29.265731) (xy 377.476394 -29.276822) (xy 377.423172 -29.280544) (xy 377.36995 -29.276822)
			(xy 377.317763 -29.265731) (xy 377.267628 -29.247485) (xy 377.22052 -29.22244) (xy 377.177355 -29.191084)
			(xy 377.138974 -29.154025) (xy 377.122182 -29.133292) (xy 377.112285 -29.121487) (xy 377.086961 -29.103968)
			(xy 377.057568 -29.094792) (xy 377.026776 -29.094792) (xy 376.997383 -29.103968) (xy 376.972059 -29.121487)
			(xy 376.962162 -29.133292) (xy 376.943954 -29.155746) (xy 376.901909 -29.195419) (xy 376.854365 -29.228302)
			(xy 376.802407 -29.253644) (xy 376.747224 -29.270866) (xy 376.690076 -29.279574) (xy 376.661172 -29.280104)
			(xy 376.633904 -29.279602) (xy 376.579923 -29.271837) (xy 376.527596 -29.256471) (xy 376.477989 -29.233814)
			(xy 376.43211 -29.204329) (xy 376.390894 -29.168616) (xy 376.355179 -29.127401) (xy 376.325693 -29.081523)
			(xy 376.303034 -29.031917) (xy 376.287666 -28.979591) (xy 376.279899 -28.92561) (xy 376.27941 -28.898342)
			(xy 376.279955 -28.86944) (xy 376.288671 -28.812296) (xy 376.305896 -28.757117) (xy 376.331236 -28.705162)
			(xy 376.364113 -28.657618) (xy 376.403776 -28.615568) (xy 376.426222 -28.597352) (xy 376.437982 -28.587407)
			(xy 376.455494 -28.562095) (xy 376.464671 -28.532715) (xy 376.464678 -28.501936) (xy 376.455517 -28.472552)
			(xy 376.438017 -28.447231) (xy 376.426222 -28.437332) (xy 376.405529 -28.420492) (xy 376.368469 -28.382117)
			(xy 376.33711 -28.338959) (xy 376.312062 -28.291856) (xy 376.293813 -28.241726) (xy 376.282718 -28.189544)
			(xy 376.278993 -28.136326) (xy 367.920254 -28.136326) (xy 369.916456 -30.132528) (xy 369.923854 -30.139374)
			(xy 369.942453 -30.147099) (xy 369.952524 -30.147514) (xy 403.483318 -30.147514) (xy 403.493386 -30.147941)
			(xy 403.511985 -30.155661) (xy 403.519386 -30.1625) (xy 403.836886 -30.48) (xy 409.599382 -30.48)
			(xy 409.603453 -30.424378) (xy 409.615579 -30.369941) (xy 409.635502 -30.31785) (xy 409.662798 -30.269215)
			(xy 409.696884 -30.225072) (xy 409.737033 -30.186363) (xy 409.782391 -30.153912) (xy 409.831991 -30.128411)
			(xy 409.884775 -30.110404) (xy 409.939618 -30.100274) (xy 409.995352 -30.098237) (xy 410.050789 -30.104337)
			(xy 410.104746 -30.118443) (xy 410.156075 -30.140255) (xy 410.203681 -30.169309) (xy 410.246549 -30.204984)
			(xy 410.283766 -30.246521) (xy 410.314539 -30.293034) (xy 410.338211 -30.343531) (xy 410.354279 -30.396938)
			(xy 410.362399 -30.452114) (xy 410.362908 -30.48) (xy 410.362399 -30.507886) (xy 410.354279 -30.563062)
			(xy 410.338211 -30.616469) (xy 410.314539 -30.666966) (xy 410.283766 -30.713479) (xy 410.246549 -30.755016)
			(xy 410.203681 -30.790691) (xy 410.156075 -30.819745) (xy 410.104746 -30.841557) (xy 410.050789 -30.855663)
			(xy 409.995352 -30.861763) (xy 409.939618 -30.859726) (xy 409.884775 -30.849596) (xy 409.831991 -30.831589)
			(xy 409.782391 -30.806088) (xy 409.737033 -30.773637) (xy 409.696884 -30.734928) (xy 409.662798 -30.690785)
			(xy 409.635502 -30.64215) (xy 409.615579 -30.590059) (xy 409.603453 -30.535622) (xy 409.599382 -30.48)
			(xy 403.836886 -30.48) (xy 404.901146 -31.54426) (xy 404.901146 -31.544006) (xy 405.180038 -31.822898)
			(xy 405.188667 -31.830553) (xy 405.210436 -31.838087) (xy 405.221948 -31.837376) (xy 405.294084 -31.82874)
			(xy 405.304498 -31.82493) (xy 405.30907 -31.822136) (xy 405.328374 -31.810452) (xy 405.332692 -31.806134)
			(xy 405.344884 -31.794196) (xy 405.35098 -31.78556) (xy 405.366303 -31.764324) (xy 405.401841 -31.725863)
			(xy 405.442316 -31.692637) (xy 405.486964 -31.665273) (xy 405.534942 -31.644289) (xy 405.585343 -31.63008)
			(xy 405.637217 -31.622915) (xy 405.6634 -31.622492) (xy 405.690651 -31.622978) (xy 405.744599 -31.630734)
			(xy 405.796894 -31.646089) (xy 405.846471 -31.668731) (xy 405.892321 -31.698197) (xy 405.933512 -31.733888)
			(xy 405.969203 -31.775079) (xy 405.998669 -31.820929) (xy 406.021311 -31.870506) (xy 406.036666 -31.922801)
			(xy 406.044422 -31.976749) (xy 406.044908 -32.004) (xy 406.044908 -32.004508) (xy 406.044654 -32.01035)
			(xy 406.0444 -32.012128) (xy 406.0444 -32.02432) (xy 406.044634 -32.030691) (xy 406.047853 -32.043024)
			(xy 406.05075 -32.048704) (xy 406.053544 -32.054038) (xy 406.061164 -32.064452) (xy 406.108662 -32.114998)
			(xy 406.116106 -32.122237) (xy 406.135122 -32.130521) (xy 406.145492 -32.131) (xy 410.341318 -32.131)
			(xy 410.349954 -32.130238) (xy 410.357472 -32.128636) (xy 410.37116 -32.121659) (xy 410.376878 -32.116522)
			(xy 411.729428 -30.763972) (xy 411.736825 -30.757122) (xy 411.755423 -30.749387) (xy 411.765496 -30.748986)
			(xy 412.129732 -30.748986) (xy 412.138368 -30.748224) (xy 412.145885 -30.74662) (xy 412.159568 -30.739639)
			(xy 412.165292 -30.734508) (xy 412.455614 -30.444186) (xy 412.462468 -30.436791) (xy 412.47021 -30.418192)
			(xy 412.4706 -30.408118) (xy 412.4706 -28.763722) (xy 412.46298 -28.744926) (xy 412.455614 -28.737814)
			(xy 411.774386 -28.056586) (xy 411.767532 -28.049191) (xy 411.75979 -28.030592) (xy 411.7594 -28.020518)
			(xy 411.7594 -26.106882) (xy 411.759827 -26.096813) (xy 411.767546 -26.078214) (xy 411.774386 -26.070814)
			(xy 413.166814 -24.678386) (xy 413.174209 -24.671532) (xy 413.192808 -24.66379) (xy 413.202882 -24.6634)
			(xy 418.75837 -24.6634) (xy 418.767289 -24.663003) (xy 418.78405 -24.656894) (xy 418.791136 -24.651462)
			(xy 418.823176 -24.625159) (xy 418.89133 -24.577961) (xy 418.96358 -24.537309) (xy 419.0393 -24.503556)
			(xy 419.117831 -24.476996) (xy 419.198493 -24.457857) (xy 419.280586 -24.446308) (xy 419.363398 -24.442447)
			(xy 419.44621 -24.446308) (xy 419.528303 -24.457857) (xy 419.608965 -24.476996) (xy 419.687496 -24.503556)
			(xy 419.763216 -24.537309) (xy 419.835466 -24.577961) (xy 419.90362 -24.625159) (xy 419.93566 -24.651462)
			(xy 419.94271 -24.656956) (xy 419.959494 -24.66307) (xy 419.968426 -24.6634) (xy 422.914318 -24.6634)
			(xy 422.924387 -24.663827) (xy 422.942986 -24.671546) (xy 422.950386 -24.678386) (xy 424.815 -26.543)
			(xy 438.326782 -26.543) (xy 438.330853 -26.487378) (xy 438.342979 -26.432941) (xy 438.362902 -26.38085)
			(xy 438.390198 -26.332215) (xy 438.424284 -26.288072) (xy 438.464433 -26.249363) (xy 438.509791 -26.216912)
			(xy 438.559391 -26.191411) (xy 438.612175 -26.173404) (xy 438.667018 -26.163274) (xy 438.722752 -26.161237)
			(xy 438.778189 -26.167337) (xy 438.832146 -26.181443) (xy 438.883475 -26.203255) (xy 438.931081 -26.232309)
			(xy 438.973949 -26.267984) (xy 439.011166 -26.309521) (xy 439.041939 -26.356034) (xy 439.065611 -26.406531)
			(xy 439.081679 -26.459938) (xy 439.089799 -26.515114) (xy 439.090308 -26.543) (xy 439.089799 -26.570886)
			(xy 439.081679 -26.626062) (xy 439.065611 -26.679469) (xy 439.041939 -26.729966) (xy 439.011166 -26.776479)
			(xy 438.973949 -26.818016) (xy 438.931081 -26.853691) (xy 438.883475 -26.882745) (xy 438.832146 -26.904557)
			(xy 438.778189 -26.918663) (xy 438.722752 -26.924763) (xy 438.667018 -26.922726) (xy 438.612175 -26.912596)
			(xy 438.559391 -26.894589) (xy 438.509791 -26.869088) (xy 438.464433 -26.836637) (xy 438.424284 -26.797928)
			(xy 438.390198 -26.753785) (xy 438.362902 -26.70515) (xy 438.342979 -26.653059) (xy 438.330853 -26.598622)
			(xy 438.326782 -26.543) (xy 424.815 -26.543) (xy 425.454064 -27.182064) (xy 436.263032 -27.182064)
			(xy 436.267103 -27.126442) (xy 436.279229 -27.072005) (xy 436.299152 -27.019914) (xy 436.326448 -26.971279)
			(xy 436.360534 -26.927136) (xy 436.400683 -26.888427) (xy 436.446041 -26.855976) (xy 436.495641 -26.830475)
			(xy 436.548425 -26.812468) (xy 436.603268 -26.802338) (xy 436.659002 -26.800301) (xy 436.714439 -26.806401)
			(xy 436.768396 -26.820507) (xy 436.819725 -26.842319) (xy 436.867331 -26.871373) (xy 436.910199 -26.907048)
			(xy 436.947416 -26.948585) (xy 436.978189 -26.995098) (xy 437.001861 -27.045595) (xy 437.017929 -27.099002)
			(xy 437.026049 -27.154178) (xy 437.026484 -27.178) (xy 447.673728 -27.178) (xy 447.677801 -27.122341)
			(xy 447.689936 -27.067868) (xy 447.709872 -27.015742) (xy 447.737186 -26.967074) (xy 447.771294 -26.922902)
			(xy 447.811471 -26.884167) (xy 447.856859 -26.851695) (xy 447.906491 -26.826177) (xy 447.959311 -26.808158)
			(xy 448.01419 -26.798021) (xy 448.069961 -26.795983) (xy 448.125435 -26.802086) (xy 448.179428 -26.816202)
			(xy 448.230791 -26.838029) (xy 448.278429 -26.867102) (xy 448.321325 -26.902801) (xy 448.358567 -26.944365)
			(xy 448.389361 -26.990909) (xy 448.413049 -27.04144) (xy 448.429127 -27.094882) (xy 448.437253 -27.150096)
			(xy 448.437762 -27.178) (xy 448.543932 -27.178) (xy 448.548003 -27.122378) (xy 448.560129 -27.067941)
			(xy 448.580052 -27.01585) (xy 448.607348 -26.967215) (xy 448.641434 -26.923072) (xy 448.681583 -26.884363)
			(xy 448.726941 -26.851912) (xy 448.776541 -26.826411) (xy 448.829325 -26.808404) (xy 448.884168 -26.798274)
			(xy 448.939902 -26.796237) (xy 448.995339 -26.802337) (xy 449.049296 -26.816443) (xy 449.100625 -26.838255)
			(xy 449.148231 -26.867309) (xy 449.191099 -26.902984) (xy 449.228316 -26.944521) (xy 449.259089 -26.991034)
			(xy 449.282761 -27.041531) (xy 449.298829 -27.094938) (xy 449.306949 -27.150114) (xy 449.307458 -27.178)
			(xy 449.306949 -27.205886) (xy 449.298829 -27.261062) (xy 449.282761 -27.314469) (xy 449.259089 -27.364966)
			(xy 449.228316 -27.411479) (xy 449.191099 -27.453016) (xy 449.148231 -27.488691) (xy 449.100625 -27.517745)
			(xy 449.049296 -27.539557) (xy 448.995339 -27.553663) (xy 448.939902 -27.559763) (xy 448.884168 -27.557726)
			(xy 448.829325 -27.547596) (xy 448.776541 -27.529589) (xy 448.726941 -27.504088) (xy 448.681583 -27.471637)
			(xy 448.641434 -27.432928) (xy 448.607348 -27.388785) (xy 448.580052 -27.34015) (xy 448.560129 -27.288059)
			(xy 448.548003 -27.233622) (xy 448.543932 -27.178) (xy 448.437762 -27.178) (xy 448.437253 -27.205904)
			(xy 448.429127 -27.261118) (xy 448.413049 -27.31456) (xy 448.389361 -27.365091) (xy 448.358567 -27.411635)
			(xy 448.321325 -27.453199) (xy 448.278429 -27.488898) (xy 448.230791 -27.517971) (xy 448.179428 -27.539798)
			(xy 448.125435 -27.553914) (xy 448.069961 -27.560017) (xy 448.01419 -27.557979) (xy 447.959311 -27.547842)
			(xy 447.906491 -27.529823) (xy 447.856859 -27.504305) (xy 447.811471 -27.471833) (xy 447.771294 -27.433098)
			(xy 447.737186 -27.388926) (xy 447.709872 -27.340258) (xy 447.689936 -27.288132) (xy 447.677801 -27.233659)
			(xy 447.673728 -27.178) (xy 437.026484 -27.178) (xy 437.026558 -27.182064) (xy 437.026049 -27.20995)
			(xy 437.017929 -27.265126) (xy 437.001861 -27.318533) (xy 436.978189 -27.36903) (xy 436.947416 -27.415543)
			(xy 436.910199 -27.45708) (xy 436.867331 -27.492755) (xy 436.819725 -27.521809) (xy 436.768396 -27.543621)
			(xy 436.714439 -27.557727) (xy 436.659002 -27.563827) (xy 436.603268 -27.56179) (xy 436.548425 -27.55166)
			(xy 436.495641 -27.533653) (xy 436.446041 -27.508152) (xy 436.400683 -27.475701) (xy 436.360534 -27.436992)
			(xy 436.326448 -27.392849) (xy 436.299152 -27.344214) (xy 436.279229 -27.292123) (xy 436.267103 -27.237686)
			(xy 436.263032 -27.182064) (xy 425.454064 -27.182064) (xy 426.72 -28.448) (xy 436.263032 -28.448)
			(xy 436.267103 -28.392378) (xy 436.279229 -28.337941) (xy 436.299152 -28.28585) (xy 436.326448 -28.237215)
			(xy 436.360534 -28.193072) (xy 436.400683 -28.154363) (xy 436.446041 -28.121912) (xy 436.495641 -28.096411)
			(xy 436.548425 -28.078404) (xy 436.603268 -28.068274) (xy 436.659002 -28.066237) (xy 436.714439 -28.072337)
			(xy 436.768396 -28.086443) (xy 436.819725 -28.108255) (xy 436.867331 -28.137309) (xy 436.910199 -28.172984)
			(xy 436.947416 -28.214521) (xy 436.978189 -28.261034) (xy 437.001861 -28.311531) (xy 437.017929 -28.364938)
			(xy 437.026049 -28.420114) (xy 437.026558 -28.448) (xy 437.026049 -28.475886) (xy 437.017929 -28.531062)
			(xy 437.001861 -28.584469) (xy 436.978189 -28.634966) (xy 436.947416 -28.681479) (xy 436.910199 -28.723016)
			(xy 436.867331 -28.758691) (xy 436.819725 -28.787745) (xy 436.768396 -28.809557) (xy 436.714439 -28.823663)
			(xy 436.659002 -28.829763) (xy 436.603268 -28.827726) (xy 436.548425 -28.817596) (xy 436.495641 -28.799589)
			(xy 436.446041 -28.774088) (xy 436.400683 -28.741637) (xy 436.360534 -28.702928) (xy 436.326448 -28.658785)
			(xy 436.299152 -28.61015) (xy 436.279229 -28.558059) (xy 436.267103 -28.503622) (xy 436.263032 -28.448)
			(xy 426.72 -28.448) (xy 426.793914 -28.521914) (xy 426.800768 -28.529309) (xy 426.80851 -28.547908)
			(xy 426.8089 -28.557982) (xy 426.8089 -29.0195) (xy 431.760882 -29.0195) (xy 431.764953 -28.963878)
			(xy 431.777079 -28.909441) (xy 431.797002 -28.85735) (xy 431.824298 -28.808715) (xy 431.858384 -28.764572)
			(xy 431.898533 -28.725863) (xy 431.943891 -28.693412) (xy 431.993491 -28.667911) (xy 432.046275 -28.649904)
			(xy 432.101118 -28.639774) (xy 432.156852 -28.637737) (xy 432.212289 -28.643837) (xy 432.266246 -28.657943)
			(xy 432.317575 -28.679755) (xy 432.365181 -28.708809) (xy 432.408049 -28.744484) (xy 432.445266 -28.786021)
			(xy 432.476039 -28.832534) (xy 432.499711 -28.883031) (xy 432.515779 -28.936438) (xy 432.523899 -28.991614)
			(xy 432.524408 -29.0195) (xy 432.523899 -29.047386) (xy 432.518658 -29.083) (xy 446.556382 -29.083)
			(xy 446.560453 -29.027378) (xy 446.572579 -28.972941) (xy 446.592502 -28.92085) (xy 446.619798 -28.872215)
			(xy 446.653884 -28.828072) (xy 446.694033 -28.789363) (xy 446.739391 -28.756912) (xy 446.788991 -28.731411)
			(xy 446.841775 -28.713404) (xy 446.896618 -28.703274) (xy 446.952352 -28.701237) (xy 446.959286 -28.702)
			(xy 447.546728 -28.702) (xy 447.550801 -28.646341) (xy 447.562936 -28.591868) (xy 447.582872 -28.539742)
			(xy 447.610186 -28.491074) (xy 447.644294 -28.446902) (xy 447.684471 -28.408167) (xy 447.729859 -28.375695)
			(xy 447.779491 -28.350177) (xy 447.832311 -28.332158) (xy 447.88719 -28.322021) (xy 447.942961 -28.319983)
			(xy 447.998435 -28.326086) (xy 448.052428 -28.340202) (xy 448.103791 -28.362029) (xy 448.151429 -28.391102)
			(xy 448.194325 -28.426801) (xy 448.231567 -28.468365) (xy 448.262361 -28.514909) (xy 448.286049 -28.56544)
			(xy 448.302127 -28.618882) (xy 448.310253 -28.674096) (xy 448.310762 -28.702) (xy 448.310253 -28.729904)
			(xy 448.302127 -28.785118) (xy 448.286049 -28.83856) (xy 448.262361 -28.889091) (xy 448.231567 -28.935635)
			(xy 448.209678 -28.960064) (xy 448.569332 -28.960064) (xy 448.573403 -28.904442) (xy 448.585529 -28.850005)
			(xy 448.605452 -28.797914) (xy 448.632748 -28.749279) (xy 448.666834 -28.705136) (xy 448.706983 -28.666427)
			(xy 448.752341 -28.633976) (xy 448.801941 -28.608475) (xy 448.854725 -28.590468) (xy 448.909568 -28.580338)
			(xy 448.965302 -28.578301) (xy 449.020739 -28.584401) (xy 449.074696 -28.598507) (xy 449.126025 -28.620319)
			(xy 449.173631 -28.649373) (xy 449.216499 -28.685048) (xy 449.253716 -28.726585) (xy 449.284489 -28.773098)
			(xy 449.308161 -28.823595) (xy 449.324229 -28.877002) (xy 449.332349 -28.932178) (xy 449.332858 -28.960064)
			(xy 449.332349 -28.98795) (xy 449.324229 -29.043126) (xy 449.308161 -29.096533) (xy 449.284489 -29.14703)
			(xy 449.253716 -29.193543) (xy 449.216499 -29.23508) (xy 449.173631 -29.270755) (xy 449.126025 -29.299809)
			(xy 449.074696 -29.321621) (xy 449.020739 -29.335727) (xy 448.965302 -29.341827) (xy 448.909568 -29.33979)
			(xy 448.854725 -29.32966) (xy 448.801941 -29.311653) (xy 448.752341 -29.286152) (xy 448.706983 -29.253701)
			(xy 448.666834 -29.214992) (xy 448.632748 -29.170849) (xy 448.605452 -29.122214) (xy 448.585529 -29.070123)
			(xy 448.573403 -29.015686) (xy 448.569332 -28.960064) (xy 448.209678 -28.960064) (xy 448.194325 -28.977199)
			(xy 448.151429 -29.012898) (xy 448.103791 -29.041971) (xy 448.052428 -29.063798) (xy 447.998435 -29.077914)
			(xy 447.942961 -29.084017) (xy 447.88719 -29.081979) (xy 447.832311 -29.071842) (xy 447.779491 -29.053823)
			(xy 447.729859 -29.028305) (xy 447.684471 -28.995833) (xy 447.644294 -28.957098) (xy 447.610186 -28.912926)
			(xy 447.582872 -28.864258) (xy 447.562936 -28.812132) (xy 447.550801 -28.757659) (xy 447.546728 -28.702)
			(xy 446.959286 -28.702) (xy 447.007789 -28.707337) (xy 447.061746 -28.721443) (xy 447.113075 -28.743255)
			(xy 447.160681 -28.772309) (xy 447.203549 -28.807984) (xy 447.240766 -28.849521) (xy 447.271539 -28.896034)
			(xy 447.295211 -28.946531) (xy 447.311279 -28.999938) (xy 447.319399 -29.055114) (xy 447.319908 -29.083)
			(xy 447.319399 -29.110886) (xy 447.311279 -29.166062) (xy 447.295211 -29.219469) (xy 447.271539 -29.269966)
			(xy 447.240766 -29.316479) (xy 447.203549 -29.358016) (xy 447.160681 -29.393691) (xy 447.113075 -29.422745)
			(xy 447.061746 -29.444557) (xy 447.007789 -29.458663) (xy 446.952352 -29.464763) (xy 446.896618 -29.462726)
			(xy 446.841775 -29.452596) (xy 446.788991 -29.434589) (xy 446.739391 -29.409088) (xy 446.694033 -29.376637)
			(xy 446.653884 -29.337928) (xy 446.619798 -29.293785) (xy 446.592502 -29.24515) (xy 446.572579 -29.193059)
			(xy 446.560453 -29.138622) (xy 446.556382 -29.083) (xy 432.518658 -29.083) (xy 432.515779 -29.102562)
			(xy 432.499711 -29.155969) (xy 432.476039 -29.206466) (xy 432.445266 -29.252979) (xy 432.408049 -29.294516)
			(xy 432.365181 -29.330191) (xy 432.317575 -29.359245) (xy 432.266246 -29.381057) (xy 432.212289 -29.395163)
			(xy 432.156852 -29.401263) (xy 432.101118 -29.399226) (xy 432.046275 -29.389096) (xy 431.993491 -29.371089)
			(xy 431.943891 -29.345588) (xy 431.898533 -29.313137) (xy 431.858384 -29.274428) (xy 431.824298 -29.230285)
			(xy 431.797002 -29.18165) (xy 431.777079 -29.129559) (xy 431.764953 -29.075122) (xy 431.760882 -29.0195)
			(xy 426.8089 -29.0195) (xy 426.8089 -30.226) (xy 430.554382 -30.226) (xy 430.558453 -30.170378) (xy 430.570579 -30.115941)
			(xy 430.590502 -30.06385) (xy 430.617798 -30.015215) (xy 430.651884 -29.971072) (xy 430.692033 -29.932363)
			(xy 430.737391 -29.899912) (xy 430.786991 -29.874411) (xy 430.839775 -29.856404) (xy 430.894618 -29.846274)
			(xy 430.950352 -29.844237) (xy 431.005789 -29.850337) (xy 431.059746 -29.864443) (xy 431.111075 -29.886255)
			(xy 431.158681 -29.915309) (xy 431.201549 -29.950984) (xy 431.238766 -29.992521) (xy 431.269539 -30.039034)
			(xy 431.293211 -30.089531) (xy 431.309279 -30.142938) (xy 431.317399 -30.198114) (xy 431.317908 -30.226)
			(xy 431.317399 -30.253886) (xy 431.309279 -30.309062) (xy 431.29606 -30.353) (xy 447.699382 -30.353)
			(xy 447.703453 -30.297378) (xy 447.715579 -30.242941) (xy 447.735502 -30.19085) (xy 447.762798 -30.142215)
			(xy 447.796884 -30.098072) (xy 447.837033 -30.059363) (xy 447.882391 -30.026912) (xy 447.931991 -30.001411)
			(xy 447.984775 -29.983404) (xy 448.039618 -29.973274) (xy 448.095352 -29.971237) (xy 448.150789 -29.977337)
			(xy 448.204746 -29.991443) (xy 448.256075 -30.013255) (xy 448.303681 -30.042309) (xy 448.346549 -30.077984)
			(xy 448.383766 -30.119521) (xy 448.414539 -30.166034) (xy 448.438211 -30.216531) (xy 448.454279 -30.269938)
			(xy 448.462399 -30.325114) (xy 448.462908 -30.353) (xy 448.462399 -30.380886) (xy 448.454279 -30.436062)
			(xy 448.438211 -30.489469) (xy 448.414539 -30.539966) (xy 448.383766 -30.586479) (xy 448.346549 -30.628016)
			(xy 448.303681 -30.663691) (xy 448.256075 -30.692745) (xy 448.204746 -30.714557) (xy 448.150789 -30.728663)
			(xy 448.102286 -30.734) (xy 450.086728 -30.734) (xy 450.090801 -30.678341) (xy 450.102936 -30.623868)
			(xy 450.122872 -30.571742) (xy 450.150186 -30.523074) (xy 450.184294 -30.478902) (xy 450.224471 -30.440167)
			(xy 450.269859 -30.407695) (xy 450.319491 -30.382177) (xy 450.372311 -30.364158) (xy 450.42719 -30.354021)
			(xy 450.482961 -30.351983) (xy 450.538435 -30.358086) (xy 450.592428 -30.372202) (xy 450.643791 -30.394029)
			(xy 450.691429 -30.423102) (xy 450.734325 -30.458801) (xy 450.771567 -30.500365) (xy 450.802361 -30.546909)
			(xy 450.826049 -30.59744) (xy 450.842127 -30.650882) (xy 450.850253 -30.706096) (xy 450.850762 -30.734)
			(xy 450.850253 -30.761904) (xy 450.842127 -30.817118) (xy 450.826049 -30.87056) (xy 450.802361 -30.921091)
			(xy 450.771567 -30.967635) (xy 450.734325 -31.009199) (xy 450.691429 -31.044898) (xy 450.643791 -31.073971)
			(xy 450.592428 -31.095798) (xy 450.538435 -31.109914) (xy 450.482961 -31.116017) (xy 450.42719 -31.113979)
			(xy 450.372311 -31.103842) (xy 450.319491 -31.085823) (xy 450.269859 -31.060305) (xy 450.224471 -31.027833)
			(xy 450.184294 -30.989098) (xy 450.150186 -30.944926) (xy 450.122872 -30.896258) (xy 450.102936 -30.844132)
			(xy 450.090801 -30.789659) (xy 450.086728 -30.734) (xy 448.102286 -30.734) (xy 448.095352 -30.734763)
			(xy 448.039618 -30.732726) (xy 447.984775 -30.722596) (xy 447.931991 -30.704589) (xy 447.882391 -30.679088)
			(xy 447.837033 -30.646637) (xy 447.796884 -30.607928) (xy 447.762798 -30.563785) (xy 447.735502 -30.51515)
			(xy 447.715579 -30.463059) (xy 447.703453 -30.408622) (xy 447.699382 -30.353) (xy 431.29606 -30.353)
			(xy 431.293211 -30.362469) (xy 431.269539 -30.412966) (xy 431.238766 -30.459479) (xy 431.201549 -30.501016)
			(xy 431.158681 -30.536691) (xy 431.111075 -30.565745) (xy 431.059746 -30.587557) (xy 431.005789 -30.601663)
			(xy 430.950352 -30.607763) (xy 430.894618 -30.605726) (xy 430.839775 -30.595596) (xy 430.786991 -30.577589)
			(xy 430.737391 -30.552088) (xy 430.692033 -30.519637) (xy 430.651884 -30.480928) (xy 430.617798 -30.436785)
			(xy 430.590502 -30.38815) (xy 430.570579 -30.336059) (xy 430.558453 -30.281622) (xy 430.554382 -30.226)
			(xy 426.8089 -30.226) (xy 426.8089 -31.623) (xy 441.069982 -31.623) (xy 441.074053 -31.567378) (xy 441.086179 -31.512941)
			(xy 441.106102 -31.46085) (xy 441.133398 -31.412215) (xy 441.167484 -31.368072) (xy 441.207633 -31.329363)
			(xy 441.252991 -31.296912) (xy 441.302591 -31.271411) (xy 441.355375 -31.253404) (xy 441.410218 -31.243274)
			(xy 441.465952 -31.241237) (xy 441.521389 -31.247337) (xy 441.575346 -31.261443) (xy 441.626675 -31.283255)
			(xy 441.674281 -31.312309) (xy 441.717149 -31.347984) (xy 441.754366 -31.389521) (xy 441.785139 -31.436034)
			(xy 441.808811 -31.486531) (xy 441.824879 -31.539938) (xy 441.832999 -31.595114) (xy 441.833508 -31.623)
			(xy 441.833397 -31.629096) (xy 447.064382 -31.629096) (xy 447.068453 -31.573474) (xy 447.080579 -31.519037)
			(xy 447.100502 -31.466946) (xy 447.127798 -31.418311) (xy 447.161884 -31.374168) (xy 447.202033 -31.335459)
			(xy 447.247391 -31.303008) (xy 447.296991 -31.277507) (xy 447.349775 -31.2595) (xy 447.404618 -31.24937)
			(xy 447.460352 -31.247333) (xy 447.515789 -31.253433) (xy 447.569746 -31.267539) (xy 447.621075 -31.289351)
			(xy 447.668681 -31.318405) (xy 447.711549 -31.35408) (xy 447.748766 -31.395617) (xy 447.779539 -31.44213)
			(xy 447.803211 -31.492627) (xy 447.819279 -31.546034) (xy 447.827399 -31.60121) (xy 447.827797 -31.623)
			(xy 449.953632 -31.623) (xy 449.957703 -31.567378) (xy 449.969829 -31.512941) (xy 449.989752 -31.46085)
			(xy 450.017048 -31.412215) (xy 450.051134 -31.368072) (xy 450.091283 -31.329363) (xy 450.136641 -31.296912)
			(xy 450.186241 -31.271411) (xy 450.239025 -31.253404) (xy 450.293868 -31.243274) (xy 450.349602 -31.241237)
			(xy 450.405039 -31.247337) (xy 450.458996 -31.261443) (xy 450.510325 -31.283255) (xy 450.557931 -31.312309)
			(xy 450.600799 -31.347984) (xy 450.638016 -31.389521) (xy 450.668789 -31.436034) (xy 450.692461 -31.486531)
			(xy 450.708529 -31.539938) (xy 450.716649 -31.595114) (xy 450.717158 -31.623) (xy 450.716649 -31.650886)
			(xy 450.708529 -31.706062) (xy 450.692461 -31.759469) (xy 450.668789 -31.809966) (xy 450.638016 -31.856479)
			(xy 450.600799 -31.898016) (xy 450.557931 -31.933691) (xy 450.510325 -31.962745) (xy 450.458996 -31.984557)
			(xy 450.405039 -31.998663) (xy 450.349602 -32.004763) (xy 450.293868 -32.002726) (xy 450.239025 -31.992596)
			(xy 450.186241 -31.974589) (xy 450.136641 -31.949088) (xy 450.091283 -31.916637) (xy 450.051134 -31.877928)
			(xy 450.017048 -31.833785) (xy 449.989752 -31.78515) (xy 449.969829 -31.733059) (xy 449.957703 -31.678622)
			(xy 449.953632 -31.623) (xy 447.827797 -31.623) (xy 447.827908 -31.629096) (xy 447.827399 -31.656982)
			(xy 447.819279 -31.712158) (xy 447.803211 -31.765565) (xy 447.779539 -31.816062) (xy 447.748766 -31.862575)
			(xy 447.711549 -31.904112) (xy 447.668681 -31.939787) (xy 447.621075 -31.968841) (xy 447.569746 -31.990653)
			(xy 447.515789 -32.004759) (xy 447.460352 -32.010859) (xy 447.404618 -32.008822) (xy 447.349775 -31.998692)
			(xy 447.296991 -31.980685) (xy 447.247391 -31.955184) (xy 447.202033 -31.922733) (xy 447.161884 -31.884024)
			(xy 447.127798 -31.839881) (xy 447.100502 -31.791246) (xy 447.080579 -31.739155) (xy 447.068453 -31.684718)
			(xy 447.064382 -31.629096) (xy 441.833397 -31.629096) (xy 441.832999 -31.650886) (xy 441.824879 -31.706062)
			(xy 441.808811 -31.759469) (xy 441.785139 -31.809966) (xy 441.754366 -31.856479) (xy 441.717149 -31.898016)
			(xy 441.674281 -31.933691) (xy 441.626675 -31.962745) (xy 441.575346 -31.984557) (xy 441.521389 -31.998663)
			(xy 441.465952 -32.004763) (xy 441.410218 -32.002726) (xy 441.355375 -31.992596) (xy 441.302591 -31.974589)
			(xy 441.252991 -31.949088) (xy 441.207633 -31.916637) (xy 441.167484 -31.877928) (xy 441.133398 -31.833785)
			(xy 441.106102 -31.78515) (xy 441.086179 -31.733059) (xy 441.074053 -31.678622) (xy 441.069982 -31.623)
			(xy 426.8089 -31.623) (xy 426.8089 -32.385) (xy 427.633128 -32.385) (xy 427.637201 -32.329341) (xy 427.649336 -32.274868)
			(xy 427.669272 -32.222742) (xy 427.696586 -32.174074) (xy 427.730694 -32.129902) (xy 427.770871 -32.091167)
			(xy 427.816259 -32.058695) (xy 427.865891 -32.033177) (xy 427.918711 -32.015158) (xy 427.97359 -32.005021)
			(xy 428.029361 -32.002983) (xy 428.084835 -32.009086) (xy 428.138828 -32.023202) (xy 428.190191 -32.045029)
			(xy 428.237829 -32.074102) (xy 428.280725 -32.109801) (xy 428.317967 -32.151365) (xy 428.348761 -32.197909)
			(xy 428.372449 -32.24844) (xy 428.388527 -32.301882) (xy 428.396653 -32.357096) (xy 428.397162 -32.385)
			(xy 428.396653 -32.412904) (xy 428.388527 -32.468118) (xy 428.372449 -32.52156) (xy 428.348761 -32.572091)
			(xy 428.317967 -32.618635) (xy 428.280725 -32.660199) (xy 428.237829 -32.695898) (xy 428.190191 -32.724971)
			(xy 428.138828 -32.746798) (xy 428.084835 -32.760914) (xy 428.029361 -32.767017) (xy 427.97359 -32.764979)
			(xy 427.918711 -32.754842) (xy 427.865891 -32.736823) (xy 427.816259 -32.711305) (xy 427.770871 -32.678833)
			(xy 427.730694 -32.640098) (xy 427.696586 -32.595926) (xy 427.669272 -32.547258) (xy 427.649336 -32.495132)
			(xy 427.637201 -32.440659) (xy 427.633128 -32.385) (xy 426.8089 -32.385) (xy 426.8089 -32.893) (xy 432.059332 -32.893)
			(xy 432.063403 -32.837378) (xy 432.075529 -32.782941) (xy 432.095452 -32.73085) (xy 432.122748 -32.682215)
			(xy 432.156834 -32.638072) (xy 432.196983 -32.599363) (xy 432.242341 -32.566912) (xy 432.291941 -32.541411)
			(xy 432.344725 -32.523404) (xy 432.399568 -32.513274) (xy 432.455302 -32.511237) (xy 432.510739 -32.517337)
			(xy 432.564696 -32.531443) (xy 432.616025 -32.553255) (xy 432.663631 -32.582309) (xy 432.706499 -32.617984)
			(xy 432.743716 -32.659521) (xy 432.774489 -32.706034) (xy 432.798161 -32.756531) (xy 432.814229 -32.809938)
			(xy 432.822349 -32.865114) (xy 432.822858 -32.893) (xy 450.086728 -32.893) (xy 450.090801 -32.837341)
			(xy 450.102936 -32.782868) (xy 450.122872 -32.730742) (xy 450.150186 -32.682074) (xy 450.184294 -32.637902)
			(xy 450.224471 -32.599167) (xy 450.269859 -32.566695) (xy 450.319491 -32.541177) (xy 450.372311 -32.523158)
			(xy 450.42719 -32.513021) (xy 450.482961 -32.510983) (xy 450.538435 -32.517086) (xy 450.592428 -32.531202)
			(xy 450.643791 -32.553029) (xy 450.691429 -32.582102) (xy 450.734325 -32.617801) (xy 450.771567 -32.659365)
			(xy 450.802361 -32.705909) (xy 450.826049 -32.75644) (xy 450.842127 -32.809882) (xy 450.850253 -32.865096)
			(xy 450.850762 -32.893) (xy 450.850253 -32.920904) (xy 450.842127 -32.976118) (xy 450.826049 -33.02956)
			(xy 450.802361 -33.080091) (xy 450.771567 -33.126635) (xy 450.734325 -33.168199) (xy 450.691429 -33.203898)
			(xy 450.643791 -33.232971) (xy 450.592428 -33.254798) (xy 450.538435 -33.268914) (xy 450.482961 -33.275017)
			(xy 450.42719 -33.272979) (xy 450.372311 -33.262842) (xy 450.319491 -33.244823) (xy 450.269859 -33.219305)
			(xy 450.224471 -33.186833) (xy 450.184294 -33.148098) (xy 450.150186 -33.103926) (xy 450.122872 -33.055258)
			(xy 450.102936 -33.003132) (xy 450.090801 -32.948659) (xy 450.086728 -32.893) (xy 432.822858 -32.893)
			(xy 432.822349 -32.920886) (xy 432.814229 -32.976062) (xy 432.798161 -33.029469) (xy 432.774489 -33.079966)
			(xy 432.743716 -33.126479) (xy 432.706499 -33.168016) (xy 432.663631 -33.203691) (xy 432.616025 -33.232745)
			(xy 432.564696 -33.254557) (xy 432.510739 -33.268663) (xy 432.455302 -33.274763) (xy 432.399568 -33.272726)
			(xy 432.344725 -33.262596) (xy 432.291941 -33.244589) (xy 432.242341 -33.219088) (xy 432.196983 -33.186637)
			(xy 432.156834 -33.147928) (xy 432.122748 -33.103785) (xy 432.095452 -33.05515) (xy 432.075529 -33.003059)
			(xy 432.063403 -32.948622) (xy 432.059332 -32.893) (xy 426.8089 -32.893) (xy 426.8089 -33.801558)
			(xy 427.609 -33.801558) (xy 427.609 -33.762442) (xy 427.61102 -33.733508) (xy 427.622727 -33.676701)
			(xy 427.642898 -33.622322) (xy 427.671067 -33.571622) (xy 427.706586 -33.52577) (xy 427.748637 -33.485823)
			(xy 427.796249 -33.452701) (xy 427.848326 -33.427168) (xy 427.903668 -33.409812) (xy 427.961 -33.401033)
			(xy 427.99 -33.400492) (xy 428.017251 -33.400978) (xy 428.071199 -33.408734) (xy 428.123494 -33.424089)
			(xy 428.173071 -33.446731) (xy 428.218921 -33.476197) (xy 428.260112 -33.511888) (xy 428.295803 -33.553079)
			(xy 428.325269 -33.598929) (xy 428.347911 -33.648506) (xy 428.363266 -33.700801) (xy 428.371022 -33.754749)
			(xy 428.371022 -33.809251) (xy 428.363266 -33.863199) (xy 428.347911 -33.915494) (xy 428.325269 -33.965071)
			(xy 428.295803 -34.010921) (xy 428.260112 -34.052112) (xy 428.218921 -34.087803) (xy 428.173071 -34.117269)
			(xy 428.123494 -34.139911) (xy 428.071199 -34.155266) (xy 428.017251 -34.163022) (xy 427.99 -34.163508)
			(xy 427.961001 -34.162961) (xy 427.90367 -34.154182) (xy 427.848329 -34.136826) (xy 427.796252 -34.111293)
			(xy 427.748641 -34.078172) (xy 427.706591 -34.038226) (xy 427.671072 -33.992375) (xy 427.642904 -33.941676)
			(xy 427.622733 -33.887297) (xy 427.611027 -33.830492) (xy 427.609 -33.801558) (xy 426.8089 -33.801558)
			(xy 426.8089 -34.557208) (xy 429.5394 -34.557208) (xy 429.5394 -34.518092) (xy 429.541464 -34.489161)
			(xy 429.553164 -34.432356) (xy 429.573328 -34.377977) (xy 429.601491 -34.327277) (xy 429.637005 -34.281424)
			(xy 429.679051 -34.241476) (xy 429.726659 -34.208353) (xy 429.778733 -34.182819) (xy 429.834072 -34.165462)
			(xy 429.891401 -34.156683) (xy 429.9204 -34.156142) (xy 429.947655 -34.156528) (xy 430.00161 -34.164285)
			(xy 430.053911 -34.179643) (xy 430.103495 -34.202287) (xy 430.149351 -34.231757) (xy 430.190547 -34.267453)
			(xy 430.226243 -34.308649) (xy 430.255713 -34.354505) (xy 430.278357 -34.404089) (xy 430.293715 -34.45639)
			(xy 430.301472 -34.510345) (xy 430.301472 -34.564855) (xy 430.293715 -34.61881) (xy 430.278357 -34.671111)
			(xy 430.255713 -34.720695) (xy 430.226243 -34.766551) (xy 430.198993 -34.798) (xy 449.344032 -34.798)
			(xy 449.348103 -34.742378) (xy 449.360229 -34.687941) (xy 449.380152 -34.63585) (xy 449.407448 -34.587215)
			(xy 449.441534 -34.543072) (xy 449.481683 -34.504363) (xy 449.527041 -34.471912) (xy 449.576641 -34.446411)
			(xy 449.629425 -34.428404) (xy 449.684268 -34.418274) (xy 449.740002 -34.416237) (xy 449.795439 -34.422337)
			(xy 449.849396 -34.436443) (xy 449.900725 -34.458255) (xy 449.948331 -34.487309) (xy 449.991199 -34.522984)
			(xy 450.028416 -34.564521) (xy 450.059189 -34.611034) (xy 450.082861 -34.661531) (xy 450.098929 -34.714938)
			(xy 450.107049 -34.770114) (xy 450.107558 -34.798) (xy 450.107049 -34.825886) (xy 450.098929 -34.881062)
			(xy 450.082861 -34.934469) (xy 450.059189 -34.984966) (xy 450.028416 -35.031479) (xy 449.991199 -35.073016)
			(xy 449.948331 -35.108691) (xy 449.900725 -35.137745) (xy 449.849396 -35.159557) (xy 449.795439 -35.173663)
			(xy 449.740002 -35.179763) (xy 449.684268 -35.177726) (xy 449.629425 -35.167596) (xy 449.576641 -35.149589)
			(xy 449.527041 -35.124088) (xy 449.481683 -35.091637) (xy 449.441534 -35.052928) (xy 449.407448 -35.008785)
			(xy 449.380152 -34.96015) (xy 449.360229 -34.908059) (xy 449.348103 -34.853622) (xy 449.344032 -34.798)
			(xy 430.198993 -34.798) (xy 430.190547 -34.807747) (xy 430.149351 -34.843443) (xy 430.103495 -34.872913)
			(xy 430.053911 -34.895557) (xy 430.00161 -34.910915) (xy 429.947655 -34.918672) (xy 429.9204 -34.919158)
			(xy 429.891403 -34.918564) (xy 429.834077 -34.909786) (xy 429.778739 -34.892433) (xy 429.726666 -34.866904)
			(xy 429.679056 -34.833788) (xy 429.637007 -34.793848) (xy 429.601488 -34.748003) (xy 429.573317 -34.697311)
			(xy 429.553143 -34.642938) (xy 429.54143 -34.586139) (xy 429.5394 -34.557208) (xy 426.8089 -34.557208)
			(xy 426.8089 -35.58667) (xy 426.808464 -35.596735) (xy 426.800732 -35.61532) (xy 426.793914 -35.622738)
			(xy 426.702401 -35.714251) (xy 432.714378 -35.714251) (xy 432.714378 -35.659749) (xy 432.722134 -35.605801)
			(xy 432.737489 -35.553506) (xy 432.760131 -35.503929) (xy 432.789597 -35.458079) (xy 432.825288 -35.416888)
			(xy 432.866479 -35.381197) (xy 432.912329 -35.351731) (xy 432.961906 -35.329089) (xy 433.014201 -35.313734)
			(xy 433.068149 -35.305978) (xy 433.0954 -35.305492) (xy 433.12264 -35.305977) (xy 433.176565 -35.313727)
			(xy 433.22884 -35.329069) (xy 433.2784 -35.351692) (xy 433.324238 -35.381134) (xy 433.365422 -35.416798)
			(xy 433.401113 -35.457958) (xy 433.430586 -35.503777) (xy 433.453242 -35.553322) (xy 433.468619 -35.605586)
			(xy 433.476405 -35.659507) (xy 433.476908 -35.686746) (xy 433.476908 -35.687254) (xy 433.476654 -35.69208)
			(xy 433.4764 -35.694112) (xy 433.4764 -35.710114) (xy 433.476792 -35.720188) (xy 433.484533 -35.738787)
			(xy 433.491386 -35.746182) (xy 433.544472 -35.799268) (xy 433.552332 -35.806327) (xy 433.572009 -35.813944)
			(xy 433.582572 -35.814) (xy 433.58308 -35.814) (xy 433.6034 -35.813492) (xy 433.630651 -35.813978)
			(xy 433.684599 -35.821734) (xy 433.736894 -35.837089) (xy 433.786471 -35.859731) (xy 433.832321 -35.889197)
			(xy 433.873512 -35.924888) (xy 433.909203 -35.966079) (xy 433.938669 -36.011929) (xy 433.961311 -36.061506)
			(xy 433.976666 -36.113801) (xy 433.984422 -36.167749) (xy 433.984422 -36.20135) (xy 436.751982 -36.20135)
			(xy 436.756053 -36.145728) (xy 436.768179 -36.091291) (xy 436.788102 -36.0392) (xy 436.815398 -35.990565)
			(xy 436.849484 -35.946422) (xy 436.889633 -35.907713) (xy 436.934991 -35.875262) (xy 436.984591 -35.849761)
			(xy 437.037375 -35.831754) (xy 437.092218 -35.821624) (xy 437.147952 -35.819587) (xy 437.203389 -35.825687)
			(xy 437.257346 -35.839793) (xy 437.308675 -35.861605) (xy 437.356281 -35.890659) (xy 437.399149 -35.926334)
			(xy 437.436366 -35.967871) (xy 437.467139 -36.014384) (xy 437.490811 -36.064881) (xy 437.506879 -36.118288)
			(xy 437.514999 -36.173464) (xy 437.515508 -36.20135) (xy 437.514999 -36.229236) (xy 437.506879 -36.284412)
			(xy 437.490811 -36.337819) (xy 437.467139 -36.388316) (xy 437.436366 -36.434829) (xy 437.399149 -36.476366)
			(xy 437.382893 -36.489894) (xy 438.888376 -36.489894) (xy 438.892447 -36.434272) (xy 438.904573 -36.379835)
			(xy 438.924496 -36.327744) (xy 438.951792 -36.279109) (xy 438.985878 -36.234966) (xy 439.026027 -36.196257)
			(xy 439.071385 -36.163806) (xy 439.120985 -36.138305) (xy 439.173769 -36.120298) (xy 439.228612 -36.110168)
			(xy 439.284346 -36.108131) (xy 439.339783 -36.114231) (xy 439.39374 -36.128337) (xy 439.445069 -36.150149)
			(xy 439.492675 -36.179203) (xy 439.519287 -36.20135) (xy 447.673982 -36.20135) (xy 447.678053 -36.145728)
			(xy 447.690179 -36.091291) (xy 447.710102 -36.0392) (xy 447.737398 -35.990565) (xy 447.771484 -35.946422)
			(xy 447.811633 -35.907713) (xy 447.856991 -35.875262) (xy 447.906591 -35.849761) (xy 447.959375 -35.831754)
			(xy 448.014218 -35.821624) (xy 448.069952 -35.819587) (xy 448.125389 -35.825687) (xy 448.179346 -35.839793)
			(xy 448.230675 -35.861605) (xy 448.278281 -35.890659) (xy 448.321149 -35.926334) (xy 448.358366 -35.967871)
			(xy 448.389139 -36.014384) (xy 448.412811 -36.064881) (xy 448.428879 -36.118288) (xy 448.436999 -36.173464)
			(xy 448.437508 -36.20135) (xy 449.959982 -36.20135) (xy 449.964053 -36.145728) (xy 449.976179 -36.091291)
			(xy 449.996102 -36.0392) (xy 450.023398 -35.990565) (xy 450.057484 -35.946422) (xy 450.097633 -35.907713)
			(xy 450.142991 -35.875262) (xy 450.192591 -35.849761) (xy 450.245375 -35.831754) (xy 450.300218 -35.821624)
			(xy 450.355952 -35.819587) (xy 450.411389 -35.825687) (xy 450.465346 -35.839793) (xy 450.516675 -35.861605)
			(xy 450.564281 -35.890659) (xy 450.607149 -35.926334) (xy 450.644366 -35.967871) (xy 450.675139 -36.014384)
			(xy 450.698811 -36.064881) (xy 450.714879 -36.118288) (xy 450.722999 -36.173464) (xy 450.723508 -36.20135)
			(xy 450.722999 -36.229236) (xy 450.714879 -36.284412) (xy 450.698811 -36.337819) (xy 450.675139 -36.388316)
			(xy 450.644366 -36.434829) (xy 450.607149 -36.476366) (xy 450.564281 -36.512041) (xy 450.516675 -36.541095)
			(xy 450.465346 -36.562907) (xy 450.411389 -36.577013) (xy 450.355952 -36.583113) (xy 450.300218 -36.581076)
			(xy 450.245375 -36.570946) (xy 450.192591 -36.552939) (xy 450.142991 -36.527438) (xy 450.097633 -36.494987)
			(xy 450.057484 -36.456278) (xy 450.023398 -36.412135) (xy 449.996102 -36.3635) (xy 449.976179 -36.311409)
			(xy 449.964053 -36.256972) (xy 449.959982 -36.20135) (xy 448.437508 -36.20135) (xy 448.436999 -36.229236)
			(xy 448.428879 -36.284412) (xy 448.412811 -36.337819) (xy 448.389139 -36.388316) (xy 448.358366 -36.434829)
			(xy 448.321149 -36.476366) (xy 448.278281 -36.512041) (xy 448.230675 -36.541095) (xy 448.179346 -36.562907)
			(xy 448.125389 -36.577013) (xy 448.069952 -36.583113) (xy 448.014218 -36.581076) (xy 447.959375 -36.570946)
			(xy 447.906591 -36.552939) (xy 447.856991 -36.527438) (xy 447.811633 -36.494987) (xy 447.771484 -36.456278)
			(xy 447.737398 -36.412135) (xy 447.710102 -36.3635) (xy 447.690179 -36.311409) (xy 447.678053 -36.256972)
			(xy 447.673982 -36.20135) (xy 439.519287 -36.20135) (xy 439.535543 -36.214878) (xy 439.57276 -36.256415)
			(xy 439.603533 -36.302928) (xy 439.627205 -36.353425) (xy 439.643273 -36.406832) (xy 439.651393 -36.462008)
			(xy 439.651902 -36.489894) (xy 439.651393 -36.51778) (xy 439.643273 -36.572956) (xy 439.627205 -36.626363)
			(xy 439.603533 -36.67686) (xy 439.57276 -36.723373) (xy 439.535543 -36.76491) (xy 439.492675 -36.800585)
			(xy 439.445069 -36.829639) (xy 439.39374 -36.851451) (xy 439.339783 -36.865557) (xy 439.284346 -36.871657)
			(xy 439.228612 -36.86962) (xy 439.173769 -36.85949) (xy 439.120985 -36.841483) (xy 439.071385 -36.815982)
			(xy 439.026027 -36.783531) (xy 438.985878 -36.744822) (xy 438.951792 -36.700679) (xy 438.924496 -36.652044)
			(xy 438.904573 -36.599953) (xy 438.892447 -36.545516) (xy 438.888376 -36.489894) (xy 437.382893 -36.489894)
			(xy 437.356281 -36.512041) (xy 437.308675 -36.541095) (xy 437.257346 -36.562907) (xy 437.203389 -36.577013)
			(xy 437.147952 -36.583113) (xy 437.092218 -36.581076) (xy 437.037375 -36.570946) (xy 436.984591 -36.552939)
			(xy 436.934991 -36.527438) (xy 436.889633 -36.494987) (xy 436.849484 -36.456278) (xy 436.815398 -36.412135)
			(xy 436.788102 -36.3635) (xy 436.768179 -36.311409) (xy 436.756053 -36.256972) (xy 436.751982 -36.20135)
			(xy 433.984422 -36.20135) (xy 433.984422 -36.222251) (xy 433.976666 -36.276199) (xy 433.961311 -36.328494)
			(xy 433.938669 -36.378071) (xy 433.909203 -36.423921) (xy 433.873512 -36.465112) (xy 433.832321 -36.500803)
			(xy 433.786471 -36.530269) (xy 433.736894 -36.552911) (xy 433.684599 -36.568266) (xy 433.630651 -36.576022)
			(xy 433.6034 -36.576508) (xy 433.57616 -36.576023) (xy 433.522235 -36.568273) (xy 433.46996 -36.552931)
			(xy 433.4204 -36.530308) (xy 433.374562 -36.500866) (xy 433.333378 -36.465202) (xy 433.297687 -36.424042)
			(xy 433.268214 -36.378223) (xy 433.245558 -36.328678) (xy 433.230181 -36.276414) (xy 433.222395 -36.222493)
			(xy 433.221892 -36.195254) (xy 433.221892 -36.194746) (xy 433.222146 -36.18992) (xy 433.2224 -36.187888)
			(xy 433.2224 -36.171886) (xy 433.222008 -36.161812) (xy 433.214267 -36.143213) (xy 433.207414 -36.135818)
			(xy 433.154328 -36.082732) (xy 433.146468 -36.075673) (xy 433.126791 -36.068056) (xy 433.116228 -36.068)
			(xy 433.11572 -36.068) (xy 433.0954 -36.068508) (xy 433.068149 -36.068022) (xy 433.014201 -36.060266)
			(xy 432.961906 -36.044911) (xy 432.912329 -36.022269) (xy 432.866479 -35.992803) (xy 432.825288 -35.957112)
			(xy 432.789597 -35.915921) (xy 432.760131 -35.870071) (xy 432.737489 -35.820494) (xy 432.722134 -35.768199)
			(xy 432.714378 -35.714251) (xy 426.702401 -35.714251) (xy 426.353986 -36.062666) (xy 426.34662 -36.069778)
			(xy 426.339 -36.088574) (xy 426.339 -37.592) (xy 427.856396 -37.592) (xy 427.856855 -37.564747) (xy 427.864612 -37.510796)
			(xy 427.879969 -37.458498) (xy 427.902611 -37.408917) (xy 427.93208 -37.363064) (xy 427.967774 -37.321871)
			(xy 428.008967 -37.286177) (xy 428.054821 -37.25671) (xy 428.104401 -37.234067) (xy 428.1567 -37.218712)
			(xy 428.210651 -37.210955) (xy 428.237904 -37.210492) (xy 428.253406 -37.210665) (xy 428.284305 -37.213209)
			(xy 428.299626 -37.215572) (xy 428.314288 -37.217381) (xy 428.343563 -37.213548) (xy 428.370521 -37.201506)
			(xy 428.392911 -37.18226) (xy 428.408864 -37.157416) (xy 428.417049 -37.129048) (xy 428.416782 -37.099524)
			(xy 428.41291 -37.08527) (xy 428.405006 -37.057876) (xy 428.396462 -37.001507) (xy 428.395892 -36.973002)
			(xy 428.395892 -36.97224) (xy 428.396312 -36.944984) (xy 428.404065 -36.891025) (xy 428.419417 -36.838719)
			(xy 428.442058 -36.78913) (xy 428.471526 -36.743269) (xy 428.50722 -36.702067) (xy 428.548415 -36.666366)
			(xy 428.594272 -36.63689) (xy 428.643856 -36.614241) (xy 428.69616 -36.598879) (xy 428.750117 -36.591117)
			(xy 428.80463 -36.591113) (xy 428.858588 -36.598867) (xy 428.910894 -36.614222) (xy 428.960481 -36.636865)
			(xy 429.006342 -36.666334) (xy 429.047542 -36.70203) (xy 429.083242 -36.743226) (xy 429.112716 -36.789083)
			(xy 429.122704 -36.81095) (xy 434.999382 -36.81095) (xy 435.003453 -36.755328) (xy 435.015579 -36.700891)
			(xy 435.035502 -36.6488) (xy 435.062798 -36.600165) (xy 435.096884 -36.556022) (xy 435.137033 -36.517313)
			(xy 435.182391 -36.484862) (xy 435.231991 -36.459361) (xy 435.284775 -36.441354) (xy 435.339618 -36.431224)
			(xy 435.395352 -36.429187) (xy 435.450789 -36.435287) (xy 435.504746 -36.449393) (xy 435.556075 -36.471205)
			(xy 435.603681 -36.500259) (xy 435.646549 -36.535934) (xy 435.683766 -36.577471) (xy 435.714539 -36.623984)
			(xy 435.738211 -36.674481) (xy 435.754279 -36.727888) (xy 435.762399 -36.783064) (xy 435.762908 -36.81095)
			(xy 435.762399 -36.838836) (xy 435.754279 -36.894012) (xy 435.738211 -36.947419) (xy 435.714539 -36.997916)
			(xy 435.683766 -37.044429) (xy 435.646549 -37.085966) (xy 435.603681 -37.121641) (xy 435.556075 -37.150695)
			(xy 435.504746 -37.172507) (xy 435.450789 -37.186613) (xy 435.395352 -37.192713) (xy 435.339618 -37.190676)
			(xy 435.284775 -37.180546) (xy 435.231991 -37.162539) (xy 435.182391 -37.137038) (xy 435.137033 -37.104587)
			(xy 435.096884 -37.065878) (xy 435.062798 -37.021735) (xy 435.035502 -36.9731) (xy 435.015579 -36.921009)
			(xy 435.003453 -36.866572) (xy 434.999382 -36.81095) (xy 429.122704 -36.81095) (xy 429.135364 -36.838669)
			(xy 429.150724 -36.890973) (xy 429.158484 -36.94493) (xy 429.158486 -36.999443) (xy 429.15073 -37.053401)
			(xy 429.135373 -37.105706) (xy 429.112729 -37.155293) (xy 429.083258 -37.201153) (xy 429.047561 -37.242351)
			(xy 429.006363 -37.27805) (xy 428.960505 -37.307523) (xy 428.910919 -37.330169) (xy 428.858614 -37.345527)
			(xy 428.804656 -37.353285) (xy 428.7774 -37.353748) (xy 428.761898 -37.353576) (xy 428.730999 -37.351032)
			(xy 428.715678 -37.348668) (xy 428.701019 -37.346812) (xy 428.671735 -37.350644) (xy 428.644769 -37.362691)
			(xy 428.622374 -37.381946) (xy 428.60642 -37.4068) (xy 428.598239 -37.435179) (xy 428.598515 -37.464713)
			(xy 428.602394 -37.47897) (xy 428.610307 -37.506361) (xy 428.618845 -37.562732) (xy 428.619412 -37.591238)
			(xy 428.619412 -37.592) (xy 428.61895 -37.618856) (xy 428.611417 -37.672036) (xy 428.596499 -37.723634)
			(xy 428.574491 -37.77263) (xy 428.545828 -37.818054) (xy 428.511078 -37.85901) (xy 428.470927 -37.894686)
			(xy 428.426169 -37.924378) (xy 428.377689 -37.947499) (xy 428.352204 -37.955982) (xy 428.32434 -37.964163)
			(xy 428.266939 -37.972964) (xy 428.208869 -37.972964) (xy 428.151468 -37.964163) (xy 428.123604 -37.955982)
			(xy 428.098119 -37.947498) (xy 428.049638 -37.924378) (xy 428.00488 -37.894686) (xy 427.964728 -37.85901)
			(xy 427.929977 -37.818055) (xy 427.901314 -37.772631) (xy 427.879306 -37.723635) (xy 427.864387 -37.672037)
			(xy 427.856854 -37.618856) (xy 427.856396 -37.592) (xy 426.339 -37.592) (xy 426.339 -38.989) (xy 427.855886 -38.989)
			(xy 427.859957 -38.933378) (xy 427.872083 -38.878941) (xy 427.892006 -38.82685) (xy 427.919302 -38.778215)
			(xy 427.953388 -38.734072) (xy 427.993537 -38.695363) (xy 428.038895 -38.662912) (xy 428.088495 -38.637411)
			(xy 428.141279 -38.619404) (xy 428.196122 -38.609274) (xy 428.251856 -38.607237) (xy 428.307293 -38.613337)
			(xy 428.36125 -38.627443) (xy 428.412579 -38.649255) (xy 428.460185 -38.678309) (xy 428.503053 -38.713984)
			(xy 428.54027 -38.755521) (xy 428.571043 -38.802034) (xy 428.594715 -38.852531) (xy 428.597564 -38.862)
			(xy 434.465728 -38.862) (xy 434.469801 -38.806341) (xy 434.481936 -38.751868) (xy 434.501872 -38.699742)
			(xy 434.529186 -38.651074) (xy 434.563294 -38.606902) (xy 434.603471 -38.568167) (xy 434.648859 -38.535695)
			(xy 434.698491 -38.510177) (xy 434.751311 -38.492158) (xy 434.80619 -38.482021) (xy 434.861961 -38.479983)
			(xy 434.917435 -38.486086) (xy 434.971428 -38.500202) (xy 435.022791 -38.522029) (xy 435.070429 -38.551102)
			(xy 435.113325 -38.586801) (xy 435.150567 -38.628365) (xy 435.181361 -38.674909) (xy 435.205049 -38.72544)
			(xy 435.221127 -38.778882) (xy 435.229253 -38.834096) (xy 435.229762 -38.862) (xy 435.361332 -38.862)
			(xy 435.365403 -38.806378) (xy 435.377529 -38.751941) (xy 435.397452 -38.69985) (xy 435.424748 -38.651215)
			(xy 435.458834 -38.607072) (xy 435.498983 -38.568363) (xy 435.544341 -38.535912) (xy 435.593941 -38.510411)
			(xy 435.646725 -38.492404) (xy 435.701568 -38.482274) (xy 435.757302 -38.480237) (xy 435.812739 -38.486337)
			(xy 435.866696 -38.500443) (xy 435.918025 -38.522255) (xy 435.965631 -38.551309) (xy 436.008499 -38.586984)
			(xy 436.045716 -38.628521) (xy 436.076489 -38.675034) (xy 436.100161 -38.725531) (xy 436.116229 -38.778938)
			(xy 436.124349 -38.834114) (xy 436.124858 -38.862) (xy 438.047128 -38.862) (xy 438.051199 -38.806378)
			(xy 438.063325 -38.751941) (xy 438.083248 -38.69985) (xy 438.110544 -38.651215) (xy 438.14463 -38.607072)
			(xy 438.184779 -38.568363) (xy 438.230137 -38.535912) (xy 438.279737 -38.510411) (xy 438.332521 -38.492404)
			(xy 438.387364 -38.482274) (xy 438.443098 -38.480237) (xy 438.498535 -38.486337) (xy 438.552492 -38.500443)
			(xy 438.603821 -38.522255) (xy 438.651427 -38.551309) (xy 438.694295 -38.586984) (xy 438.731512 -38.628521)
			(xy 438.762285 -38.675034) (xy 438.785957 -38.725531) (xy 438.802025 -38.778938) (xy 438.810145 -38.834114)
			(xy 438.810654 -38.862) (xy 438.810145 -38.889886) (xy 438.802025 -38.945062) (xy 438.785957 -38.998469)
			(xy 438.762285 -39.048966) (xy 438.731512 -39.095479) (xy 438.694295 -39.137016) (xy 438.651427 -39.172691)
			(xy 438.603821 -39.201745) (xy 438.552492 -39.223557) (xy 438.498535 -39.237663) (xy 438.443098 -39.243763)
			(xy 438.387364 -39.241726) (xy 438.332521 -39.231596) (xy 438.279737 -39.213589) (xy 438.230137 -39.188088)
			(xy 438.184779 -39.155637) (xy 438.14463 -39.116928) (xy 438.110544 -39.072785) (xy 438.083248 -39.02415)
			(xy 438.063325 -38.972059) (xy 438.051199 -38.917622) (xy 438.047128 -38.862) (xy 436.124858 -38.862)
			(xy 436.124349 -38.889886) (xy 436.116229 -38.945062) (xy 436.100161 -38.998469) (xy 436.076489 -39.048966)
			(xy 436.045716 -39.095479) (xy 436.008499 -39.137016) (xy 435.965631 -39.172691) (xy 435.918025 -39.201745)
			(xy 435.866696 -39.223557) (xy 435.812739 -39.237663) (xy 435.757302 -39.243763) (xy 435.701568 -39.241726)
			(xy 435.646725 -39.231596) (xy 435.593941 -39.213589) (xy 435.544341 -39.188088) (xy 435.498983 -39.155637)
			(xy 435.458834 -39.116928) (xy 435.424748 -39.072785) (xy 435.397452 -39.02415) (xy 435.377529 -38.972059)
			(xy 435.365403 -38.917622) (xy 435.361332 -38.862) (xy 435.229762 -38.862) (xy 435.229253 -38.889904)
			(xy 435.221127 -38.945118) (xy 435.205049 -38.99856) (xy 435.181361 -39.049091) (xy 435.150567 -39.095635)
			(xy 435.113325 -39.137199) (xy 435.070429 -39.172898) (xy 435.022791 -39.201971) (xy 434.971428 -39.223798)
			(xy 434.917435 -39.237914) (xy 434.861961 -39.244017) (xy 434.80619 -39.241979) (xy 434.751311 -39.231842)
			(xy 434.698491 -39.213823) (xy 434.648859 -39.188305) (xy 434.603471 -39.155833) (xy 434.563294 -39.117098)
			(xy 434.529186 -39.072926) (xy 434.501872 -39.024258) (xy 434.481936 -38.972132) (xy 434.469801 -38.917659)
			(xy 434.465728 -38.862) (xy 428.597564 -38.862) (xy 428.610783 -38.905938) (xy 428.618903 -38.961114)
			(xy 428.619412 -38.989) (xy 428.618903 -39.016886) (xy 428.610783 -39.072062) (xy 428.594715 -39.125469)
			(xy 428.571043 -39.175966) (xy 428.54027 -39.222479) (xy 428.503053 -39.264016) (xy 428.460185 -39.299691)
			(xy 428.412579 -39.328745) (xy 428.36125 -39.350557) (xy 428.307293 -39.364663) (xy 428.251856 -39.370763)
			(xy 428.196122 -39.368726) (xy 428.141279 -39.358596) (xy 428.088495 -39.340589) (xy 428.038895 -39.315088)
			(xy 427.993537 -39.282637) (xy 427.953388 -39.243928) (xy 427.919302 -39.199785) (xy 427.892006 -39.15115)
			(xy 427.872083 -39.099059) (xy 427.859957 -39.044622) (xy 427.855886 -38.989) (xy 426.339 -38.989)
			(xy 426.339 -40.386) (xy 427.855886 -40.386) (xy 427.859957 -40.330378) (xy 427.872083 -40.275941)
			(xy 427.892006 -40.22385) (xy 427.919302 -40.175215) (xy 427.953388 -40.131072) (xy 427.993537 -40.092363)
			(xy 428.038895 -40.059912) (xy 428.088495 -40.034411) (xy 428.141279 -40.016404) (xy 428.196122 -40.006274)
			(xy 428.251856 -40.004237) (xy 428.307293 -40.010337) (xy 428.36125 -40.024443) (xy 428.412579 -40.046255)
			(xy 428.460185 -40.075309) (xy 428.503053 -40.110984) (xy 428.54027 -40.152521) (xy 428.571043 -40.199034)
			(xy 428.594715 -40.249531) (xy 428.610783 -40.302938) (xy 428.618903 -40.358114) (xy 428.619412 -40.386)
			(xy 431.671982 -40.386) (xy 431.676053 -40.330378) (xy 431.688179 -40.275941) (xy 431.708102 -40.22385)
			(xy 431.735398 -40.175215) (xy 431.769484 -40.131072) (xy 431.809633 -40.092363) (xy 431.854991 -40.059912)
			(xy 431.904591 -40.034411) (xy 431.957375 -40.016404) (xy 432.012218 -40.006274) (xy 432.067952 -40.004237)
			(xy 432.123389 -40.010337) (xy 432.177346 -40.024443) (xy 432.228675 -40.046255) (xy 432.276281 -40.075309)
			(xy 432.319149 -40.110984) (xy 432.337979 -40.132) (xy 433.856382 -40.132) (xy 433.860453 -40.076378)
			(xy 433.872579 -40.021941) (xy 433.892502 -39.96985) (xy 433.919798 -39.921215) (xy 433.953884 -39.877072)
			(xy 433.994033 -39.838363) (xy 434.039391 -39.805912) (xy 434.088991 -39.780411) (xy 434.141775 -39.762404)
			(xy 434.196618 -39.752274) (xy 434.252352 -39.750237) (xy 434.307789 -39.756337) (xy 434.361746 -39.770443)
			(xy 434.413075 -39.792255) (xy 434.460681 -39.821309) (xy 434.503549 -39.856984) (xy 434.513731 -39.868348)
			(xy 437.021984 -39.868348) (xy 437.026055 -39.812726) (xy 437.038181 -39.758289) (xy 437.058104 -39.706198)
			(xy 437.0854 -39.657563) (xy 437.119486 -39.61342) (xy 437.159635 -39.574711) (xy 437.204993 -39.54226)
			(xy 437.254593 -39.516759) (xy 437.307377 -39.498752) (xy 437.36222 -39.488622) (xy 437.417954 -39.486585)
			(xy 437.473391 -39.492685) (xy 437.474351 -39.492936) (xy 448.455032 -39.492936) (xy 448.459103 -39.437314)
			(xy 448.471229 -39.382877) (xy 448.491152 -39.330786) (xy 448.518448 -39.282151) (xy 448.552534 -39.238008)
			(xy 448.592683 -39.199299) (xy 448.638041 -39.166848) (xy 448.687641 -39.141347) (xy 448.740425 -39.12334)
			(xy 448.795268 -39.11321) (xy 448.851002 -39.111173) (xy 448.906439 -39.117273) (xy 448.960396 -39.131379)
			(xy 449.011725 -39.153191) (xy 449.059331 -39.182245) (xy 449.102199 -39.21792) (xy 449.139416 -39.259457)
			(xy 449.170189 -39.30597) (xy 449.193861 -39.356467) (xy 449.209929 -39.409874) (xy 449.218049 -39.46505)
			(xy 449.218558 -39.492936) (xy 449.218049 -39.520822) (xy 449.209929 -39.575998) (xy 449.193861 -39.629405)
			(xy 449.170189 -39.679902) (xy 449.139416 -39.726415) (xy 449.102199 -39.767952) (xy 449.059331 -39.803627)
			(xy 449.011725 -39.832681) (xy 448.960396 -39.854493) (xy 448.906439 -39.868599) (xy 448.851002 -39.874699)
			(xy 448.795268 -39.872662) (xy 448.740425 -39.862532) (xy 448.687641 -39.844525) (xy 448.638041 -39.819024)
			(xy 448.592683 -39.786573) (xy 448.552534 -39.747864) (xy 448.518448 -39.703721) (xy 448.491152 -39.655086)
			(xy 448.471229 -39.602995) (xy 448.459103 -39.548558) (xy 448.455032 -39.492936) (xy 437.474351 -39.492936)
			(xy 437.527348 -39.506791) (xy 437.578677 -39.528603) (xy 437.626283 -39.557657) (xy 437.669151 -39.593332)
			(xy 437.706368 -39.634869) (xy 437.737141 -39.681382) (xy 437.760813 -39.731879) (xy 437.776881 -39.785286)
			(xy 437.785001 -39.840462) (xy 437.78551 -39.868348) (xy 437.785001 -39.896234) (xy 437.776881 -39.95141)
			(xy 437.760813 -40.004817) (xy 437.737141 -40.055314) (xy 437.706368 -40.101827) (xy 437.669151 -40.143364)
			(xy 437.626283 -40.179039) (xy 437.578677 -40.208093) (xy 437.527348 -40.229905) (xy 437.473391 -40.244011)
			(xy 437.417954 -40.250111) (xy 437.36222 -40.248074) (xy 437.307377 -40.237944) (xy 437.254593 -40.219937)
			(xy 437.204993 -40.194436) (xy 437.159635 -40.161985) (xy 437.119486 -40.123276) (xy 437.0854 -40.079133)
			(xy 437.058104 -40.030498) (xy 437.038181 -39.978407) (xy 437.026055 -39.92397) (xy 437.021984 -39.868348)
			(xy 434.513731 -39.868348) (xy 434.540766 -39.898521) (xy 434.571539 -39.945034) (xy 434.595211 -39.995531)
			(xy 434.611279 -40.048938) (xy 434.619399 -40.104114) (xy 434.619908 -40.132) (xy 434.619399 -40.159886)
			(xy 434.611279 -40.215062) (xy 434.595211 -40.268469) (xy 434.571539 -40.318966) (xy 434.540766 -40.365479)
			(xy 434.503549 -40.407016) (xy 434.479663 -40.426894) (xy 438.888376 -40.426894) (xy 438.892447 -40.371272)
			(xy 438.904573 -40.316835) (xy 438.924496 -40.264744) (xy 438.951792 -40.216109) (xy 438.985878 -40.171966)
			(xy 439.026027 -40.133257) (xy 439.071385 -40.100806) (xy 439.120985 -40.075305) (xy 439.173769 -40.057298)
			(xy 439.228612 -40.047168) (xy 439.284346 -40.045131) (xy 439.339783 -40.051231) (xy 439.39374 -40.065337)
			(xy 439.445069 -40.087149) (xy 439.492675 -40.116203) (xy 439.519287 -40.13835) (xy 447.673982 -40.13835)
			(xy 447.678053 -40.082728) (xy 447.690179 -40.028291) (xy 447.710102 -39.9762) (xy 447.737398 -39.927565)
			(xy 447.771484 -39.883422) (xy 447.811633 -39.844713) (xy 447.856991 -39.812262) (xy 447.906591 -39.786761)
			(xy 447.959375 -39.768754) (xy 448.014218 -39.758624) (xy 448.069952 -39.756587) (xy 448.125389 -39.762687)
			(xy 448.179346 -39.776793) (xy 448.230675 -39.798605) (xy 448.278281 -39.827659) (xy 448.321149 -39.863334)
			(xy 448.358366 -39.904871) (xy 448.389139 -39.951384) (xy 448.412811 -40.001881) (xy 448.428879 -40.055288)
			(xy 448.436999 -40.110464) (xy 448.437392 -40.132) (xy 449.959982 -40.132) (xy 449.964053 -40.076378)
			(xy 449.976179 -40.021941) (xy 449.996102 -39.96985) (xy 450.023398 -39.921215) (xy 450.057484 -39.877072)
			(xy 450.097633 -39.838363) (xy 450.142991 -39.805912) (xy 450.192591 -39.780411) (xy 450.245375 -39.762404)
			(xy 450.300218 -39.752274) (xy 450.355952 -39.750237) (xy 450.411389 -39.756337) (xy 450.465346 -39.770443)
			(xy 450.516675 -39.792255) (xy 450.564281 -39.821309) (xy 450.607149 -39.856984) (xy 450.644366 -39.898521)
			(xy 450.675139 -39.945034) (xy 450.698811 -39.995531) (xy 450.714879 -40.048938) (xy 450.722999 -40.104114)
			(xy 450.723508 -40.132) (xy 450.722999 -40.159886) (xy 450.714879 -40.215062) (xy 450.698811 -40.268469)
			(xy 450.675139 -40.318966) (xy 450.644366 -40.365479) (xy 450.607149 -40.407016) (xy 450.564281 -40.442691)
			(xy 450.516675 -40.471745) (xy 450.465346 -40.493557) (xy 450.411389 -40.507663) (xy 450.355952 -40.513763)
			(xy 450.300218 -40.511726) (xy 450.245375 -40.501596) (xy 450.192591 -40.483589) (xy 450.142991 -40.458088)
			(xy 450.097633 -40.425637) (xy 450.057484 -40.386928) (xy 450.023398 -40.342785) (xy 449.996102 -40.29415)
			(xy 449.976179 -40.242059) (xy 449.964053 -40.187622) (xy 449.959982 -40.132) (xy 448.437392 -40.132)
			(xy 448.437508 -40.13835) (xy 448.436999 -40.166236) (xy 448.428879 -40.221412) (xy 448.412811 -40.274819)
			(xy 448.389139 -40.325316) (xy 448.358366 -40.371829) (xy 448.321149 -40.413366) (xy 448.278281 -40.449041)
			(xy 448.230675 -40.478095) (xy 448.179346 -40.499907) (xy 448.125389 -40.514013) (xy 448.069952 -40.520113)
			(xy 448.014218 -40.518076) (xy 447.959375 -40.507946) (xy 447.906591 -40.489939) (xy 447.856991 -40.464438)
			(xy 447.811633 -40.431987) (xy 447.771484 -40.393278) (xy 447.737398 -40.349135) (xy 447.710102 -40.3005)
			(xy 447.690179 -40.248409) (xy 447.678053 -40.193972) (xy 447.673982 -40.13835) (xy 439.519287 -40.13835)
			(xy 439.535543 -40.151878) (xy 439.57276 -40.193415) (xy 439.603533 -40.239928) (xy 439.627205 -40.290425)
			(xy 439.643273 -40.343832) (xy 439.651393 -40.399008) (xy 439.651902 -40.426894) (xy 439.651393 -40.45478)
			(xy 439.643273 -40.509956) (xy 439.627205 -40.563363) (xy 439.603533 -40.61386) (xy 439.57276 -40.660373)
			(xy 439.535543 -40.70191) (xy 439.492675 -40.737585) (xy 439.445069 -40.766639) (xy 439.39374 -40.788451)
			(xy 439.339783 -40.802557) (xy 439.284346 -40.808657) (xy 439.228612 -40.80662) (xy 439.173769 -40.79649)
			(xy 439.120985 -40.778483) (xy 439.071385 -40.752982) (xy 439.026027 -40.720531) (xy 438.985878 -40.681822)
			(xy 438.951792 -40.637679) (xy 438.924496 -40.589044) (xy 438.904573 -40.536953) (xy 438.892447 -40.482516)
			(xy 438.888376 -40.426894) (xy 434.479663 -40.426894) (xy 434.460681 -40.442691) (xy 434.413075 -40.471745)
			(xy 434.361746 -40.493557) (xy 434.307789 -40.507663) (xy 434.252352 -40.513763) (xy 434.196618 -40.511726)
			(xy 434.141775 -40.501596) (xy 434.088991 -40.483589) (xy 434.039391 -40.458088) (xy 433.994033 -40.425637)
			(xy 433.953884 -40.386928) (xy 433.919798 -40.342785) (xy 433.892502 -40.29415) (xy 433.872579 -40.242059)
			(xy 433.860453 -40.187622) (xy 433.856382 -40.132) (xy 432.337979 -40.132) (xy 432.356366 -40.152521)
			(xy 432.387139 -40.199034) (xy 432.410811 -40.249531) (xy 432.426879 -40.302938) (xy 432.434999 -40.358114)
			(xy 432.435508 -40.386) (xy 432.434999 -40.413886) (xy 432.426879 -40.469062) (xy 432.410811 -40.522469)
			(xy 432.387139 -40.572966) (xy 432.356366 -40.619479) (xy 432.319149 -40.661016) (xy 432.276281 -40.696691)
			(xy 432.228675 -40.725745) (xy 432.177346 -40.747557) (xy 432.123389 -40.761663) (xy 432.067952 -40.767763)
			(xy 432.012218 -40.765726) (xy 431.957375 -40.755596) (xy 431.904591 -40.737589) (xy 431.854991 -40.712088)
			(xy 431.809633 -40.679637) (xy 431.769484 -40.640928) (xy 431.735398 -40.596785) (xy 431.708102 -40.54815)
			(xy 431.688179 -40.496059) (xy 431.676053 -40.441622) (xy 431.671982 -40.386) (xy 428.619412 -40.386)
			(xy 428.618903 -40.413886) (xy 428.610783 -40.469062) (xy 428.594715 -40.522469) (xy 428.571043 -40.572966)
			(xy 428.54027 -40.619479) (xy 428.503053 -40.661016) (xy 428.460185 -40.696691) (xy 428.412579 -40.725745)
			(xy 428.36125 -40.747557) (xy 428.307293 -40.761663) (xy 428.251856 -40.767763) (xy 428.196122 -40.765726)
			(xy 428.141279 -40.755596) (xy 428.088495 -40.737589) (xy 428.038895 -40.712088) (xy 427.993537 -40.679637)
			(xy 427.953388 -40.640928) (xy 427.919302 -40.596785) (xy 427.892006 -40.54815) (xy 427.872083 -40.496059)
			(xy 427.859957 -40.441622) (xy 427.855886 -40.386) (xy 426.339 -40.386) (xy 426.339 -41.81025) (xy 427.856855 -41.81025)
			(xy 427.856856 -41.755744) (xy 427.864613 -41.701793) (xy 427.879969 -41.649496) (xy 427.902612 -41.599916)
			(xy 427.932081 -41.554063) (xy 427.967775 -41.51287) (xy 428.008968 -41.477177) (xy 428.054821 -41.447709)
			(xy 428.104402 -41.425067) (xy 428.1567 -41.409711) (xy 428.210651 -41.401955) (xy 428.237904 -41.401492)
			(xy 428.253406 -41.401665) (xy 428.284305 -41.404209) (xy 428.299626 -41.406572) (xy 428.314288 -41.408381)
			(xy 428.343563 -41.404548) (xy 428.370521 -41.392506) (xy 428.392911 -41.37326) (xy 428.408864 -41.348416)
			(xy 428.417049 -41.320048) (xy 428.416782 -41.290524) (xy 428.41291 -41.27627) (xy 428.405006 -41.248876)
			(xy 428.396462 -41.192507) (xy 428.395892 -41.164002) (xy 428.395892 -41.16324) (xy 428.396312 -41.135984)
			(xy 428.404065 -41.082025) (xy 428.419417 -41.029719) (xy 428.442058 -40.98013) (xy 428.471526 -40.934269)
			(xy 428.50722 -40.893067) (xy 428.548415 -40.857366) (xy 428.594272 -40.82789) (xy 428.643856 -40.805241)
			(xy 428.69616 -40.789879) (xy 428.750117 -40.782117) (xy 428.80463 -40.782113) (xy 428.858588 -40.789867)
			(xy 428.910894 -40.805222) (xy 428.960481 -40.827865) (xy 429.006342 -40.857334) (xy 429.047542 -40.89303)
			(xy 429.083242 -40.934226) (xy 429.112716 -40.980083) (xy 429.135364 -41.029669) (xy 429.150724 -41.081973)
			(xy 429.158484 -41.13593) (xy 429.158486 -41.190443) (xy 429.15073 -41.244401) (xy 429.135373 -41.296706)
			(xy 429.112729 -41.346293) (xy 429.083258 -41.392153) (xy 429.047561 -41.433351) (xy 429.006363 -41.46905)
			(xy 428.960505 -41.498523) (xy 428.910919 -41.521169) (xy 428.858614 -41.536527) (xy 428.804656 -41.544285)
			(xy 428.7774 -41.544748) (xy 428.761898 -41.544576) (xy 428.730999 -41.542032) (xy 428.715678 -41.539668)
			(xy 428.701019 -41.537812) (xy 428.671735 -41.541644) (xy 428.644769 -41.553691) (xy 428.622374 -41.572946)
			(xy 428.60642 -41.5978) (xy 428.598239 -41.626179) (xy 428.598515 -41.655713) (xy 428.602394 -41.66997)
			(xy 428.610307 -41.697361) (xy 428.618845 -41.753732) (xy 428.619412 -41.782238) (xy 428.619412 -41.783)
			(xy 431.671982 -41.783) (xy 431.676053 -41.727378) (xy 431.688179 -41.672941) (xy 431.708102 -41.62085)
			(xy 431.735398 -41.572215) (xy 431.769484 -41.528072) (xy 431.809633 -41.489363) (xy 431.854991 -41.456912)
			(xy 431.904591 -41.431411) (xy 431.957375 -41.413404) (xy 432.012218 -41.403274) (xy 432.067952 -41.401237)
			(xy 432.123389 -41.407337) (xy 432.177346 -41.421443) (xy 432.228675 -41.443255) (xy 432.276281 -41.472309)
			(xy 432.319149 -41.507984) (xy 432.356366 -41.549521) (xy 432.387139 -41.596034) (xy 432.410811 -41.646531)
			(xy 432.426879 -41.699938) (xy 432.430879 -41.72712) (xy 438.301382 -41.72712) (xy 438.305453 -41.671498)
			(xy 438.317579 -41.617061) (xy 438.337502 -41.56497) (xy 438.364798 -41.516335) (xy 438.398884 -41.472192)
			(xy 438.439033 -41.433483) (xy 438.484391 -41.401032) (xy 438.533991 -41.375531) (xy 438.586775 -41.357524)
			(xy 438.641618 -41.347394) (xy 438.697352 -41.345357) (xy 438.752789 -41.351457) (xy 438.806746 -41.365563)
			(xy 438.858075 -41.387375) (xy 438.905681 -41.416429) (xy 438.948549 -41.452104) (xy 438.985766 -41.493641)
			(xy 439.016539 -41.540154) (xy 439.040211 -41.590651) (xy 439.056279 -41.644058) (xy 439.064399 -41.699234)
			(xy 439.064908 -41.72712) (xy 439.064399 -41.755006) (xy 439.056279 -41.810182) (xy 439.040211 -41.863589)
			(xy 439.016539 -41.914086) (xy 438.985766 -41.960599) (xy 438.948549 -42.002136) (xy 438.905681 -42.037811)
			(xy 438.858075 -42.066865) (xy 438.806746 -42.088677) (xy 438.752789 -42.102783) (xy 438.697352 -42.108883)
			(xy 438.641618 -42.106846) (xy 438.586775 -42.096716) (xy 438.533991 -42.078709) (xy 438.484391 -42.053208)
			(xy 438.439033 -42.020757) (xy 438.398884 -41.982048) (xy 438.364798 -41.937905) (xy 438.337502 -41.88927)
			(xy 438.317579 -41.837179) (xy 438.305453 -41.782742) (xy 438.301382 -41.72712) (xy 432.430879 -41.72712)
			(xy 432.434999 -41.755114) (xy 432.435508 -41.783) (xy 432.434999 -41.810886) (xy 432.426879 -41.866062)
			(xy 432.410811 -41.919469) (xy 432.387139 -41.969966) (xy 432.356366 -42.016479) (xy 432.319149 -42.058016)
			(xy 432.276281 -42.093691) (xy 432.228675 -42.122745) (xy 432.177346 -42.144557) (xy 432.123389 -42.158663)
			(xy 432.067952 -42.164763) (xy 432.012218 -42.162726) (xy 431.957375 -42.152596) (xy 431.904591 -42.134589)
			(xy 431.854991 -42.109088) (xy 431.809633 -42.076637) (xy 431.769484 -42.037928) (xy 431.735398 -41.993785)
			(xy 431.708102 -41.94515) (xy 431.688179 -41.893059) (xy 431.676053 -41.838622) (xy 431.671982 -41.783)
			(xy 428.619412 -41.783) (xy 428.618945 -41.810253) (xy 428.611188 -41.864204) (xy 428.595832 -41.916502)
			(xy 428.573189 -41.966082) (xy 428.543721 -42.011935) (xy 428.508027 -42.053128) (xy 428.466834 -42.088822)
			(xy 428.420981 -42.11829) (xy 428.371401 -42.140932) (xy 428.319103 -42.156288) (xy 428.265152 -42.164045)
			(xy 428.210646 -42.164045) (xy 428.156695 -42.156287) (xy 428.104397 -42.140931) (xy 428.054817 -42.118288)
			(xy 428.008964 -42.08882) (xy 427.967771 -42.053126) (xy 427.932078 -42.011933) (xy 427.90261 -41.96608)
			(xy 427.879968 -41.916499) (xy 427.864612 -41.864201) (xy 427.856855 -41.81025) (xy 426.339 -41.81025)
			(xy 426.339 -43.18) (xy 427.855886 -43.18) (xy 427.859957 -43.124378) (xy 427.872083 -43.069941)
			(xy 427.892006 -43.01785) (xy 427.919302 -42.969215) (xy 427.953388 -42.925072) (xy 427.993537 -42.886363)
			(xy 428.038895 -42.853912) (xy 428.088495 -42.828411) (xy 428.141279 -42.810404) (xy 428.196122 -42.800274)
			(xy 428.251856 -42.798237) (xy 428.25879 -42.799) (xy 435.361332 -42.799) (xy 435.365403 -42.743378)
			(xy 435.377529 -42.688941) (xy 435.397452 -42.63685) (xy 435.424748 -42.588215) (xy 435.458834 -42.544072)
			(xy 435.498983 -42.505363) (xy 435.544341 -42.472912) (xy 435.593941 -42.447411) (xy 435.646725 -42.429404)
			(xy 435.701568 -42.419274) (xy 435.757302 -42.417237) (xy 435.812739 -42.423337) (xy 435.866696 -42.437443)
			(xy 435.918025 -42.459255) (xy 435.965631 -42.488309) (xy 436.008499 -42.523984) (xy 436.045716 -42.565521)
			(xy 436.076489 -42.612034) (xy 436.100161 -42.662531) (xy 436.116229 -42.715938) (xy 436.124349 -42.771114)
			(xy 436.124858 -42.799) (xy 449.064886 -42.799) (xy 449.068957 -42.743378) (xy 449.081083 -42.688941)
			(xy 449.101006 -42.63685) (xy 449.128302 -42.588215) (xy 449.162388 -42.544072) (xy 449.202537 -42.505363)
			(xy 449.247895 -42.472912) (xy 449.297495 -42.447411) (xy 449.350279 -42.429404) (xy 449.405122 -42.419274)
			(xy 449.460856 -42.417237) (xy 449.516293 -42.423337) (xy 449.57025 -42.437443) (xy 449.621579 -42.459255)
			(xy 449.669185 -42.488309) (xy 449.712053 -42.523984) (xy 449.74927 -42.565521) (xy 449.780043 -42.612034)
			(xy 449.803715 -42.662531) (xy 449.819783 -42.715938) (xy 449.827903 -42.771114) (xy 449.828412 -42.799)
			(xy 449.827903 -42.826886) (xy 449.819783 -42.882062) (xy 449.803715 -42.935469) (xy 449.780043 -42.985966)
			(xy 449.74927 -43.032479) (xy 449.712053 -43.074016) (xy 449.669185 -43.109691) (xy 449.621579 -43.138745)
			(xy 449.57025 -43.160557) (xy 449.516293 -43.174663) (xy 449.460856 -43.180763) (xy 449.405122 -43.178726)
			(xy 449.350279 -43.168596) (xy 449.297495 -43.150589) (xy 449.247895 -43.125088) (xy 449.202537 -43.092637)
			(xy 449.162388 -43.053928) (xy 449.128302 -43.009785) (xy 449.101006 -42.96115) (xy 449.081083 -42.909059)
			(xy 449.068957 -42.854622) (xy 449.064886 -42.799) (xy 436.124858 -42.799) (xy 436.124349 -42.826886)
			(xy 436.116229 -42.882062) (xy 436.100161 -42.935469) (xy 436.076489 -42.985966) (xy 436.045716 -43.032479)
			(xy 436.008499 -43.074016) (xy 435.965631 -43.109691) (xy 435.918025 -43.138745) (xy 435.866696 -43.160557)
			(xy 435.812739 -43.174663) (xy 435.757302 -43.180763) (xy 435.701568 -43.178726) (xy 435.646725 -43.168596)
			(xy 435.593941 -43.150589) (xy 435.544341 -43.125088) (xy 435.498983 -43.092637) (xy 435.458834 -43.053928)
			(xy 435.424748 -43.009785) (xy 435.397452 -42.96115) (xy 435.377529 -42.909059) (xy 435.365403 -42.854622)
			(xy 435.361332 -42.799) (xy 428.25879 -42.799) (xy 428.307293 -42.804337) (xy 428.36125 -42.818443)
			(xy 428.412579 -42.840255) (xy 428.460185 -42.869309) (xy 428.503053 -42.904984) (xy 428.54027 -42.946521)
			(xy 428.571043 -42.993034) (xy 428.594715 -43.043531) (xy 428.610783 -43.096938) (xy 428.618903 -43.152114)
			(xy 428.619412 -43.18) (xy 428.618903 -43.207886) (xy 428.610783 -43.263062) (xy 428.594715 -43.316469)
			(xy 428.571043 -43.366966) (xy 428.54027 -43.413479) (xy 428.503053 -43.455016) (xy 428.460185 -43.490691)
			(xy 428.412579 -43.519745) (xy 428.36125 -43.541557) (xy 428.307293 -43.555663) (xy 428.25879 -43.561)
			(xy 432.078382 -43.561) (xy 432.082453 -43.505378) (xy 432.094579 -43.450941) (xy 432.114502 -43.39885)
			(xy 432.141798 -43.350215) (xy 432.175884 -43.306072) (xy 432.216033 -43.267363) (xy 432.261391 -43.234912)
			(xy 432.310991 -43.209411) (xy 432.363775 -43.191404) (xy 432.418618 -43.181274) (xy 432.474352 -43.179237)
			(xy 432.529789 -43.185337) (xy 432.583746 -43.199443) (xy 432.635075 -43.221255) (xy 432.682681 -43.250309)
			(xy 432.725549 -43.285984) (xy 432.762766 -43.327521) (xy 432.793539 -43.374034) (xy 432.817211 -43.424531)
			(xy 432.833279 -43.477938) (xy 432.841399 -43.533114) (xy 432.841908 -43.561) (xy 432.841399 -43.588886)
			(xy 432.833279 -43.644062) (xy 432.817211 -43.697469) (xy 432.793539 -43.747966) (xy 432.762766 -43.794479)
			(xy 432.725549 -43.836016) (xy 432.682681 -43.871691) (xy 432.635075 -43.900745) (xy 432.583746 -43.922557)
			(xy 432.529789 -43.936663) (xy 432.474352 -43.942763) (xy 432.418618 -43.940726) (xy 432.363775 -43.930596)
			(xy 432.310991 -43.912589) (xy 432.261391 -43.887088) (xy 432.216033 -43.854637) (xy 432.175884 -43.815928)
			(xy 432.141798 -43.771785) (xy 432.114502 -43.72315) (xy 432.094579 -43.671059) (xy 432.082453 -43.616622)
			(xy 432.078382 -43.561) (xy 428.25879 -43.561) (xy 428.251856 -43.561763) (xy 428.196122 -43.559726)
			(xy 428.141279 -43.549596) (xy 428.088495 -43.531589) (xy 428.038895 -43.506088) (xy 427.993537 -43.473637)
			(xy 427.953388 -43.434928) (xy 427.919302 -43.390785) (xy 427.892006 -43.34215) (xy 427.872083 -43.290059)
			(xy 427.859957 -43.235622) (xy 427.855886 -43.18) (xy 426.339 -43.18) (xy 426.339 -44.153836) (xy 426.33943 -44.163903)
			(xy 426.347153 -44.182498) (xy 426.353986 -44.189904) (xy 426.76835 -44.604268) (xy 427.856601 -44.604268)
			(xy 427.856602 -44.549726) (xy 427.864364 -44.495739) (xy 427.879731 -44.443407) (xy 427.902389 -44.393794)
			(xy 427.931877 -44.34791) (xy 427.967595 -44.30669) (xy 428.008815 -44.270973) (xy 428.054699 -44.241486)
			(xy 428.104313 -44.218829) (xy 428.156646 -44.203463) (xy 428.210633 -44.195701) (xy 428.237904 -44.195238)
			(xy 428.239174 -44.195238) (xy 428.255899 -44.195412) (xy 428.289222 -44.19834) (xy 428.305722 -44.20108)
			(xy 428.313088 -44.201842) (xy 428.328228 -44.201719) (xy 428.357411 -44.193717) (xy 428.370492 -44.186094)
			(xy 428.382604 -44.177887) (xy 428.401838 -44.155852) (xy 428.414015 -44.129259) (xy 428.41813 -44.100301)
			(xy 428.416466 -44.085764) (xy 428.415196 -44.078652) (xy 428.413418 -44.071286) (xy 428.41291 -44.070016)
			(xy 428.404944 -44.042696) (xy 428.396275 -43.986453) (xy 428.395638 -43.958002) (xy 428.395638 -43.95724)
			(xy 428.396059 -43.929965) (xy 428.403816 -43.875971) (xy 428.419179 -43.82363) (xy 428.441835 -43.774009)
			(xy 428.471322 -43.728116) (xy 428.507041 -43.686888) (xy 428.548263 -43.651162) (xy 428.59415 -43.621667)
			(xy 428.643768 -43.599003) (xy 428.696106 -43.583631) (xy 428.750099 -43.575864) (xy 428.804648 -43.57586)
			(xy 428.858642 -43.583619) (xy 428.910982 -43.598984) (xy 428.960603 -43.621642) (xy 429.006494 -43.65113)
			(xy 429.047722 -43.68685) (xy 429.083446 -43.728074) (xy 429.112939 -43.773962) (xy 429.135602 -43.82358)
			(xy 429.150972 -43.875919) (xy 429.158737 -43.929912) (xy 429.158739 -43.984461) (xy 429.150978 -44.038455)
			(xy 429.135611 -44.090795) (xy 429.112952 -44.140415) (xy 429.083462 -44.186305) (xy 429.04774 -44.227531)
			(xy 429.006516 -44.263254) (xy 428.960627 -44.292746) (xy 428.911007 -44.315407) (xy 428.858668 -44.330775)
			(xy 428.804674 -44.338538) (xy 428.7774 -44.339002) (xy 428.77613 -44.339002) (xy 428.759405 -44.338827)
			(xy 428.726082 -44.3359) (xy 428.709582 -44.33316) (xy 428.702216 -44.332398) (xy 428.687077 -44.332532)
			(xy 428.657894 -44.340527) (xy 428.644812 -44.348146) (xy 428.632733 -44.356398) (xy 428.613497 -44.378418)
			(xy 428.601312 -44.404997) (xy 428.597182 -44.433943) (xy 428.598838 -44.448476) (xy 428.59911 -44.45)
			(xy 438.650632 -44.45) (xy 438.654703 -44.394378) (xy 438.666829 -44.339941) (xy 438.686752 -44.28785)
			(xy 438.714048 -44.239215) (xy 438.748134 -44.195072) (xy 438.788283 -44.156363) (xy 438.833641 -44.123912)
			(xy 438.883241 -44.098411) (xy 438.936025 -44.080404) (xy 438.990868 -44.070274) (xy 439.046602 -44.068237)
			(xy 439.102039 -44.074337) (xy 439.155996 -44.088443) (xy 439.207325 -44.110255) (xy 439.247936 -44.13504)
			(xy 439.926982 -44.13504) (xy 439.931053 -44.079418) (xy 439.943179 -44.024981) (xy 439.963102 -43.97289)
			(xy 439.990398 -43.924255) (xy 440.024484 -43.880112) (xy 440.064633 -43.841403) (xy 440.109991 -43.808952)
			(xy 440.159591 -43.783451) (xy 440.212375 -43.765444) (xy 440.267218 -43.755314) (xy 440.322952 -43.753277)
			(xy 440.378389 -43.759377) (xy 440.432346 -43.773483) (xy 440.483675 -43.795295) (xy 440.531281 -43.824349)
			(xy 440.574149 -43.860024) (xy 440.611366 -43.901561) (xy 440.642139 -43.948074) (xy 440.665811 -43.998571)
			(xy 440.681879 -44.051978) (xy 440.689999 -44.107154) (xy 440.690508 -44.13504) (xy 440.689999 -44.162926)
			(xy 440.685132 -44.196) (xy 449.833492 -44.196) (xy 449.833978 -44.168749) (xy 449.841734 -44.114801)
			(xy 449.857089 -44.062506) (xy 449.879731 -44.012929) (xy 449.909197 -43.967079) (xy 449.944888 -43.925888)
			(xy 449.986079 -43.890197) (xy 450.031929 -43.860731) (xy 450.081506 -43.838089) (xy 450.133801 -43.822734)
			(xy 450.187749 -43.814978) (xy 450.242251 -43.814978) (xy 450.296199 -43.822734) (xy 450.348494 -43.838089)
			(xy 450.398071 -43.860731) (xy 450.443921 -43.890197) (xy 450.485112 -43.925888) (xy 450.520803 -43.967079)
			(xy 450.550269 -44.012929) (xy 450.572911 -44.062506) (xy 450.588266 -44.114801) (xy 450.596022 -44.168749)
			(xy 450.596508 -44.196) (xy 450.596029 -44.223825) (xy 450.587938 -44.278883) (xy 450.571929 -44.332179)
			(xy 450.548341 -44.382582) (xy 450.517675 -44.42902) (xy 450.480584 -44.470506) (xy 450.437855 -44.506158)
			(xy 450.41439 -44.52112) (xy 450.402095 -44.529155) (xy 450.382464 -44.55099) (xy 450.369851 -44.577506)
			(xy 450.365296 -44.606513) (xy 450.369176 -44.635618) (xy 450.38117 -44.662419) (xy 450.400289 -44.684705)
			(xy 450.412358 -44.693078) (xy 450.416422 -44.695364) (xy 450.439315 -44.707819) (xy 450.481855 -44.737923)
			(xy 450.519906 -44.773531) (xy 450.552764 -44.813982) (xy 450.579816 -44.858524) (xy 450.600561 -44.906331)
			(xy 450.614614 -44.956515) (xy 450.621713 -45.008143) (xy 450.622162 -45.0342) (xy 450.621676 -45.061469)
			(xy 450.613914 -45.115453) (xy 450.598549 -45.167783) (xy 450.575892 -45.217393) (xy 450.546406 -45.263274)
			(xy 450.510691 -45.304491) (xy 450.469474 -45.340206) (xy 450.423593 -45.369692) (xy 450.373983 -45.392349)
			(xy 450.321653 -45.407714) (xy 450.267669 -45.415476) (xy 450.213131 -45.415476) (xy 450.159147 -45.407714)
			(xy 450.106817 -45.392349) (xy 450.057207 -45.369692) (xy 450.011326 -45.340206) (xy 449.970109 -45.304491)
			(xy 449.934394 -45.263274) (xy 449.904908 -45.217393) (xy 449.882251 -45.167783) (xy 449.866886 -45.115453)
			(xy 449.859124 -45.061469) (xy 449.858638 -45.0342) (xy 449.859125 -45.006188) (xy 449.867313 -44.950765)
			(xy 449.883513 -44.897135) (xy 449.907377 -44.846447) (xy 449.938392 -44.799792) (xy 449.975894 -44.758171)
			(xy 450.019076 -44.722477) (xy 450.042788 -44.707556) (xy 450.044058 -44.706794) (xy 450.04482 -44.706286)
			(xy 450.048122 -44.704254) (xy 450.051932 -44.701206) (xy 450.06275 -44.69182) (xy 450.079096 -44.668315)
			(xy 450.088267 -44.641195) (xy 450.089541 -44.612594) (xy 450.082817 -44.584765) (xy 450.068626 -44.559901)
			(xy 450.048084 -44.539959) (xy 450.035676 -44.532804) (xy 450.00993 -44.518415) (xy 449.962767 -44.483005)
			(xy 449.921612 -44.440763) (xy 449.887444 -44.392694) (xy 449.861076 -44.339941) (xy 449.843135 -44.28376)
			(xy 449.834049 -44.225488) (xy 449.833492 -44.196) (xy 440.685132 -44.196) (xy 440.681879 -44.218102)
			(xy 440.665811 -44.271509) (xy 440.642139 -44.322006) (xy 440.611366 -44.368519) (xy 440.574149 -44.410056)
			(xy 440.531281 -44.445731) (xy 440.483675 -44.474785) (xy 440.432346 -44.496597) (xy 440.378389 -44.510703)
			(xy 440.322952 -44.516803) (xy 440.267218 -44.514766) (xy 440.212375 -44.504636) (xy 440.159591 -44.486629)
			(xy 440.109991 -44.461128) (xy 440.064633 -44.428677) (xy 440.024484 -44.389968) (xy 439.990398 -44.345825)
			(xy 439.963102 -44.29719) (xy 439.943179 -44.245099) (xy 439.931053 -44.190662) (xy 439.926982 -44.13504)
			(xy 439.247936 -44.13504) (xy 439.254931 -44.139309) (xy 439.297799 -44.174984) (xy 439.335016 -44.216521)
			(xy 439.365789 -44.263034) (xy 439.389461 -44.313531) (xy 439.405529 -44.366938) (xy 439.413649 -44.422114)
			(xy 439.414158 -44.45) (xy 439.413649 -44.477886) (xy 439.405529 -44.533062) (xy 439.389461 -44.586469)
			(xy 439.365789 -44.636966) (xy 439.335016 -44.683479) (xy 439.297799 -44.725016) (xy 439.254931 -44.760691)
			(xy 439.207325 -44.789745) (xy 439.155996 -44.811557) (xy 439.102039 -44.825663) (xy 439.046602 -44.831763)
			(xy 438.990868 -44.829726) (xy 438.936025 -44.819596) (xy 438.883241 -44.801589) (xy 438.833641 -44.776088)
			(xy 438.788283 -44.743637) (xy 438.748134 -44.704928) (xy 438.714048 -44.660785) (xy 438.686752 -44.61215)
			(xy 438.666829 -44.560059) (xy 438.654703 -44.505622) (xy 438.650632 -44.45) (xy 428.59911 -44.45)
			(xy 428.600108 -44.455588) (xy 428.601886 -44.462954) (xy 428.602394 -44.464224) (xy 428.610347 -44.491548)
			(xy 428.619024 -44.547788) (xy 428.619666 -44.576238) (xy 428.619666 -44.577) (xy 428.619199 -44.604271)
			(xy 428.611436 -44.658258) (xy 428.59607 -44.710591) (xy 428.573412 -44.760204) (xy 428.543925 -44.806088)
			(xy 428.508207 -44.847308) (xy 428.466987 -44.883025) (xy 428.421103 -44.912513) (xy 428.37149 -44.93517)
			(xy 428.319157 -44.950537) (xy 428.26517 -44.958299) (xy 428.210628 -44.958298) (xy 428.156641 -44.950536)
			(xy 428.104308 -44.93517) (xy 428.054695 -44.912512) (xy 428.008811 -44.883024) (xy 427.967591 -44.847306)
			(xy 427.931874 -44.806086) (xy 427.902386 -44.760202) (xy 427.879729 -44.710588) (xy 427.864363 -44.658255)
			(xy 427.856601 -44.604268) (xy 426.76835 -44.604268) (xy 426.793914 -44.629832) (xy 426.800765 -44.637228)
			(xy 426.808501 -44.655827) (xy 426.8089 -44.6659) (xy 426.8089 -45.339) (xy 431.697382 -45.339) (xy 431.701453 -45.283378)
			(xy 431.713579 -45.228941) (xy 431.733502 -45.17685) (xy 431.760798 -45.128215) (xy 431.794884 -45.084072)
			(xy 431.835033 -45.045363) (xy 431.880391 -45.012912) (xy 431.929991 -44.987411) (xy 431.982775 -44.969404)
			(xy 432.037618 -44.959274) (xy 432.093352 -44.957237) (xy 432.148789 -44.963337) (xy 432.202746 -44.977443)
			(xy 432.254075 -44.999255) (xy 432.301681 -45.028309) (xy 432.344549 -45.063984) (xy 432.381766 -45.105521)
			(xy 432.412539 -45.152034) (xy 432.436211 -45.202531) (xy 432.452279 -45.255938) (xy 432.460399 -45.311114)
			(xy 432.460908 -45.339) (xy 432.460399 -45.366886) (xy 432.452279 -45.422062) (xy 432.436211 -45.475469)
			(xy 432.412539 -45.525966) (xy 432.381766 -45.572479) (xy 432.363379 -45.593) (xy 436.523382 -45.593)
			(xy 436.527453 -45.537378) (xy 436.539579 -45.482941) (xy 436.559502 -45.43085) (xy 436.586798 -45.382215)
			(xy 436.620884 -45.338072) (xy 436.661033 -45.299363) (xy 436.706391 -45.266912) (xy 436.755991 -45.241411)
			(xy 436.808775 -45.223404) (xy 436.863618 -45.213274) (xy 436.919352 -45.211237) (xy 436.974789 -45.217337)
			(xy 437.028746 -45.231443) (xy 437.080075 -45.253255) (xy 437.127681 -45.282309) (xy 437.170549 -45.317984)
			(xy 437.207766 -45.359521) (xy 437.238539 -45.406034) (xy 437.254743 -45.4406) (xy 447.439032 -45.4406)
			(xy 447.443103 -45.384978) (xy 447.455229 -45.330541) (xy 447.475152 -45.27845) (xy 447.502448 -45.229815)
			(xy 447.536534 -45.185672) (xy 447.576683 -45.146963) (xy 447.622041 -45.114512) (xy 447.671641 -45.089011)
			(xy 447.724425 -45.071004) (xy 447.779268 -45.060874) (xy 447.835002 -45.058837) (xy 447.890439 -45.064937)
			(xy 447.944396 -45.079043) (xy 447.995725 -45.100855) (xy 448.043331 -45.129909) (xy 448.086199 -45.165584)
			(xy 448.123416 -45.207121) (xy 448.154189 -45.253634) (xy 448.177861 -45.304131) (xy 448.193929 -45.357538)
			(xy 448.202049 -45.412714) (xy 448.202558 -45.4406) (xy 448.202049 -45.468486) (xy 448.193929 -45.523662)
			(xy 448.177861 -45.577069) (xy 448.154189 -45.627566) (xy 448.123416 -45.674079) (xy 448.086199 -45.715616)
			(xy 448.043331 -45.751291) (xy 447.995725 -45.780345) (xy 447.944396 -45.802157) (xy 447.890439 -45.816263)
			(xy 447.835002 -45.822363) (xy 447.779268 -45.820326) (xy 447.724425 -45.810196) (xy 447.671641 -45.792189)
			(xy 447.622041 -45.766688) (xy 447.576683 -45.734237) (xy 447.536534 -45.695528) (xy 447.502448 -45.651385)
			(xy 447.475152 -45.60275) (xy 447.455229 -45.550659) (xy 447.443103 -45.496222) (xy 447.439032 -45.4406)
			(xy 437.254743 -45.4406) (xy 437.262211 -45.456531) (xy 437.278279 -45.509938) (xy 437.286399 -45.565114)
			(xy 437.286908 -45.593) (xy 437.286399 -45.620886) (xy 437.278279 -45.676062) (xy 437.262211 -45.729469)
			(xy 437.238539 -45.779966) (xy 437.207766 -45.826479) (xy 437.170549 -45.868016) (xy 437.127681 -45.903691)
			(xy 437.080075 -45.932745) (xy 437.028746 -45.954557) (xy 436.974789 -45.968663) (xy 436.919352 -45.974763)
			(xy 436.863618 -45.972726) (xy 436.808775 -45.962596) (xy 436.755991 -45.944589) (xy 436.706391 -45.919088)
			(xy 436.661033 -45.886637) (xy 436.620884 -45.847928) (xy 436.586798 -45.803785) (xy 436.559502 -45.75515)
			(xy 436.539579 -45.703059) (xy 436.527453 -45.648622) (xy 436.523382 -45.593) (xy 432.363379 -45.593)
			(xy 432.344549 -45.614016) (xy 432.301681 -45.649691) (xy 432.254075 -45.678745) (xy 432.202746 -45.700557)
			(xy 432.148789 -45.714663) (xy 432.093352 -45.720763) (xy 432.037618 -45.718726) (xy 431.982775 -45.708596)
			(xy 431.929991 -45.690589) (xy 431.880391 -45.665088) (xy 431.835033 -45.632637) (xy 431.794884 -45.593928)
			(xy 431.760798 -45.549785) (xy 431.733502 -45.50115) (xy 431.713579 -45.449059) (xy 431.701453 -45.394622)
			(xy 431.697382 -45.339) (xy 426.8089 -45.339) (xy 426.8089 -45.635418) (xy 426.809327 -45.645487)
			(xy 426.817046 -45.664086) (xy 426.823886 -45.671486) (xy 427.1264 -45.974) (xy 427.855886 -45.974)
			(xy 427.859957 -45.918378) (xy 427.872083 -45.863941) (xy 427.892006 -45.81185) (xy 427.919302 -45.763215)
			(xy 427.953388 -45.719072) (xy 427.993537 -45.680363) (xy 428.038895 -45.647912) (xy 428.088495 -45.622411)
			(xy 428.141279 -45.604404) (xy 428.196122 -45.594274) (xy 428.251856 -45.592237) (xy 428.307293 -45.598337)
			(xy 428.36125 -45.612443) (xy 428.412579 -45.634255) (xy 428.460185 -45.663309) (xy 428.503053 -45.698984)
			(xy 428.54027 -45.740521) (xy 428.571043 -45.787034) (xy 428.594715 -45.837531) (xy 428.610783 -45.890938)
			(xy 428.618903 -45.946114) (xy 428.619412 -45.974) (xy 428.618903 -46.001886) (xy 428.610783 -46.057062)
			(xy 428.594715 -46.110469) (xy 428.571043 -46.160966) (xy 428.54027 -46.207479) (xy 428.521883 -46.228)
			(xy 431.697382 -46.228) (xy 431.701453 -46.172378) (xy 431.713579 -46.117941) (xy 431.733502 -46.06585)
			(xy 431.760798 -46.017215) (xy 431.794884 -45.973072) (xy 431.835033 -45.934363) (xy 431.880391 -45.901912)
			(xy 431.929991 -45.876411) (xy 431.982775 -45.858404) (xy 432.037618 -45.848274) (xy 432.093352 -45.846237)
			(xy 432.148789 -45.852337) (xy 432.202746 -45.866443) (xy 432.254075 -45.888255) (xy 432.301681 -45.917309)
			(xy 432.344549 -45.952984) (xy 432.381766 -45.994521) (xy 432.412539 -46.041034) (xy 432.436211 -46.091531)
			(xy 432.43906 -46.101) (xy 449.216778 -46.101) (xy 449.220851 -46.045341) (xy 449.232986 -45.990868)
			(xy 449.252922 -45.938742) (xy 449.280236 -45.890074) (xy 449.314344 -45.845902) (xy 449.354521 -45.807167)
			(xy 449.399909 -45.774695) (xy 449.449541 -45.749177) (xy 449.502361 -45.731158) (xy 449.55724 -45.721021)
			(xy 449.613011 -45.718983) (xy 449.668485 -45.725086) (xy 449.722478 -45.739202) (xy 449.773841 -45.761029)
			(xy 449.821479 -45.790102) (xy 449.864375 -45.825801) (xy 449.901617 -45.867365) (xy 449.932411 -45.913909)
			(xy 449.956099 -45.96444) (xy 449.972177 -46.017882) (xy 449.980303 -46.073096) (xy 449.980812 -46.101)
			(xy 449.980303 -46.128904) (xy 449.972177 -46.184118) (xy 449.956099 -46.23756) (xy 449.932411 -46.288091)
			(xy 449.901617 -46.334635) (xy 449.864375 -46.376199) (xy 449.821479 -46.411898) (xy 449.773841 -46.440971)
			(xy 449.722478 -46.462798) (xy 449.668485 -46.476914) (xy 449.613011 -46.483017) (xy 449.55724 -46.480979)
			(xy 449.502361 -46.470842) (xy 449.449541 -46.452823) (xy 449.399909 -46.427305) (xy 449.354521 -46.394833)
			(xy 449.314344 -46.356098) (xy 449.280236 -46.311926) (xy 449.252922 -46.263258) (xy 449.232986 -46.211132)
			(xy 449.220851 -46.156659) (xy 449.216778 -46.101) (xy 432.43906 -46.101) (xy 432.452279 -46.144938)
			(xy 432.460399 -46.200114) (xy 432.460908 -46.228) (xy 432.460399 -46.255886) (xy 432.452279 -46.311062)
			(xy 432.436211 -46.364469) (xy 432.412539 -46.414966) (xy 432.381766 -46.461479) (xy 432.344549 -46.503016)
			(xy 432.301681 -46.538691) (xy 432.254075 -46.567745) (xy 432.202746 -46.589557) (xy 432.148789 -46.603663)
			(xy 432.100286 -46.609) (xy 438.783982 -46.609) (xy 438.788053 -46.553378) (xy 438.800179 -46.498941)
			(xy 438.820102 -46.44685) (xy 438.847398 -46.398215) (xy 438.881484 -46.354072) (xy 438.921633 -46.315363)
			(xy 438.966991 -46.282912) (xy 439.016591 -46.257411) (xy 439.069375 -46.239404) (xy 439.124218 -46.229274)
			(xy 439.179952 -46.227237) (xy 439.235389 -46.233337) (xy 439.289346 -46.247443) (xy 439.340675 -46.269255)
			(xy 439.388281 -46.298309) (xy 439.431149 -46.333984) (xy 439.468366 -46.375521) (xy 439.499139 -46.422034)
			(xy 439.522811 -46.472531) (xy 439.538879 -46.525938) (xy 439.546999 -46.581114) (xy 439.547508 -46.609)
			(xy 439.546999 -46.636886) (xy 439.538879 -46.692062) (xy 439.522811 -46.745469) (xy 439.499139 -46.795966)
			(xy 439.468366 -46.842479) (xy 439.431149 -46.884016) (xy 439.388281 -46.919691) (xy 439.340675 -46.948745)
			(xy 439.289346 -46.970557) (xy 439.235389 -46.984663) (xy 439.179952 -46.990763) (xy 439.124218 -46.988726)
			(xy 439.069375 -46.978596) (xy 439.016591 -46.960589) (xy 438.966991 -46.935088) (xy 438.921633 -46.902637)
			(xy 438.881484 -46.863928) (xy 438.847398 -46.819785) (xy 438.820102 -46.77115) (xy 438.800179 -46.719059)
			(xy 438.788053 -46.664622) (xy 438.783982 -46.609) (xy 432.100286 -46.609) (xy 432.093352 -46.609763)
			(xy 432.037618 -46.607726) (xy 431.982775 -46.597596) (xy 431.929991 -46.579589) (xy 431.880391 -46.554088)
			(xy 431.835033 -46.521637) (xy 431.794884 -46.482928) (xy 431.760798 -46.438785) (xy 431.733502 -46.39015)
			(xy 431.713579 -46.338059) (xy 431.701453 -46.283622) (xy 431.697382 -46.228) (xy 428.521883 -46.228)
			(xy 428.503053 -46.249016) (xy 428.460185 -46.284691) (xy 428.412579 -46.313745) (xy 428.36125 -46.335557)
			(xy 428.307293 -46.349663) (xy 428.251856 -46.355763) (xy 428.196122 -46.353726) (xy 428.141279 -46.343596)
			(xy 428.088495 -46.325589) (xy 428.038895 -46.300088) (xy 427.993537 -46.267637) (xy 427.953388 -46.228928)
			(xy 427.919302 -46.184785) (xy 427.892006 -46.13615) (xy 427.872083 -46.084059) (xy 427.859957 -46.029622)
			(xy 427.855886 -45.974) (xy 427.1264 -45.974) (xy 428.141384 -46.988984) (xy 428.164498 -46.99635)
			(xy 428.182602 -46.993021) (xy 428.219243 -46.989461) (xy 428.23765 -46.989238) (xy 428.252956 -46.989369)
			(xy 428.283473 -46.991786) (xy 428.29861 -46.994064) (xy 428.305722 -46.993048) (xy 428.309975 -46.992277)
			(xy 428.318151 -46.98947) (xy 428.321978 -46.98746) (xy 428.329598 -46.983142) (xy 428.390812 -46.917356)
			(xy 428.39706 -46.91012) (xy 428.404105 -46.892363) (xy 428.404528 -46.882812) (xy 428.404528 -46.873414)
			(xy 428.403512 -46.868334) (xy 428.399871 -46.849557) (xy 428.395924 -46.811512) (xy 428.395638 -46.792388)
			(xy 428.395638 -46.79188) (xy 428.396126 -46.764611) (xy 428.40389 -46.710628) (xy 428.419258 -46.6583)
			(xy 428.441916 -46.608692) (xy 428.471404 -46.562813) (xy 428.507121 -46.521597) (xy 428.548339 -46.485884)
			(xy 428.594221 -46.4564) (xy 428.643831 -46.433746) (xy 428.696161 -46.418383) (xy 428.750144 -46.410623)
			(xy 428.804682 -46.410625) (xy 428.858665 -46.418389) (xy 428.910994 -46.433756) (xy 428.960603 -46.456413)
			(xy 429.006482 -46.4859) (xy 429.047698 -46.521616) (xy 429.083412 -46.562834) (xy 429.112897 -46.608715)
			(xy 429.135551 -46.658325) (xy 429.150916 -46.710654) (xy 429.158676 -46.764638) (xy 429.158675 -46.819176)
			(xy 429.150913 -46.873159) (xy 429.135547 -46.925487) (xy 429.11289 -46.975097) (xy 429.083404 -47.020977)
			(xy 429.047689 -47.062194) (xy 429.006471 -47.097908) (xy 428.960591 -47.127393) (xy 428.910981 -47.150049)
			(xy 428.858652 -47.165414) (xy 428.804669 -47.173176) (xy 428.7774 -47.173642) (xy 428.763959 -47.173579)
			(xy 428.737137 -47.171802) (xy 428.723806 -47.170086) (xy 428.71136 -47.168308) (xy 428.6885 -47.176436)
			(xy 428.623476 -47.245778) (xy 428.616241 -47.254164) (xy 428.609117 -47.275108) (xy 428.60976 -47.286164)
			(xy 428.614264 -47.307084) (xy 428.619104 -47.349603) (xy 428.619412 -47.371) (xy 433.094382 -47.371)
			(xy 433.098453 -47.315378) (xy 433.110579 -47.260941) (xy 433.130502 -47.20885) (xy 433.157798 -47.160215)
			(xy 433.191884 -47.116072) (xy 433.232033 -47.077363) (xy 433.277391 -47.044912) (xy 433.326991 -47.019411)
			(xy 433.379775 -47.001404) (xy 433.434618 -46.991274) (xy 433.490352 -46.989237) (xy 433.545789 -46.995337)
			(xy 433.599746 -47.009443) (xy 433.651075 -47.031255) (xy 433.698681 -47.060309) (xy 433.741549 -47.095984)
			(xy 433.778766 -47.137521) (xy 433.809539 -47.184034) (xy 433.833211 -47.234531) (xy 433.849279 -47.287938)
			(xy 433.857399 -47.343114) (xy 433.857908 -47.371) (xy 433.857399 -47.398886) (xy 433.849279 -47.454062)
			(xy 433.83606 -47.498) (xy 434.218332 -47.498) (xy 434.222403 -47.442378) (xy 434.234529 -47.387941)
			(xy 434.254452 -47.33585) (xy 434.281748 -47.287215) (xy 434.315834 -47.243072) (xy 434.355983 -47.204363)
			(xy 434.401341 -47.171912) (xy 434.450941 -47.146411) (xy 434.503725 -47.128404) (xy 434.558568 -47.118274)
			(xy 434.614302 -47.116237) (xy 434.669739 -47.122337) (xy 434.723696 -47.136443) (xy 434.775025 -47.158255)
			(xy 434.822631 -47.187309) (xy 434.865499 -47.222984) (xy 434.902716 -47.264521) (xy 434.933489 -47.311034)
			(xy 434.957161 -47.361531) (xy 434.973229 -47.414938) (xy 434.981349 -47.470114) (xy 434.981858 -47.498)
			(xy 434.981349 -47.525886) (xy 434.975734 -47.56404) (xy 445.200022 -47.56404) (xy 445.204093 -47.508418)
			(xy 445.216219 -47.453981) (xy 445.236142 -47.40189) (xy 445.263438 -47.353255) (xy 445.297524 -47.309112)
			(xy 445.337673 -47.270403) (xy 445.383031 -47.237952) (xy 445.432631 -47.212451) (xy 445.485415 -47.194444)
			(xy 445.540258 -47.184314) (xy 445.595992 -47.182277) (xy 445.651429 -47.188377) (xy 445.705386 -47.202483)
			(xy 445.756715 -47.224295) (xy 445.804321 -47.253349) (xy 445.847189 -47.289024) (xy 445.884406 -47.330561)
			(xy 445.915179 -47.377074) (xy 445.938851 -47.427571) (xy 445.954919 -47.480978) (xy 445.963039 -47.536154)
			(xy 445.963548 -47.56404) (xy 448.689982 -47.56404) (xy 448.694053 -47.508418) (xy 448.706179 -47.453981)
			(xy 448.726102 -47.40189) (xy 448.753398 -47.353255) (xy 448.787484 -47.309112) (xy 448.827633 -47.270403)
			(xy 448.872991 -47.237952) (xy 448.922591 -47.212451) (xy 448.975375 -47.194444) (xy 449.030218 -47.184314)
			(xy 449.085952 -47.182277) (xy 449.141389 -47.188377) (xy 449.195346 -47.202483) (xy 449.246675 -47.224295)
			(xy 449.294281 -47.253349) (xy 449.337149 -47.289024) (xy 449.374366 -47.330561) (xy 449.405139 -47.377074)
			(xy 449.428811 -47.427571) (xy 449.444879 -47.480978) (xy 449.452999 -47.536154) (xy 449.453508 -47.56404)
			(xy 449.452999 -47.591926) (xy 449.448132 -47.625) (xy 456.843382 -47.625) (xy 456.847453 -47.569378)
			(xy 456.859579 -47.514941) (xy 456.879502 -47.46285) (xy 456.906798 -47.414215) (xy 456.940884 -47.370072)
			(xy 456.981033 -47.331363) (xy 457.026391 -47.298912) (xy 457.075991 -47.273411) (xy 457.128775 -47.255404)
			(xy 457.183618 -47.245274) (xy 457.239352 -47.243237) (xy 457.246286 -47.244) (xy 459.738982 -47.244)
			(xy 459.743053 -47.188378) (xy 459.755179 -47.133941) (xy 459.775102 -47.08185) (xy 459.802398 -47.033215)
			(xy 459.836484 -46.989072) (xy 459.876633 -46.950363) (xy 459.921991 -46.917912) (xy 459.971591 -46.892411)
			(xy 460.024375 -46.874404) (xy 460.079218 -46.864274) (xy 460.134952 -46.862237) (xy 460.190389 -46.868337)
			(xy 460.244346 -46.882443) (xy 460.295675 -46.904255) (xy 460.343281 -46.933309) (xy 460.386149 -46.968984)
			(xy 460.423366 -47.010521) (xy 460.454139 -47.057034) (xy 460.477811 -47.107531) (xy 460.493879 -47.160938)
			(xy 460.501999 -47.216114) (xy 460.502508 -47.244) (xy 460.501999 -47.271886) (xy 460.493879 -47.327062)
			(xy 460.477811 -47.380469) (xy 460.454139 -47.430966) (xy 460.423366 -47.477479) (xy 460.386149 -47.519016)
			(xy 460.343281 -47.554691) (xy 460.295675 -47.583745) (xy 460.244346 -47.605557) (xy 460.190389 -47.619663)
			(xy 460.134952 -47.625763) (xy 460.079218 -47.623726) (xy 460.024375 -47.613596) (xy 459.971591 -47.595589)
			(xy 459.921991 -47.570088) (xy 459.876633 -47.537637) (xy 459.836484 -47.498928) (xy 459.802398 -47.454785)
			(xy 459.775102 -47.40615) (xy 459.755179 -47.354059) (xy 459.743053 -47.299622) (xy 459.738982 -47.244)
			(xy 457.246286 -47.244) (xy 457.294789 -47.249337) (xy 457.348746 -47.263443) (xy 457.400075 -47.285255)
			(xy 457.447681 -47.314309) (xy 457.490549 -47.349984) (xy 457.527766 -47.391521) (xy 457.558539 -47.438034)
			(xy 457.582211 -47.488531) (xy 457.598279 -47.541938) (xy 457.606399 -47.597114) (xy 457.606908 -47.625)
			(xy 457.606399 -47.652886) (xy 457.598279 -47.708062) (xy 457.582211 -47.761469) (xy 457.558539 -47.811966)
			(xy 457.527766 -47.858479) (xy 457.490549 -47.900016) (xy 457.447681 -47.935691) (xy 457.400075 -47.964745)
			(xy 457.348746 -47.986557) (xy 457.294789 -48.000663) (xy 457.239352 -48.006763) (xy 457.183618 -48.004726)
			(xy 457.128775 -47.994596) (xy 457.075991 -47.976589) (xy 457.026391 -47.951088) (xy 456.981033 -47.918637)
			(xy 456.940884 -47.879928) (xy 456.906798 -47.835785) (xy 456.879502 -47.78715) (xy 456.859579 -47.735059)
			(xy 456.847453 -47.680622) (xy 456.843382 -47.625) (xy 449.448132 -47.625) (xy 449.444879 -47.647102)
			(xy 449.428811 -47.700509) (xy 449.405139 -47.751006) (xy 449.374366 -47.797519) (xy 449.337149 -47.839056)
			(xy 449.294281 -47.874731) (xy 449.246675 -47.903785) (xy 449.195346 -47.925597) (xy 449.141389 -47.939703)
			(xy 449.085952 -47.945803) (xy 449.030218 -47.943766) (xy 448.975375 -47.933636) (xy 448.922591 -47.915629)
			(xy 448.872991 -47.890128) (xy 448.827633 -47.857677) (xy 448.787484 -47.818968) (xy 448.753398 -47.774825)
			(xy 448.726102 -47.72619) (xy 448.706179 -47.674099) (xy 448.694053 -47.619662) (xy 448.689982 -47.56404)
			(xy 445.963548 -47.56404) (xy 445.963039 -47.591926) (xy 445.954919 -47.647102) (xy 445.938851 -47.700509)
			(xy 445.915179 -47.751006) (xy 445.884406 -47.797519) (xy 445.847189 -47.839056) (xy 445.804321 -47.874731)
			(xy 445.756715 -47.903785) (xy 445.705386 -47.925597) (xy 445.651429 -47.939703) (xy 445.595992 -47.945803)
			(xy 445.540258 -47.943766) (xy 445.485415 -47.933636) (xy 445.432631 -47.915629) (xy 445.383031 -47.890128)
			(xy 445.337673 -47.857677) (xy 445.297524 -47.818968) (xy 445.263438 -47.774825) (xy 445.236142 -47.72619)
			(xy 445.216219 -47.674099) (xy 445.204093 -47.619662) (xy 445.200022 -47.56404) (xy 434.975734 -47.56404)
			(xy 434.973229 -47.581062) (xy 434.957161 -47.634469) (xy 434.933489 -47.684966) (xy 434.902716 -47.731479)
			(xy 434.865499 -47.773016) (xy 434.822631 -47.808691) (xy 434.775025 -47.837745) (xy 434.723696 -47.859557)
			(xy 434.669739 -47.873663) (xy 434.614302 -47.879763) (xy 434.558568 -47.877726) (xy 434.503725 -47.867596)
			(xy 434.450941 -47.849589) (xy 434.401341 -47.824088) (xy 434.355983 -47.791637) (xy 434.315834 -47.752928)
			(xy 434.281748 -47.708785) (xy 434.254452 -47.66015) (xy 434.234529 -47.608059) (xy 434.222403 -47.553622)
			(xy 434.218332 -47.498) (xy 433.83606 -47.498) (xy 433.833211 -47.507469) (xy 433.809539 -47.557966)
			(xy 433.778766 -47.604479) (xy 433.741549 -47.646016) (xy 433.698681 -47.681691) (xy 433.651075 -47.710745)
			(xy 433.599746 -47.732557) (xy 433.545789 -47.746663) (xy 433.490352 -47.752763) (xy 433.434618 -47.750726)
			(xy 433.379775 -47.740596) (xy 433.326991 -47.722589) (xy 433.277391 -47.697088) (xy 433.232033 -47.664637)
			(xy 433.191884 -47.625928) (xy 433.157798 -47.581785) (xy 433.130502 -47.53315) (xy 433.110579 -47.481059)
			(xy 433.098453 -47.426622) (xy 433.094382 -47.371) (xy 428.619412 -47.371) (xy 428.619179 -47.389406)
			(xy 428.615618 -47.426046) (xy 428.6123 -47.444152) (xy 428.619666 -47.467266) (xy 429.2854 -48.133)
			(xy 451.229982 -48.133) (xy 451.234053 -48.077378) (xy 451.246179 -48.022941) (xy 451.266102 -47.97085)
			(xy 451.293398 -47.922215) (xy 451.327484 -47.878072) (xy 451.367633 -47.839363) (xy 451.412991 -47.806912)
			(xy 451.462591 -47.781411) (xy 451.515375 -47.763404) (xy 451.570218 -47.753274) (xy 451.625952 -47.751237)
			(xy 451.681389 -47.757337) (xy 451.735346 -47.771443) (xy 451.786675 -47.793255) (xy 451.834281 -47.822309)
			(xy 451.877149 -47.857984) (xy 451.914366 -47.899521) (xy 451.945139 -47.946034) (xy 451.968811 -47.996531)
			(xy 451.984879 -48.049938) (xy 451.992999 -48.105114) (xy 451.993508 -48.133) (xy 451.992999 -48.160886)
			(xy 451.984879 -48.216062) (xy 451.968811 -48.269469) (xy 451.945139 -48.319966) (xy 451.914366 -48.366479)
			(xy 451.877149 -48.408016) (xy 451.834281 -48.443691) (xy 451.786675 -48.472745) (xy 451.735346 -48.494557)
			(xy 451.681389 -48.508663) (xy 451.625952 -48.514763) (xy 451.570218 -48.512726) (xy 451.515375 -48.502596)
			(xy 451.462591 -48.484589) (xy 451.412991 -48.459088) (xy 451.367633 -48.426637) (xy 451.327484 -48.387928)
			(xy 451.293398 -48.343785) (xy 451.266102 -48.29515) (xy 451.246179 -48.243059) (xy 451.234053 -48.188622)
			(xy 451.229982 -48.133) (xy 429.2854 -48.133) (xy 429.7934 -48.641) (xy 441.257942 -48.641) (xy 441.262013 -48.585378)
			(xy 441.274139 -48.530941) (xy 441.294062 -48.47885) (xy 441.321358 -48.430215) (xy 441.355444 -48.386072)
			(xy 441.395593 -48.347363) (xy 441.440951 -48.314912) (xy 441.490551 -48.289411) (xy 441.543335 -48.271404)
			(xy 441.598178 -48.261274) (xy 441.653912 -48.259237) (xy 441.709349 -48.265337) (xy 441.763306 -48.279443)
			(xy 441.814635 -48.301255) (xy 441.862241 -48.330309) (xy 441.905109 -48.365984) (xy 441.942326 -48.407521)
			(xy 441.973099 -48.454034) (xy 441.996771 -48.504531) (xy 442.012839 -48.557938) (xy 442.015344 -48.57496)
			(xy 443.101728 -48.57496) (xy 443.105801 -48.519301) (xy 443.117936 -48.464828) (xy 443.137872 -48.412702)
			(xy 443.165186 -48.364034) (xy 443.199294 -48.319862) (xy 443.239471 -48.281127) (xy 443.284859 -48.248655)
			(xy 443.334491 -48.223137) (xy 443.387311 -48.205118) (xy 443.44219 -48.194981) (xy 443.497961 -48.192943)
			(xy 443.553435 -48.199046) (xy 443.607428 -48.213162) (xy 443.658791 -48.234989) (xy 443.706429 -48.264062)
			(xy 443.749325 -48.299761) (xy 443.786567 -48.341325) (xy 443.817361 -48.387869) (xy 443.841049 -48.4384)
			(xy 443.857127 -48.491842) (xy 443.865253 -48.547056) (xy 443.865762 -48.57496) (xy 443.865253 -48.602864)
			(xy 443.857127 -48.658078) (xy 443.841049 -48.71152) (xy 443.817361 -48.762051) (xy 443.786567 -48.808595)
			(xy 443.749325 -48.850159) (xy 443.706429 -48.885858) (xy 443.658791 -48.914931) (xy 443.607428 -48.936758)
			(xy 443.553435 -48.950874) (xy 443.497961 -48.956977) (xy 443.44219 -48.954939) (xy 443.387311 -48.944802)
			(xy 443.334491 -48.926783) (xy 443.284859 -48.901265) (xy 443.239471 -48.868793) (xy 443.199294 -48.830058)
			(xy 443.165186 -48.785886) (xy 443.137872 -48.737218) (xy 443.117936 -48.685092) (xy 443.105801 -48.630619)
			(xy 443.101728 -48.57496) (xy 442.015344 -48.57496) (xy 442.020959 -48.613114) (xy 442.021468 -48.641)
			(xy 442.020959 -48.668886) (xy 442.012839 -48.724062) (xy 441.996771 -48.777469) (xy 441.973099 -48.827966)
			(xy 441.942326 -48.874479) (xy 441.905109 -48.916016) (xy 441.862241 -48.951691) (xy 441.814635 -48.980745)
			(xy 441.763306 -49.002557) (xy 441.709349 -49.016663) (xy 441.653912 -49.022763) (xy 441.598178 -49.020726)
			(xy 441.543335 -49.010596) (xy 441.490551 -48.992589) (xy 441.440951 -48.967088) (xy 441.395593 -48.934637)
			(xy 441.355444 -48.895928) (xy 441.321358 -48.851785) (xy 441.294062 -48.80315) (xy 441.274139 -48.751059)
			(xy 441.262013 -48.696622) (xy 441.257942 -48.641) (xy 429.7934 -48.641) (xy 430.62144 -49.46904)
			(xy 436.904382 -49.46904) (xy 436.908453 -49.413418) (xy 436.920579 -49.358981) (xy 436.940502 -49.30689)
			(xy 436.967798 -49.258255) (xy 437.001884 -49.214112) (xy 437.042033 -49.175403) (xy 437.087391 -49.142952)
			(xy 437.136991 -49.117451) (xy 437.189775 -49.099444) (xy 437.244618 -49.089314) (xy 437.300352 -49.087277)
			(xy 437.355789 -49.093377) (xy 437.409746 -49.107483) (xy 437.461075 -49.129295) (xy 437.508681 -49.158349)
			(xy 437.551549 -49.194024) (xy 437.588766 -49.235561) (xy 437.619539 -49.282074) (xy 437.643211 -49.332571)
			(xy 437.659279 -49.385978) (xy 437.667399 -49.441154) (xy 437.667908 -49.46904) (xy 437.667399 -49.496926)
			(xy 437.662532 -49.53) (xy 459.256382 -49.53) (xy 459.260453 -49.474378) (xy 459.272579 -49.419941)
			(xy 459.292502 -49.36785) (xy 459.319798 -49.319215) (xy 459.353884 -49.275072) (xy 459.394033 -49.236363)
			(xy 459.439391 -49.203912) (xy 459.488991 -49.178411) (xy 459.541775 -49.160404) (xy 459.596618 -49.150274)
			(xy 459.652352 -49.148237) (xy 459.707789 -49.154337) (xy 459.761746 -49.168443) (xy 459.813075 -49.190255)
			(xy 459.860681 -49.219309) (xy 459.903549 -49.254984) (xy 459.940766 -49.296521) (xy 459.971539 -49.343034)
			(xy 459.995211 -49.393531) (xy 460.011279 -49.446938) (xy 460.019399 -49.502114) (xy 460.019908 -49.53)
			(xy 460.019399 -49.557886) (xy 460.011279 -49.613062) (xy 459.995211 -49.666469) (xy 459.971539 -49.716966)
			(xy 459.940766 -49.763479) (xy 459.903549 -49.805016) (xy 459.860681 -49.840691) (xy 459.813075 -49.869745)
			(xy 459.761746 -49.891557) (xy 459.707789 -49.905663) (xy 459.652352 -49.911763) (xy 459.596618 -49.909726)
			(xy 459.541775 -49.899596) (xy 459.488991 -49.881589) (xy 459.439391 -49.856088) (xy 459.394033 -49.823637)
			(xy 459.353884 -49.784928) (xy 459.319798 -49.740785) (xy 459.292502 -49.69215) (xy 459.272579 -49.640059)
			(xy 459.260453 -49.585622) (xy 459.256382 -49.53) (xy 437.662532 -49.53) (xy 437.659279 -49.552102)
			(xy 437.643211 -49.605509) (xy 437.619539 -49.656006) (xy 437.588766 -49.702519) (xy 437.551549 -49.744056)
			(xy 437.508681 -49.779731) (xy 437.461075 -49.808785) (xy 437.409746 -49.830597) (xy 437.355789 -49.844703)
			(xy 437.300352 -49.850803) (xy 437.244618 -49.848766) (xy 437.189775 -49.838636) (xy 437.136991 -49.820629)
			(xy 437.087391 -49.795128) (xy 437.042033 -49.762677) (xy 437.001884 -49.723968) (xy 436.967798 -49.679825)
			(xy 436.940502 -49.63119) (xy 436.920579 -49.579099) (xy 436.908453 -49.524662) (xy 436.904382 -49.46904)
			(xy 430.62144 -49.46904) (xy 431.5714 -50.419) (xy 436.904382 -50.419) (xy 436.908453 -50.363378)
			(xy 436.920579 -50.308941) (xy 436.940502 -50.25685) (xy 436.967798 -50.208215) (xy 437.001884 -50.164072)
			(xy 437.042033 -50.125363) (xy 437.087391 -50.092912) (xy 437.136991 -50.067411) (xy 437.189775 -50.049404)
			(xy 437.244618 -50.039274) (xy 437.300352 -50.037237) (xy 437.355789 -50.043337) (xy 437.409746 -50.057443)
			(xy 437.461075 -50.079255) (xy 437.508681 -50.108309) (xy 437.551549 -50.143984) (xy 437.588766 -50.185521)
			(xy 437.619539 -50.232034) (xy 437.643211 -50.282531) (xy 437.64606 -50.292) (xy 444.260984 -50.292)
			(xy 444.265055 -50.236378) (xy 444.277181 -50.181941) (xy 444.297104 -50.12985) (xy 444.3244 -50.081215)
			(xy 444.358486 -50.037072) (xy 444.398635 -49.998363) (xy 444.443993 -49.965912) (xy 444.493593 -49.940411)
			(xy 444.546377 -49.922404) (xy 444.60122 -49.912274) (xy 444.656954 -49.910237) (xy 444.712391 -49.916337)
			(xy 444.766348 -49.930443) (xy 444.817677 -49.952255) (xy 444.865283 -49.981309) (xy 444.908151 -50.016984)
			(xy 444.945368 -50.058521) (xy 444.976141 -50.105034) (xy 444.999813 -50.155531) (xy 445.015881 -50.208938)
			(xy 445.024001 -50.264114) (xy 445.02451 -50.292) (xy 445.024001 -50.319886) (xy 445.015881 -50.375062)
			(xy 444.999813 -50.428469) (xy 444.976141 -50.478966) (xy 444.945368 -50.525479) (xy 444.908151 -50.567016)
			(xy 444.865283 -50.602691) (xy 444.817677 -50.631745) (xy 444.766348 -50.653557) (xy 444.712391 -50.667663)
			(xy 444.656954 -50.673763) (xy 444.60122 -50.671726) (xy 444.546377 -50.661596) (xy 444.493593 -50.643589)
			(xy 444.443993 -50.618088) (xy 444.398635 -50.585637) (xy 444.358486 -50.546928) (xy 444.3244 -50.502785)
			(xy 444.297104 -50.45415) (xy 444.277181 -50.402059) (xy 444.265055 -50.347622) (xy 444.260984 -50.292)
			(xy 437.64606 -50.292) (xy 437.659279 -50.335938) (xy 437.667399 -50.391114) (xy 437.667908 -50.419)
			(xy 437.667399 -50.446886) (xy 437.659279 -50.502062) (xy 437.643211 -50.555469) (xy 437.619539 -50.605966)
			(xy 437.588766 -50.652479) (xy 437.551549 -50.694016) (xy 437.508681 -50.729691) (xy 437.461075 -50.758745)
			(xy 437.409746 -50.780557) (xy 437.355789 -50.794663) (xy 437.300352 -50.800763) (xy 437.244618 -50.798726)
			(xy 437.189775 -50.788596) (xy 437.136991 -50.770589) (xy 437.087391 -50.745088) (xy 437.042033 -50.712637)
			(xy 437.001884 -50.673928) (xy 436.967798 -50.629785) (xy 436.940502 -50.58115) (xy 436.920579 -50.529059)
			(xy 436.908453 -50.474622) (xy 436.904382 -50.419) (xy 431.5714 -50.419) (xy 433.249651 -52.097251)
			(xy 436.879978 -52.097251) (xy 436.879978 -52.042749) (xy 436.887734 -51.988801) (xy 436.903089 -51.936506)
			(xy 436.925731 -51.886929) (xy 436.955197 -51.841079) (xy 436.990888 -51.799888) (xy 437.032079 -51.764197)
			(xy 437.077929 -51.734731) (xy 437.127506 -51.712089) (xy 437.179801 -51.696734) (xy 437.233749 -51.688978)
			(xy 437.261 -51.688492) (xy 437.288476 -51.688971) (xy 437.342857 -51.696867) (xy 437.395543 -51.712482)
			(xy 437.445445 -51.735492) (xy 437.491531 -51.765421) (xy 437.532847 -51.801652) (xy 437.568539 -51.843434)
			(xy 437.59787 -51.889903) (xy 437.609488 -51.914806) (xy 437.615429 -51.927063) (xy 437.632631 -51.948163)
			(xy 437.654807 -51.963955) (xy 437.680372 -51.973312) (xy 437.707503 -51.975567) (xy 437.734262 -51.970557)
			(xy 437.75874 -51.958642) (xy 437.779189 -51.94067) (xy 437.787034 -51.929538) (xy 437.803863 -51.905103)
			(xy 437.843869 -51.861292) (xy 437.890175 -51.824201) (xy 437.941663 -51.794725) (xy 437.997094 -51.773574)
			(xy 438.055131 -51.761258) (xy 438.084722 -51.759104) (xy 438.105804 -51.758596) (xy 438.133032 -51.759116)
			(xy 438.186924 -51.766931) (xy 438.239158 -51.78233) (xy 438.288672 -51.805) (xy 438.305757 -51.816)
			(xy 443.590932 -51.816) (xy 443.595003 -51.760378) (xy 443.607129 -51.705941) (xy 443.627052 -51.65385)
			(xy 443.654348 -51.605215) (xy 443.688434 -51.561072) (xy 443.728583 -51.522363) (xy 443.773941 -51.489912)
			(xy 443.823541 -51.464411) (xy 443.876325 -51.446404) (xy 443.931168 -51.436274) (xy 443.986902 -51.434237)
			(xy 444.042339 -51.440337) (xy 444.096296 -51.454443) (xy 444.147625 -51.476255) (xy 444.195231 -51.505309)
			(xy 444.238099 -51.540984) (xy 444.275316 -51.582521) (xy 444.306089 -51.629034) (xy 444.329761 -51.679531)
			(xy 444.345829 -51.732938) (xy 444.353949 -51.788114) (xy 444.354458 -51.816) (xy 444.353949 -51.843886)
			(xy 444.345829 -51.899062) (xy 444.329761 -51.952469) (xy 444.306089 -52.002966) (xy 444.275316 -52.049479)
			(xy 444.238099 -52.091016) (xy 444.195231 -52.126691) (xy 444.147625 -52.155745) (xy 444.096296 -52.177557)
			(xy 444.042339 -52.191663) (xy 443.986902 -52.197763) (xy 443.931168 -52.195726) (xy 443.876325 -52.185596)
			(xy 443.823541 -52.167589) (xy 443.773941 -52.142088) (xy 443.728583 -52.109637) (xy 443.688434 -52.070928)
			(xy 443.654348 -52.026785) (xy 443.627052 -51.97815) (xy 443.607129 -51.926059) (xy 443.595003 -51.871622)
			(xy 443.590932 -51.816) (xy 438.305757 -51.816) (xy 438.334459 -51.83448) (xy 438.375589 -51.870171)
			(xy 438.411225 -51.911348) (xy 438.440644 -51.957174) (xy 438.463248 -52.006718) (xy 438.478577 -52.058972)
			(xy 438.48632 -52.112876) (xy 438.486804 -52.140104) (xy 438.486326 -52.167356) (xy 438.478569 -52.221304)
			(xy 438.463213 -52.273599) (xy 438.440571 -52.323176) (xy 438.411104 -52.369027) (xy 438.375412 -52.410217)
			(xy 438.334221 -52.445909) (xy 438.288369 -52.475375) (xy 438.238791 -52.498016) (xy 438.186496 -52.51337)
			(xy 438.132548 -52.521126) (xy 438.105296 -52.521612) (xy 438.105042 -52.521612) (xy 438.0992 -52.521358)
			(xy 438.097422 -52.521104) (xy 438.08523 -52.521104) (xy 438.059071 -52.519267) (xy 438.007578 -52.509352)
			(xy 437.957928 -52.492479) (xy 437.911055 -52.468968) (xy 437.867843 -52.43926) (xy 437.829105 -52.403915)
			(xy 437.795572 -52.363599) (xy 437.767875 -52.319071) (xy 437.756808 -52.295298) (xy 437.750873 -52.283038)
			(xy 437.73367 -52.261937) (xy 437.711494 -52.246144) (xy 437.685927 -52.236786) (xy 437.658795 -52.234532)
			(xy 437.632035 -52.239542) (xy 437.607556 -52.25146) (xy 437.587107 -52.269433) (xy 437.579262 -52.280566)
			(xy 437.564018 -52.302724) (xy 437.528321 -52.342953) (xy 437.487331 -52.377773) (xy 437.441859 -52.406495)
			(xy 437.392806 -52.428549) (xy 437.341142 -52.443499) (xy 437.287892 -52.451048) (xy 437.261 -52.451508)
			(xy 437.233749 -52.451022) (xy 437.179801 -52.443266) (xy 437.127506 -52.427911) (xy 437.077929 -52.405269)
			(xy 437.032079 -52.375803) (xy 436.990888 -52.340112) (xy 436.955197 -52.298921) (xy 436.925731 -52.253071)
			(xy 436.903089 -52.203494) (xy 436.887734 -52.151199) (xy 436.879978 -52.097251) (xy 433.249651 -52.097251)
			(xy 437.525414 -56.373014) (xy 437.532268 -56.380409) (xy 437.54001 -56.399008) (xy 437.5404 -56.409082)
			(xy 437.5404 -61.087) (xy 441.730892 -61.087) (xy 441.73136 -61.05963) (xy 441.739178 -61.005451)
			(xy 441.754666 -60.952948) (xy 441.777508 -60.903201) (xy 441.807231 -60.857234) (xy 441.824872 -60.836302)
			(xy 441.830968 -60.82919) (xy 441.837318 -60.812426) (xy 441.837318 -60.726574) (xy 441.830968 -60.70981)
			(xy 441.824872 -60.702698) (xy 441.807229 -60.681766) (xy 441.777501 -60.635799) (xy 441.754653 -60.586053)
			(xy 441.739155 -60.533551) (xy 441.731325 -60.479371) (xy 441.731325 -60.424629) (xy 441.739155 -60.370449)
			(xy 441.754653 -60.317947) (xy 441.777501 -60.268201) (xy 441.807229 -60.222234) (xy 441.824872 -60.201302)
			(xy 441.830968 -60.19419) (xy 441.837318 -60.177426) (xy 441.837318 -60.091574) (xy 441.830968 -60.07481)
			(xy 441.824872 -60.067698) (xy 441.807229 -60.046766) (xy 441.777501 -60.000799) (xy 441.754653 -59.951053)
			(xy 441.739155 -59.898551) (xy 441.731325 -59.844371) (xy 441.731325 -59.789629) (xy 441.739155 -59.735449)
			(xy 441.754653 -59.682947) (xy 441.777501 -59.633201) (xy 441.807229 -59.587234) (xy 441.824872 -59.566302)
			(xy 441.830968 -59.55919) (xy 441.837318 -59.542426) (xy 441.837318 -59.456574) (xy 441.830968 -59.43981)
			(xy 441.824872 -59.432698) (xy 441.807214 -59.411781) (xy 441.777506 -59.365804) (xy 441.754674 -59.316052)
			(xy 441.739187 -59.263548) (xy 441.731364 -59.20937) (xy 441.730892 -59.182) (xy 441.731378 -59.154749)
			(xy 441.739134 -59.100801) (xy 441.754489 -59.048506) (xy 441.777131 -58.998929) (xy 441.806597 -58.953079)
			(xy 441.842288 -58.911888) (xy 441.883479 -58.876197) (xy 441.929329 -58.846731) (xy 441.978906 -58.824089)
			(xy 442.031201 -58.808734) (xy 442.085149 -58.800978) (xy 442.139651 -58.800978) (xy 442.193599 -58.808734)
			(xy 442.245894 -58.824089) (xy 442.295471 -58.846731) (xy 442.341321 -58.876197) (xy 442.382512 -58.911888)
			(xy 442.418203 -58.953079) (xy 442.447669 -58.998929) (xy 442.470311 -59.048506) (xy 442.485666 -59.100801)
			(xy 442.493422 -59.154749) (xy 442.493908 -59.182) (xy 442.49344 -59.20937) (xy 442.485622 -59.263549)
			(xy 442.470134 -59.316052) (xy 442.447292 -59.365799) (xy 442.417569 -59.411766) (xy 442.399928 -59.432698)
			(xy 442.393832 -59.43981) (xy 442.387482 -59.456574) (xy 442.387482 -59.542426) (xy 442.393832 -59.55919)
			(xy 442.399928 -59.566302) (xy 442.417571 -59.587234) (xy 442.447299 -59.633201) (xy 442.470147 -59.682947)
			(xy 442.485645 -59.735449) (xy 442.493475 -59.789629) (xy 442.493475 -59.844371) (xy 442.485645 -59.898551)
			(xy 442.470147 -59.951053) (xy 442.447299 -60.000799) (xy 442.417571 -60.046766) (xy 442.399928 -60.067698)
			(xy 442.393832 -60.07481) (xy 442.387482 -60.091574) (xy 442.387482 -60.177426) (xy 442.393832 -60.19419)
			(xy 442.399928 -60.201302) (xy 442.417571 -60.222234) (xy 442.447299 -60.268201) (xy 442.470147 -60.317947)
			(xy 442.485645 -60.370449) (xy 442.493475 -60.424629) (xy 442.493475 -60.479371) (xy 442.485645 -60.533551)
			(xy 442.470147 -60.586053) (xy 442.447299 -60.635799) (xy 442.417571 -60.681766) (xy 442.399928 -60.702698)
			(xy 442.393832 -60.70981) (xy 442.387482 -60.726574) (xy 442.387482 -60.812426) (xy 442.393832 -60.82919)
			(xy 442.399928 -60.836302) (xy 442.417586 -60.857219) (xy 442.447294 -60.903196) (xy 442.470126 -60.952948)
			(xy 442.485613 -61.005452) (xy 442.493436 -61.05963) (xy 442.493908 -61.087) (xy 444.524892 -61.087)
			(xy 444.52536 -61.05963) (xy 444.533178 -61.005451) (xy 444.548666 -60.952948) (xy 444.571508 -60.903201)
			(xy 444.601231 -60.857234) (xy 444.618872 -60.836302) (xy 444.624968 -60.82919) (xy 444.631318 -60.812426)
			(xy 444.631318 -60.726574) (xy 444.624968 -60.70981) (xy 444.618872 -60.702698) (xy 444.601229 -60.681766)
			(xy 444.571501 -60.635799) (xy 444.548653 -60.586053) (xy 444.533155 -60.533551) (xy 444.525325 -60.479371)
			(xy 444.525325 -60.424629) (xy 444.533155 -60.370449) (xy 444.548653 -60.317947) (xy 444.571501 -60.268201)
			(xy 444.601229 -60.222234) (xy 444.618872 -60.201302) (xy 444.624968 -60.19419) (xy 444.631318 -60.177426)
			(xy 444.631318 -60.091574) (xy 444.624968 -60.07481) (xy 444.618872 -60.067698) (xy 444.601229 -60.046766)
			(xy 444.571501 -60.000799) (xy 444.548653 -59.951053) (xy 444.533155 -59.898551) (xy 444.525325 -59.844371)
			(xy 444.525325 -59.789629) (xy 444.533155 -59.735449) (xy 444.548653 -59.682947) (xy 444.571501 -59.633201)
			(xy 444.601229 -59.587234) (xy 444.618872 -59.566302) (xy 444.624968 -59.55919) (xy 444.631318 -59.542426)
			(xy 444.631318 -59.456574) (xy 444.624968 -59.43981) (xy 444.618872 -59.432698) (xy 444.601214 -59.411781)
			(xy 444.571506 -59.365804) (xy 444.548674 -59.316052) (xy 444.533187 -59.263548) (xy 444.525364 -59.20937)
			(xy 444.524892 -59.182) (xy 444.525378 -59.154749) (xy 444.533134 -59.100801) (xy 444.548489 -59.048506)
			(xy 444.571131 -58.998929) (xy 444.600597 -58.953079) (xy 444.636288 -58.911888) (xy 444.677479 -58.876197)
			(xy 444.723329 -58.846731) (xy 444.772906 -58.824089) (xy 444.825201 -58.808734) (xy 444.879149 -58.800978)
			(xy 444.933651 -58.800978) (xy 444.987599 -58.808734) (xy 445.039894 -58.824089) (xy 445.089471 -58.846731)
			(xy 445.135321 -58.876197) (xy 445.176512 -58.911888) (xy 445.212203 -58.953079) (xy 445.241669 -58.998929)
			(xy 445.264311 -59.048506) (xy 445.279666 -59.100801) (xy 445.287422 -59.154749) (xy 445.287908 -59.182)
			(xy 445.28744 -59.20937) (xy 445.279622 -59.263549) (xy 445.264134 -59.316052) (xy 445.241292 -59.365799)
			(xy 445.211569 -59.411766) (xy 445.193928 -59.432698) (xy 445.187832 -59.43981) (xy 445.181482 -59.456574)
			(xy 445.181482 -59.542426) (xy 445.187832 -59.55919) (xy 445.193928 -59.566302) (xy 445.211571 -59.587234)
			(xy 445.241299 -59.633201) (xy 445.264147 -59.682947) (xy 445.279645 -59.735449) (xy 445.287475 -59.789629)
			(xy 445.287475 -59.844371) (xy 445.279645 -59.898551) (xy 445.264147 -59.951053) (xy 445.241299 -60.000799)
			(xy 445.211571 -60.046766) (xy 445.193928 -60.067698) (xy 445.187832 -60.07481) (xy 445.181482 -60.091574)
			(xy 445.181482 -60.177426) (xy 445.187832 -60.19419) (xy 445.193928 -60.201302) (xy 445.211571 -60.222234)
			(xy 445.241299 -60.268201) (xy 445.264147 -60.317947) (xy 445.279645 -60.370449) (xy 445.287475 -60.424629)
			(xy 445.287475 -60.479371) (xy 445.279645 -60.533551) (xy 445.264147 -60.586053) (xy 445.241299 -60.635799)
			(xy 445.211571 -60.681766) (xy 445.193928 -60.702698) (xy 445.187832 -60.70981) (xy 445.181482 -60.726574)
			(xy 445.181482 -60.812426) (xy 445.187832 -60.82919) (xy 445.193928 -60.836302) (xy 445.211586 -60.857219)
			(xy 445.241294 -60.903196) (xy 445.264126 -60.952948) (xy 445.279613 -61.005452) (xy 445.287436 -61.05963)
			(xy 445.287908 -61.087) (xy 445.287422 -61.114251) (xy 445.279666 -61.168199) (xy 445.264311 -61.220494)
			(xy 445.241669 -61.270071) (xy 445.212203 -61.315921) (xy 445.176512 -61.357112) (xy 445.135321 -61.392803)
			(xy 445.089471 -61.422269) (xy 445.039894 -61.444911) (xy 444.987599 -61.460266) (xy 444.933651 -61.468022)
			(xy 444.879149 -61.468022) (xy 444.825201 -61.460266) (xy 444.772906 -61.444911) (xy 444.723329 -61.422269)
			(xy 444.677479 -61.392803) (xy 444.636288 -61.357112) (xy 444.600597 -61.315921) (xy 444.571131 -61.270071)
			(xy 444.548489 -61.220494) (xy 444.533134 -61.168199) (xy 444.525378 -61.114251) (xy 444.524892 -61.087)
			(xy 442.493908 -61.087) (xy 442.493422 -61.114251) (xy 442.485666 -61.168199) (xy 442.470311 -61.220494)
			(xy 442.447669 -61.270071) (xy 442.418203 -61.315921) (xy 442.382512 -61.357112) (xy 442.341321 -61.392803)
			(xy 442.295471 -61.422269) (xy 442.245894 -61.444911) (xy 442.193599 -61.460266) (xy 442.139651 -61.468022)
			(xy 442.085149 -61.468022) (xy 442.031201 -61.460266) (xy 441.978906 -61.444911) (xy 441.929329 -61.422269)
			(xy 441.883479 -61.392803) (xy 441.842288 -61.357112) (xy 441.806597 -61.315921) (xy 441.777131 -61.270071)
			(xy 441.754489 -61.220494) (xy 441.739134 -61.168199) (xy 441.731378 -61.114251) (xy 441.730892 -61.087)
			(xy 437.5404 -61.087) (xy 437.5404 -61.670692) (xy 448.29603 -61.670692) (xy 448.296603 -61.641777)
			(xy 448.305319 -61.584608) (xy 448.322566 -61.52941) (xy 448.347947 -61.477447) (xy 448.380881 -61.429912)
			(xy 448.420614 -61.387894) (xy 448.443096 -61.369702) (xy 448.451852 -61.362134) (xy 448.462039 -61.34138)
			(xy 448.462654 -61.329824) (xy 448.462654 -61.24956) (xy 448.462065 -61.237994) (xy 448.451885 -61.217222)
			(xy 448.443096 -61.209682) (xy 448.420603 -61.191502) (xy 448.380869 -61.14948) (xy 448.347931 -61.101943)
			(xy 448.322544 -61.049979) (xy 448.30529 -60.99478) (xy 448.296564 -60.937609) (xy 448.29603 -60.908692)
			(xy 448.296516 -60.881441) (xy 448.304272 -60.827493) (xy 448.319627 -60.775198) (xy 448.342269 -60.725621)
			(xy 448.371735 -60.679771) (xy 448.407426 -60.63858) (xy 448.448617 -60.602889) (xy 448.494467 -60.573423)
			(xy 448.544044 -60.550781) (xy 448.596339 -60.535426) (xy 448.650287 -60.52767) (xy 448.704789 -60.52767)
			(xy 448.758737 -60.535426) (xy 448.811032 -60.550781) (xy 448.860609 -60.573423) (xy 448.906459 -60.602889)
			(xy 448.94765 -60.63858) (xy 448.983341 -60.679771) (xy 449.012807 -60.725621) (xy 449.035449 -60.775198)
			(xy 449.050804 -60.827493) (xy 449.05856 -60.881441) (xy 449.059046 -60.908692) (xy 449.058542 -60.93761)
			(xy 449.049813 -60.994783) (xy 449.032554 -61.049983) (xy 449.007159 -61.101945) (xy 448.974212 -61.149478)
			(xy 448.934467 -61.191493) (xy 448.91198 -61.209682) (xy 448.903227 -61.217252) (xy 448.893039 -61.238005)
			(xy 448.892422 -61.24956) (xy 448.892422 -61.329824) (xy 448.893028 -61.341387) (xy 448.903197 -61.36216)
			(xy 448.91198 -61.369702) (xy 448.93446 -61.387897) (xy 448.974197 -61.429915) (xy 449.007137 -61.477449)
			(xy 449.032526 -61.52941) (xy 449.049782 -61.584607) (xy 449.058511 -61.641776) (xy 449.059046 -61.670692)
			(xy 450.58203 -61.670692) (xy 450.582603 -61.641777) (xy 450.591319 -61.584608) (xy 450.608566 -61.52941)
			(xy 450.633947 -61.477447) (xy 450.666881 -61.429912) (xy 450.706614 -61.387894) (xy 450.729096 -61.369702)
			(xy 450.737852 -61.362134) (xy 450.748039 -61.34138) (xy 450.748654 -61.329824) (xy 450.748654 -61.24956)
			(xy 450.748065 -61.237994) (xy 450.737885 -61.217222) (xy 450.729096 -61.209682) (xy 450.706603 -61.191502)
			(xy 450.666869 -61.14948) (xy 450.633931 -61.101943) (xy 450.608544 -61.049979) (xy 450.59129 -60.99478)
			(xy 450.582564 -60.937609) (xy 450.58203 -60.908692) (xy 450.582516 -60.881441) (xy 450.590272 -60.827493)
			(xy 450.605627 -60.775198) (xy 450.628269 -60.725621) (xy 450.657735 -60.679771) (xy 450.693426 -60.63858)
			(xy 450.734617 -60.602889) (xy 450.780467 -60.573423) (xy 450.830044 -60.550781) (xy 450.882339 -60.535426)
			(xy 450.936287 -60.52767) (xy 450.990789 -60.52767) (xy 451.044737 -60.535426) (xy 451.097032 -60.550781)
			(xy 451.146609 -60.573423) (xy 451.192459 -60.602889) (xy 451.23365 -60.63858) (xy 451.269341 -60.679771)
			(xy 451.298807 -60.725621) (xy 451.321449 -60.775198) (xy 451.336804 -60.827493) (xy 451.34456 -60.881441)
			(xy 451.345046 -60.908692) (xy 451.344542 -60.93761) (xy 451.335813 -60.994783) (xy 451.318554 -61.049983)
			(xy 451.293159 -61.101945) (xy 451.260212 -61.149478) (xy 451.220467 -61.191493) (xy 451.19798 -61.209682)
			(xy 451.189227 -61.217252) (xy 451.179039 -61.238005) (xy 451.178422 -61.24956) (xy 451.178422 -61.329824)
			(xy 451.179028 -61.341387) (xy 451.189197 -61.36216) (xy 451.19798 -61.369702) (xy 451.22046 -61.387897)
			(xy 451.260197 -61.429915) (xy 451.293137 -61.477449) (xy 451.318526 -61.52941) (xy 451.335782 -61.584607)
			(xy 451.344511 -61.641776) (xy 451.345046 -61.670692) (xy 452.74103 -61.670692) (xy 452.741603 -61.641777)
			(xy 452.750319 -61.584608) (xy 452.767566 -61.52941) (xy 452.792947 -61.477447) (xy 452.825881 -61.429912)
			(xy 452.865614 -61.387894) (xy 452.888096 -61.369702) (xy 452.896852 -61.362134) (xy 452.907039 -61.34138)
			(xy 452.907654 -61.329824) (xy 452.907654 -61.24956) (xy 452.907065 -61.237994) (xy 452.896885 -61.217222)
			(xy 452.888096 -61.209682) (xy 452.865603 -61.191502) (xy 452.825869 -61.14948) (xy 452.792931 -61.101943)
			(xy 452.767544 -61.049979) (xy 452.75029 -60.99478) (xy 452.741564 -60.937609) (xy 452.74103 -60.908692)
			(xy 452.741516 -60.881441) (xy 452.749272 -60.827493) (xy 452.764627 -60.775198) (xy 452.787269 -60.725621)
			(xy 452.816735 -60.679771) (xy 452.852426 -60.63858) (xy 452.893617 -60.602889) (xy 452.939467 -60.573423)
			(xy 452.989044 -60.550781) (xy 453.041339 -60.535426) (xy 453.095287 -60.52767) (xy 453.149789 -60.52767)
			(xy 453.203737 -60.535426) (xy 453.256032 -60.550781) (xy 453.305609 -60.573423) (xy 453.351459 -60.602889)
			(xy 453.39265 -60.63858) (xy 453.428341 -60.679771) (xy 453.457807 -60.725621) (xy 453.480449 -60.775198)
			(xy 453.495804 -60.827493) (xy 453.50356 -60.881441) (xy 453.504046 -60.908692) (xy 453.503542 -60.93761)
			(xy 453.494813 -60.994783) (xy 453.477554 -61.049983) (xy 453.452159 -61.101945) (xy 453.419212 -61.149478)
			(xy 453.379467 -61.191493) (xy 453.35698 -61.209682) (xy 453.348227 -61.217252) (xy 453.338039 -61.238005)
			(xy 453.337422 -61.24956) (xy 453.337422 -61.329824) (xy 453.338028 -61.341387) (xy 453.348197 -61.36216)
			(xy 453.35698 -61.369702) (xy 453.37946 -61.387897) (xy 453.419197 -61.429915) (xy 453.452137 -61.477449)
			(xy 453.477526 -61.52941) (xy 453.494782 -61.584607) (xy 453.503511 -61.641776) (xy 453.504046 -61.670692)
			(xy 453.50356 -61.697943) (xy 453.495804 -61.751891) (xy 453.480449 -61.804186) (xy 453.459982 -61.849)
			(xy 454.176382 -61.849) (xy 454.180453 -61.793378) (xy 454.192579 -61.738941) (xy 454.212502 -61.68685)
			(xy 454.239798 -61.638215) (xy 454.273884 -61.594072) (xy 454.314033 -61.555363) (xy 454.359391 -61.522912)
			(xy 454.408991 -61.497411) (xy 454.461775 -61.479404) (xy 454.516618 -61.469274) (xy 454.572352 -61.467237)
			(xy 454.627789 -61.473337) (xy 454.681746 -61.487443) (xy 454.733075 -61.509255) (xy 454.780681 -61.538309)
			(xy 454.823549 -61.573984) (xy 454.860766 -61.615521) (xy 454.891539 -61.662034) (xy 454.915211 -61.712531)
			(xy 454.931279 -61.765938) (xy 454.939399 -61.821114) (xy 454.939908 -61.849) (xy 454.939399 -61.876886)
			(xy 454.931279 -61.932062) (xy 454.915211 -61.985469) (xy 454.891539 -62.035966) (xy 454.860766 -62.082479)
			(xy 454.823549 -62.124016) (xy 454.780681 -62.159691) (xy 454.733075 -62.188745) (xy 454.681746 -62.210557)
			(xy 454.627789 -62.224663) (xy 454.572352 -62.230763) (xy 454.516618 -62.228726) (xy 454.461775 -62.218596)
			(xy 454.408991 -62.200589) (xy 454.359391 -62.175088) (xy 454.314033 -62.142637) (xy 454.273884 -62.103928)
			(xy 454.239798 -62.059785) (xy 454.212502 -62.01115) (xy 454.192579 -61.959059) (xy 454.180453 -61.904622)
			(xy 454.176382 -61.849) (xy 453.459982 -61.849) (xy 453.457807 -61.853763) (xy 453.428341 -61.899613)
			(xy 453.39265 -61.940804) (xy 453.351459 -61.976495) (xy 453.305609 -62.005961) (xy 453.256032 -62.028603)
			(xy 453.203737 -62.043958) (xy 453.149789 -62.051714) (xy 453.095287 -62.051714) (xy 453.041339 -62.043958)
			(xy 452.989044 -62.028603) (xy 452.939467 -62.005961) (xy 452.893617 -61.976495) (xy 452.852426 -61.940804)
			(xy 452.816735 -61.899613) (xy 452.787269 -61.853763) (xy 452.764627 -61.804186) (xy 452.749272 -61.751891)
			(xy 452.741516 -61.697943) (xy 452.74103 -61.670692) (xy 451.345046 -61.670692) (xy 451.34456 -61.697943)
			(xy 451.336804 -61.751891) (xy 451.321449 -61.804186) (xy 451.298807 -61.853763) (xy 451.269341 -61.899613)
			(xy 451.23365 -61.940804) (xy 451.192459 -61.976495) (xy 451.146609 -62.005961) (xy 451.097032 -62.028603)
			(xy 451.044737 -62.043958) (xy 450.990789 -62.051714) (xy 450.936287 -62.051714) (xy 450.882339 -62.043958)
			(xy 450.830044 -62.028603) (xy 450.780467 -62.005961) (xy 450.734617 -61.976495) (xy 450.693426 -61.940804)
			(xy 450.657735 -61.899613) (xy 450.628269 -61.853763) (xy 450.605627 -61.804186) (xy 450.590272 -61.751891)
			(xy 450.582516 -61.697943) (xy 450.58203 -61.670692) (xy 449.059046 -61.670692) (xy 449.05856 -61.697943)
			(xy 449.050804 -61.751891) (xy 449.035449 -61.804186) (xy 449.012807 -61.853763) (xy 448.983341 -61.899613)
			(xy 448.94765 -61.940804) (xy 448.906459 -61.976495) (xy 448.860609 -62.005961) (xy 448.811032 -62.028603)
			(xy 448.758737 -62.043958) (xy 448.704789 -62.051714) (xy 448.650287 -62.051714) (xy 448.596339 -62.043958)
			(xy 448.544044 -62.028603) (xy 448.494467 -62.005961) (xy 448.448617 -61.976495) (xy 448.407426 -61.940804)
			(xy 448.371735 -61.899613) (xy 448.342269 -61.853763) (xy 448.319627 -61.804186) (xy 448.304272 -61.751891)
			(xy 448.296516 -61.697943) (xy 448.29603 -61.670692) (xy 437.5404 -61.670692) (xy 437.5404 -76.432918)
			(xy 437.540827 -76.442987) (xy 437.548546 -76.461586) (xy 437.555386 -76.468986) (xy 438.516014 -77.429614)
			(xy 438.523409 -77.436468) (xy 438.542008 -77.44421) (xy 438.552082 -77.4446) (xy 460.226918 -77.4446)
			(xy 460.235554 -77.443838) (xy 460.243072 -77.442236) (xy 460.25676 -77.435259) (xy 460.262478 -77.430122)
			(xy 461.953356 -75.739244) (xy 461.960198 -75.731845) (xy 461.967919 -75.713246) (xy 461.968342 -75.703176)
			(xy 461.968342 -48.167798) (xy 461.955388 -48.144684) (xy 461.943704 -48.137826) (xy 461.870806 -48.093884)
			(xy 461.86192 -48.088988) (xy 461.841874 -48.085966) (xy 461.831944 -48.088042) (xy 461.825594 -48.089566)
			(xy 461.816196 -48.093122) (xy 461.813402 -48.094138) (xy 461.810354 -48.095408) (xy 461.809084 -48.095916)
			(xy 461.78335 -48.10771) (xy 461.729264 -48.124413) (xy 461.673302 -48.132933) (xy 461.645 -48.133508)
			(xy 461.617749 -48.133022) (xy 461.563801 -48.125266) (xy 461.511506 -48.109911) (xy 461.461929 -48.087269)
			(xy 461.416079 -48.057803) (xy 461.374888 -48.022112) (xy 461.339197 -47.980921) (xy 461.309731 -47.935071)
			(xy 461.287089 -47.885494) (xy 461.271734 -47.833199) (xy 461.263978 -47.779251) (xy 461.263978 -47.724749)
			(xy 461.271734 -47.670801) (xy 461.287089 -47.618506) (xy 461.309731 -47.568929) (xy 461.339197 -47.523079)
			(xy 461.374888 -47.481888) (xy 461.416079 -47.446197) (xy 461.461929 -47.416731) (xy 461.511506 -47.394089)
			(xy 461.563801 -47.378734) (xy 461.617749 -47.370978) (xy 461.645 -47.370492) (xy 461.674284 -47.371039)
			(xy 461.732157 -47.380033) (xy 461.787967 -47.397793) (xy 461.814418 -47.41037) (xy 461.814926 -47.410624)
			(xy 461.82026 -47.413164) (xy 461.832452 -47.416212) (xy 461.83296 -47.416212) (xy 461.840072 -47.418244)
			(xy 461.856836 -47.416974) (xy 461.864964 -47.413672) (xy 461.869282 -47.412148) (xy 461.944212 -47.366174)
			(xy 461.95137 -47.36134) (xy 461.962197 -47.347897) (xy 461.967952 -47.331624) (xy 461.968342 -47.322994)
			(xy 461.968342 -31.434786) (xy 461.967759 -31.423036) (xy 461.957337 -31.401975) (xy 461.93863 -31.387754)
			(xy 461.927194 -31.385002) (xy 461.834738 -31.366968) (xy 461.822312 -31.365224) (xy 461.798339 -31.372539)
			(xy 461.789018 -31.380938) (xy 461.772762 -31.397194) (xy 461.768698 -31.406846) (xy 461.768444 -31.407354)
			(xy 461.767682 -31.409386) (xy 461.729573 -31.503218) (xy 461.646924 -31.688137) (xy 461.557047 -31.869653)
			(xy 461.460084 -32.047484) (xy 461.356184 -32.221354) (xy 461.245509 -32.390991) (xy 461.128233 -32.556134)
			(xy 461.004536 -32.716524) (xy 460.874611 -32.871912) (xy 460.73866 -33.022056) (xy 460.596896 -33.166723)
			(xy 460.449537 -33.305689) (xy 460.296814 -33.438736) (xy 460.138964 -33.565658) (xy 459.976232 -33.686257)
			(xy 459.808872 -33.800346) (xy 459.637143 -33.907748) (xy 459.461314 -34.008296) (xy 459.281656 -34.101832)
			(xy 459.098451 -34.188212) (xy 458.911982 -34.267302) (xy 458.722539 -34.338978) (xy 458.530418 -34.403128)
			(xy 458.335917 -34.459654) (xy 458.139338 -34.508467) (xy 457.940988 -34.549491) (xy 457.741174 -34.582662)
			(xy 457.540208 -34.60793) (xy 457.338402 -34.625254) (xy 457.136069 -34.634607) (xy 456.933526 -34.635976)
			(xy 456.731085 -34.629357) (xy 456.529064 -34.614762) (xy 456.327774 -34.592213) (xy 456.127531 -34.561745)
			(xy 455.928644 -34.523405) (xy 455.731424 -34.477253) (xy 455.536176 -34.423361) (xy 455.343206 -34.361812)
			(xy 455.152812 -34.292703) (xy 454.965291 -34.216141) (xy 454.780935 -34.132244) (xy 454.60003 -34.041144)
			(xy 454.422858 -33.942982) (xy 454.249693 -33.83791) (xy 454.080807 -33.726093) (xy 453.91646 -33.607703)
			(xy 453.756909 -33.482926) (xy 453.602402 -33.351955) (xy 453.453179 -33.214994) (xy 453.309472 -33.072256)
			(xy 453.171505 -32.923962) (xy 453.039493 -32.770344) (xy 452.91364 -32.61164) (xy 452.794142 -32.448098)
			(xy 452.681185 -32.279971) (xy 452.574945 -32.107521) (xy 452.475587 -31.931017) (xy 452.383266 -31.750732)
			(xy 452.298125 -31.566947) (xy 452.220297 -31.379948) (xy 452.149902 -31.190026) (xy 452.08705 -30.997476)
			(xy 452.031839 -30.802598) (xy 451.984354 -30.605694) (xy 451.944671 -30.407071) (xy 451.912849 -30.207038)
			(xy 451.888939 -30.005906) (xy 451.872979 -29.803987) (xy 451.864992 -29.601596) (xy 451.864476 -29.500322)
			(xy 451.864476 -24.500332) (xy 451.864974 -24.398963) (xy 451.872974 -24.196383) (xy 451.888963 -23.994277)
			(xy 451.912915 -23.792959) (xy 451.944793 -23.592743) (xy 451.984549 -23.393941) (xy 452.032119 -23.196863)
			(xy 452.08743 -23.001816) (xy 452.150395 -22.809103) (xy 452.220917 -22.619026) (xy 452.298885 -22.43188)
			(xy 452.384178 -22.247957) (xy 452.476663 -22.067543) (xy 452.576197 -21.89092) (xy 452.682623 -21.718362)
			(xy 452.795776 -21.550139) (xy 452.915481 -21.386513) (xy 453.041549 -21.227738) (xy 453.173785 -21.074063)
			(xy 453.311984 -20.925726) (xy 453.455928 -20.782958) (xy 453.605395 -20.645982) (xy 453.760151 -20.515012)
			(xy 453.919956 -20.390252) (xy 454.084559 -20.271895) (xy 454.253706 -20.160127) (xy 454.427131 -20.055121)
			(xy 454.604566 -19.957041) (xy 454.785733 -19.86604) (xy 454.97035 -19.78226) (xy 455.15813 -19.705831)
			(xy 455.34878 -19.636872) (xy 455.542003 -19.575492) (xy 455.737497 -19.521784) (xy 455.934959 -19.475834)
			(xy 456.134081 -19.437712) (xy 456.334552 -19.407479) (xy 456.53606 -19.38518) (xy 456.738291 -19.370852)
			(xy 456.94093 -19.364515) (xy 457.143661 -19.366181) (xy 457.346168 -19.375847) (xy 457.548136 -19.393497)
			(xy 457.74925 -19.419103) (xy 457.949197 -19.452627) (xy 458.147666 -19.494016) (xy 458.344346 -19.543205)
			(xy 458.538932 -19.600118) (xy 458.73112 -19.664666) (xy 458.92061 -19.736748) (xy 459.107109 -19.816253)
			(xy 459.290324 -19.903056) (xy 459.469972 -19.997021) (xy 459.64577 -20.098004) (xy 459.817447 -20.205845)
			(xy 459.984734 -20.320378) (xy 460.14737 -20.441424) (xy 460.305103 -20.568794) (xy 460.457686 -20.702289)
			(xy 460.604882 -20.841703) (xy 460.746461 -20.986816) (xy 460.882203 -21.137405) (xy 461.011896 -21.293233)
			(xy 461.135338 -21.454058) (xy 461.252337 -21.619629) (xy 461.362711 -21.789689) (xy 461.466287 -21.963972)
			(xy 461.562904 -22.142207) (xy 461.652412 -22.324116) (xy 461.734671 -22.509416) (xy 461.772508 -22.60346)
			(xy 461.772508 -22.603714) (xy 461.777482 -22.614382) (xy 461.795073 -22.629979) (xy 461.817759 -22.636151)
			(xy 461.829404 -22.634448) (xy 461.927194 -22.615652) (xy 461.938589 -22.61282) (xy 461.957238 -22.598596)
			(xy 461.967677 -22.577593) (xy 461.968342 -22.565868) (xy 461.968342 -19.392392) (xy 461.960722 -19.373596)
			(xy 461.953356 -19.366484) (xy 460.641954 -18.055082) (xy 460.634557 -18.048234) (xy 460.615958 -18.040503)
			(xy 460.605886 -18.040096) (xy 444.999872 -18.040096) (xy 444.887949 -18.039596) (xy 444.664246 -18.031606)
			(xy 444.44097 -18.015636) (xy 444.218406 -17.991708) (xy 443.996839 -17.959851) (xy 443.776549 -17.920106)
			(xy 443.557819 -17.872524) (xy 443.340926 -17.817166) (xy 443.126147 -17.754102) (xy 442.913756 -17.683412)
			(xy 442.704023 -17.605187) (xy 442.497216 -17.519525) (xy 442.293597 -17.426538) (xy 442.093428 -17.326342)
			(xy 441.896962 -17.219065) (xy 441.70445 -17.104845) (xy 441.516138 -16.983826) (xy 441.332265 -16.856163)
			(xy 441.153065 -16.722019) (xy 440.978768 -16.581565) (xy 440.809594 -16.434979) (xy 440.645761 -16.282448)
			(xy 440.487475 -16.124167) (xy 440.33494 -15.960338) (xy 440.188349 -15.791169) (xy 440.04789 -15.616875)
			(xy 439.913741 -15.43768) (xy 439.786073 -15.25381) (xy 439.665049 -15.065501) (xy 439.550823 -14.872993)
			(xy 439.443541 -14.67653) (xy 439.343339 -14.476363) (xy 439.250346 -14.272748) (xy 439.164679 -14.065943)
			(xy 439.086447 -13.856212) (xy 439.015751 -13.643823) (xy 438.952681 -13.429046) (xy 438.897317 -13.212155)
			(xy 438.849729 -12.993425) (xy 438.809978 -12.773137) (xy 438.778115 -12.55157) (xy 438.75418 -12.329008)
			(xy 438.738204 -12.105732) (xy 438.730207 -11.882029) (xy 438.729628 -11.770106) (xy 438.729628 -4.999482)
			(xy 438.729125 -4.913325) (xy 438.721157 -4.741195) (xy 438.705249 -4.569616) (xy 438.681433 -4.398955)
			(xy 438.649762 -4.229576) (xy 438.610302 -4.061841) (xy 438.563138 -3.896107) (xy 438.50837 -3.732727)
			(xy 438.446116 -3.572052) (xy 438.376507 -3.414422) (xy 438.299694 -3.260176) (xy 438.215839 -3.109641)
			(xy 438.125121 -2.96314) (xy 438.027735 -2.820985) (xy 437.923887 -2.683479) (xy 437.8138 -2.550915)
			(xy 437.697708 -2.423577) (xy 437.57586 -2.301735) (xy 437.448515 -2.185652) (xy 437.315944 -2.075573)
			(xy 437.178432 -1.971733) (xy 437.03627 -1.874356) (xy 436.889764 -1.783647) (xy 436.739224 -1.699801)
			(xy 436.584973 -1.622997) (xy 436.42734 -1.553398) (xy 436.26666 -1.491153) (xy 436.103278 -1.436395)
			(xy 435.93754 -1.389241) (xy 435.769803 -1.349791) (xy 435.600422 -1.31813) (xy 435.429759 -1.294325)
			(xy 435.25818 -1.278427) (xy 435.086049 -1.270469) (xy 434.999892 -1.27) (xy 432.200304 -1.27) (xy 432.190958 -1.270466)
			(xy 432.173531 -1.277237) (xy 432.159665 -1.289778) (xy 432.155092 -1.29794) (xy 432.124358 -1.3589)
			(xy 432.121873 -1.364285) (xy 432.119173 -1.375831) (xy 432.119024 -1.38176) (xy 432.119024 -1.422654)
			(xy 432.12131 -1.43002) (xy 432.124104 -1.439164) (xy 432.129438 -1.446276) (xy 432.189804 -1.528741)
			(xy 432.30471 -1.697777) (xy 432.412799 -1.871252) (xy 432.5139 -2.048891) (xy 432.607853 -2.230411)
			(xy 432.694509 -2.415526) (xy 432.773731 -2.603942) (xy 432.845393 -2.795361) (xy 432.909382 -2.98948)
			(xy 432.965597 -3.185992) (xy 433.013948 -3.384584) (xy 433.054359 -3.584943) (xy 433.086766 -3.786751)
			(xy 433.111118 -3.989689) (xy 433.127376 -4.193435) (xy 433.135514 -4.397667) (xy 433.13604 -4.499864)
			(xy 433.13604 -9.500108) (xy 433.135545 -9.600949) (xy 433.127627 -9.802476) (xy 433.111803 -10.003536)
			(xy 433.088098 -10.20382) (xy 433.056548 -10.403019) (xy 433.017202 -10.600826) (xy 432.97012 -10.796935)
			(xy 432.915375 -10.991045) (xy 432.853052 -11.182856) (xy 432.783247 -11.372073) (xy 432.706066 -11.558402)
			(xy 432.62163 -11.741559) (xy 432.530068 -11.921259) (xy 432.431522 -12.097225) (xy 432.326144 -12.269188)
			(xy 432.214095 -12.43688) (xy 432.095549 -12.600044) (xy 431.970689 -12.758429) (xy 431.839707 -12.911789)
			(xy 431.702805 -13.059889) (xy 431.560195 -13.202499) (xy 431.412095 -13.339401) (xy 431.258735 -13.470383)
			(xy 431.10035 -13.595243) (xy 430.937186 -13.713789) (xy 430.769494 -13.825838) (xy 430.597531 -13.931216)
			(xy 430.421565 -14.029762) (xy 430.241865 -14.121324) (xy 430.058708 -14.20576) (xy 429.872379 -14.282941)
			(xy 429.683162 -14.352746) (xy 429.491351 -14.415069) (xy 429.297241 -14.469814) (xy 429.101132 -14.516896)
			(xy 428.903325 -14.556242) (xy 428.704126 -14.587792) (xy 428.503842 -14.611497) (xy 428.302782 -14.627321)
			(xy 428.101255 -14.635239) (xy 427.899573 -14.635239) (xy 427.698046 -14.627321) (xy 427.496986 -14.611497)
			(xy 427.296702 -14.587792) (xy 427.097503 -14.556242) (xy 426.899696 -14.516896) (xy 426.703587 -14.469814)
			(xy 426.509477 -14.415069) (xy 426.317666 -14.352746) (xy 426.128449 -14.282941) (xy 425.94212 -14.20576)
			(xy 425.758963 -14.121324) (xy 425.579263 -14.029762) (xy 425.403297 -13.931216) (xy 425.231334 -13.825838)
			(xy 425.063642 -13.713789) (xy 424.900478 -13.595243) (xy 424.742093 -13.470383) (xy 424.588733 -13.339401)
			(xy 424.440633 -13.202499) (xy 424.298023 -13.059889) (xy 424.161121 -12.911789) (xy 424.030139 -12.758429)
			(xy 423.905279 -12.600044) (xy 423.786733 -12.43688) (xy 423.674684 -12.269188) (xy 423.569306 -12.097225)
			(xy 423.47076 -11.921259) (xy 423.379198 -11.741559) (xy 423.294762 -11.558402) (xy 423.217581 -11.372073)
			(xy 423.147776 -11.182856) (xy 423.085453 -10.991045) (xy 423.030708 -10.796935) (xy 422.983626 -10.600826)
			(xy 422.94428 -10.403019) (xy 422.91273 -10.20382) (xy 422.889025 -10.003536) (xy 422.873201 -9.802476)
			(xy 422.865283 -9.600949) (xy 422.864788 -9.500108) (xy 422.864788 -4.49961) (xy 422.865307 -4.39688)
			(xy 422.873536 -4.191584) (xy 422.889968 -3.986781) (xy 422.914578 -3.7828) (xy 422.947326 -3.579966)
			(xy 422.988159 -3.378604) (xy 423.037013 -3.179036) (xy 423.093809 -2.981581) (xy 423.158456 -2.786556)
			(xy 423.230851 -2.594273) (xy 423.310879 -2.405038) (xy 423.39841 -2.219155) (xy 423.493305 -2.036922)
			(xy 423.595412 -1.85863) (xy 423.704568 -1.684563) (xy 423.820598 -1.515002) (xy 423.88155 -1.432306)
			(xy 423.890186 -1.420876) (xy 423.892726 -1.392428) (xy 423.845482 -1.298194) (xy 423.84218 -1.292352)
			(xy 423.835081 -1.282907) (xy 423.814558 -1.271256) (xy 423.80281 -1.27) (xy 423.800016 -1.27) (xy 380.15799 -1.27)
			(xy 380.139194 -1.27762) (xy 380.132082 -1.284986) (xy 380.12497 -1.292098) (xy 380.085346 -1.380236)
			(xy 380.085346 -1.412748) (xy 380.085758 -1.422025) (xy 380.092416 -1.439343) (xy 380.0983 -1.44653)
			(xy 380.137243 -1.490814) (xy 380.209653 -1.583908) (xy 380.275497 -1.681757) (xy 380.334462 -1.783898)
			(xy 380.386271 -1.889848) (xy 380.430679 -1.999108) (xy 380.467475 -2.111161) (xy 380.496487 -2.225476)
			(xy 380.517576 -2.341515) (xy 380.530643 -2.458728) (xy 380.535627 -2.576562) (xy 380.532503 -2.69446)
			(xy 380.521287 -2.811865) (xy 380.502032 -2.928222) (xy 380.474828 -3.042981) (xy 380.439805 -3.1556)
			(xy 380.397127 -3.265547) (xy 380.346996 -3.372302) (xy 380.28965 -3.475361) (xy 380.225359 -3.574236)
			(xy 380.154427 -3.668461) (xy 380.077189 -3.757591) (xy 379.99401 -3.841203) (xy 379.905284 -3.918903)
			(xy 379.811429 -3.990324) (xy 379.712889 -4.055128) (xy 379.61013 -4.11301) (xy 379.503637 -4.163694)
			(xy 379.393913 -4.206943) (xy 379.281478 -4.242552) (xy 379.166861 -4.270352) (xy 379.050606 -4.290211)
			(xy 378.933261 -4.302038) (xy 378.815381 -4.305774) (xy 378.697522 -4.301403) (xy 378.580243 -4.288945)
			(xy 378.464096 -4.268459) (xy 378.349631 -4.240043) (xy 378.237389 -4.203829) (xy 378.1279 -4.15999)
			(xy 378.021681 -4.108733) (xy 377.919235 -4.050299) (xy 377.821046 -3.984965) (xy 377.727577 -3.91304)
			(xy 377.63927 -3.834863) (xy 377.556543 -3.750804) (xy 377.479786 -3.66126) (xy 377.409362 -3.566655)
			(xy 377.345604 -3.467434) (xy 377.288814 -3.364068) (xy 377.239259 -3.257045) (xy 377.197174 -3.14687)
			(xy 377.162757 -3.034064) (xy 377.136172 -2.91916) (xy 377.117543 -2.802701) (xy 377.10696 -2.685237)
			(xy 377.104471 -2.567324) (xy 377.110089 -2.449519) (xy 377.123787 -2.332377) (xy 377.145501 -2.216454)
			(xy 377.175127 -2.102296) (xy 377.212527 -1.990444) (xy 377.257522 -1.881425) (xy 377.309901 -1.775755)
			(xy 377.369415 -1.673933) (xy 377.435785 -1.57644) (xy 377.508695 -1.483737) (xy 377.547886 -1.439672)
			(xy 377.558046 -1.428496) (xy 377.562618 -1.399032) (xy 377.518676 -1.300226) (xy 377.51258 -1.286256)
			(xy 377.487434 -1.27) (xy 375.835926 -1.27) (xy 375.827037 -1.270337) (xy 375.810334 -1.276427) (xy 375.796733 -1.287876)
			(xy 375.791984 -1.2954) (xy 375.747788 -1.371854) (xy 375.743597 -1.379777) (xy 375.740521 -1.397422)
			(xy 375.743751 -1.41504) (xy 375.748042 -1.422908) (xy 375.770768 -1.462691) (xy 375.810865 -1.545081)
			(xy 375.844638 -1.630259) (xy 375.871895 -1.717741) (xy 375.89248 -1.807028) (xy 375.906277 -1.897613)
			(xy 375.913206 -1.988979) (xy 375.91365 -2.034794) (xy 375.91365 -2.035048) (xy 375.91313 -2.085221)
			(xy 375.90484 -2.185225) (xy 375.88832 -2.284202) (xy 375.863684 -2.381477) (xy 375.831099 -2.476386)
			(xy 375.790788 -2.56828) (xy 375.743027 -2.656531) (xy 375.688142 -2.740537) (xy 375.626507 -2.819724)
			(xy 375.558544 -2.893551) (xy 375.484716 -2.961513) (xy 375.405529 -3.023148) (xy 375.321522 -3.078032)
			(xy 375.233271 -3.125793) (xy 375.141377 -3.166103) (xy 375.046468 -3.198687) (xy 374.949192 -3.223322)
			(xy 374.850215 -3.239841) (xy 374.750211 -3.24813) (xy 374.700038 -3.24866) (xy 374.646162 -3.248039)
			(xy 374.53884 -3.238419) (xy 374.432792 -3.219332) (xy 374.328852 -3.190926) (xy 374.278144 -3.172714)
			(xy 374.27408 -3.17119) (xy 374.253506 -3.166618) (xy 374.23217 -3.17119) (xy 374.22328 -3.177794)
			(xy 374.168416 -3.217926) (xy 374.158761 -3.225708) (xy 374.147852 -3.247945) (xy 374.147588 -3.260344)
			(xy 374.147588 -3.26263) (xy 374.148858 -3.30454) (xy 374.148858 -3.305048) (xy 374.148363 -3.342696)
			(xy 374.140488 -3.417578) (xy 374.124828 -3.491228) (xy 374.101556 -3.562837) (xy 374.070926 -3.631621)
			(xy 374.033273 -3.696826) (xy 373.989012 -3.757739) (xy 373.938626 -3.813691) (xy 373.882667 -3.86407)
			(xy 373.821748 -3.908324) (xy 373.756538 -3.945968) (xy 373.68775 -3.976589) (xy 373.616138 -3.999852)
			(xy 373.542487 -4.015502) (xy 373.467603 -4.023368) (xy 373.392308 -4.023363) (xy 373.317425 -4.015488)
			(xy 373.243775 -3.999829) (xy 373.172166 -3.976557) (xy 373.103382 -3.945927) (xy 373.038177 -3.908275)
			(xy 372.977264 -3.864014) (xy 372.921311 -3.813628) (xy 372.870932 -3.757669) (xy 372.826678 -3.696751)
			(xy 372.789034 -3.631541) (xy 372.758412 -3.562753) (xy 372.735149 -3.491141) (xy 372.719498 -3.41749)
			(xy 372.711632 -3.342607) (xy 372.711637 -3.267311) (xy 372.719511 -3.192428) (xy 372.73517 -3.118779)
			(xy 372.758442 -3.04717) (xy 372.789071 -2.978385) (xy 372.826723 -2.913179) (xy 372.870984 -2.852266)
			(xy 372.92137 -2.796314) (xy 372.977328 -2.745934) (xy 373.038246 -2.70168) (xy 373.103456 -2.664035)
			(xy 373.172244 -2.633414) (xy 373.243855 -2.61015) (xy 373.317507 -2.594499) (xy 373.39239 -2.586632)
			(xy 373.430038 -2.586228) (xy 373.430546 -2.586228) (xy 373.472964 -2.587498) (xy 373.475758 -2.587498)
			(xy 373.487804 -2.586896) (xy 373.509292 -2.576023) (xy 373.516906 -2.56667) (xy 373.5578 -2.510536)
			(xy 373.562367 -2.503898) (xy 373.567436 -2.488615) (xy 373.567706 -2.480564) (xy 373.564404 -2.462784)
			(xy 373.54569 -2.411431) (xy 373.516493 -2.306097) (xy 373.496891 -2.198563) (xy 373.487043 -2.089701)
			(xy 373.486426 -2.035048) (xy 373.486426 -2.034794) (xy 373.486853 -1.988978) (xy 373.493762 -1.897607)
			(xy 373.507547 -1.807018) (xy 373.528131 -1.717728) (xy 373.555394 -1.630246) (xy 373.589183 -1.545071)
			(xy 373.629303 -1.46269) (xy 373.652034 -1.422908) (xy 373.656246 -1.415016) (xy 373.65943 -1.397422)
			(xy 373.656398 -1.379802) (xy 373.652288 -1.371854) (xy 373.608092 -1.2954) (xy 373.603315 -1.287902)
			(xy 373.589713 -1.276477) (xy 373.573031 -1.270373) (xy 373.56415 -1.27) (xy 372.620286 -1.27) (xy 372.607898 -1.270554)
			(xy 372.58594 -1.282016) (xy 372.578376 -1.291844) (xy 372.573042 -1.299718) (xy 372.570248 -1.309624)
			(xy 372.545102 -1.390142) (xy 372.545102 -1.39065) (xy 372.54307 -1.39446) (xy 372.54307 -1.419606)
			(xy 372.558818 -1.449324) (xy 372.563136 -1.45415) (xy 372.566946 -1.458468) (xy 372.571772 -1.462024)
			(xy 372.572026 -1.462278) (xy 372.601905 -1.484344) (xy 372.657328 -1.533801) (xy 372.707246 -1.588809)
			(xy 372.751106 -1.648759) (xy 372.788421 -1.712988) (xy 372.818779 -1.780782) (xy 372.841842 -1.851393)
			(xy 372.857356 -1.924036) (xy 372.865148 -1.997907) (xy 372.86565 -2.035048) (xy 372.865166 -2.072002)
			(xy 372.857441 -2.145506) (xy 372.842074 -2.217799) (xy 372.819235 -2.28809) (xy 372.789174 -2.355609)
			(xy 372.75222 -2.419615) (xy 372.708778 -2.479409) (xy 372.659323 -2.534333) (xy 372.604399 -2.583788)
			(xy 372.544605 -2.62723) (xy 372.480599 -2.664184) (xy 372.41308 -2.694245) (xy 372.342789 -2.717084)
			(xy 372.270496 -2.732451) (xy 372.196992 -2.740176) (xy 372.123084 -2.740176) (xy 372.04958 -2.732451)
			(xy 371.977287 -2.717084) (xy 371.906996 -2.694245) (xy 371.839477 -2.664184) (xy 371.775471 -2.62723)
			(xy 371.715677 -2.583788) (xy 371.660753 -2.534333) (xy 371.611298 -2.479409) (xy 371.567856 -2.419615)
			(xy 371.530902 -2.355609) (xy 371.500841 -2.28809) (xy 371.478002 -2.217799) (xy 371.462635 -2.145506)
			(xy 371.45491 -2.072002) (xy 371.454426 -2.035048) (xy 371.454906 -1.997908) (xy 371.462715 -1.924039)
			(xy 371.478241 -1.8514) (xy 371.501313 -1.780793) (xy 371.531674 -1.713001) (xy 371.568989 -1.648774)
			(xy 371.612846 -1.588823) (xy 371.662758 -1.53381) (xy 371.718173 -1.484346) (xy 371.74805 -1.462278)
			(xy 371.748304 -1.462024) (xy 371.75313 -1.458468) (xy 371.75694 -1.45415) (xy 371.761258 -1.449324)
			(xy 371.764306 -1.443482) (xy 371.767862 -1.43764) (xy 371.773704 -1.429512) (xy 371.776498 -1.41859)
			(xy 371.777919 -1.411771) (xy 371.777399 -1.397855) (xy 371.775482 -1.391158) (xy 371.743478 -1.289558)
			(xy 371.7163 -1.269746) (xy 371.699536 -1.27) (xy 371.698774 -1.27) (xy 77.758036 -1.27) (xy 77.73924 -1.27762)
			(xy 77.732128 -1.284986) (xy 77.725016 -1.292098) (xy 77.685392 -1.380236) (xy 77.685392 -1.412748)
			(xy 77.685802 -1.422026) (xy 77.692455 -1.439348) (xy 77.698346 -1.44653) (xy 77.737286 -1.490812)
			(xy 77.809691 -1.583901) (xy 77.87553 -1.681745) (xy 77.934491 -1.78388) (xy 77.986297 -1.889824)
			(xy 78.030702 -1.999077) (xy 78.067497 -2.111123) (xy 78.096507 -2.225431) (xy 78.117597 -2.341462)
			(xy 78.130665 -2.458668) (xy 78.135651 -2.576495) (xy 78.13253 -2.694386) (xy 78.121318 -2.811785)
			(xy 78.102068 -2.928135) (xy 78.074869 -3.042888) (xy 78.039852 -3.155502) (xy 77.997181 -3.265444)
			(xy 77.947059 -3.372195) (xy 77.889721 -3.47525) (xy 77.825438 -3.574123) (xy 77.754516 -3.668346)
			(xy 77.677288 -3.757474) (xy 77.594119 -3.841087) (xy 77.505403 -3.918788) (xy 77.411559 -3.990211)
			(xy 77.313029 -4.055019) (xy 77.210281 -4.112904) (xy 77.103798 -4.163595) (xy 76.994085 -4.20685)
			(xy 76.881659 -4.242466) (xy 76.767052 -4.270275) (xy 76.650806 -4.290144) (xy 76.533469 -4.301981)
			(xy 76.415596 -4.305729) (xy 76.297744 -4.30137) (xy 76.18047 -4.288926) (xy 76.064328 -4.268454)
			(xy 75.949867 -4.240053) (xy 75.837628 -4.203855) (xy 75.72814 -4.160031) (xy 75.621921 -4.10879)
			(xy 75.519474 -4.050373) (xy 75.421282 -3.985056) (xy 75.327808 -3.913148) (xy 75.239496 -3.834988)
			(xy 75.156762 -3.750946) (xy 75.079996 -3.661419) (xy 75.009563 -3.566829) (xy 74.945794 -3.467625)
			(xy 74.88899 -3.364274) (xy 74.839421 -3.257265) (xy 74.79732 -3.147103) (xy 74.762887 -3.03431)
			(xy 74.736284 -2.919417) (xy 74.717636 -2.802968) (xy 74.707032 -2.685514) (xy 74.704523 -2.567608)
			(xy 74.710118 -2.449809) (xy 74.723794 -2.332672) (xy 74.745484 -2.216751) (xy 74.775086 -2.102595)
			(xy 74.812461 -1.990741) (xy 74.857432 -1.88172) (xy 74.909785 -1.776045) (xy 74.969275 -1.674217)
			(xy 75.03562 -1.576716) (xy 75.108506 -1.484003) (xy 75.147678 -1.439926) (xy 75.157838 -1.42875)
			(xy 75.162664 -1.399032) (xy 75.118722 -1.300226) (xy 75.112626 -1.286256) (xy 75.08748 -1.27) (xy 73.422256 -1.27)
			(xy 73.398888 -1.283462) (xy 73.39203 -1.2954) (xy 73.348088 -1.371346) (xy 73.348088 -1.371854)
			(xy 73.344786 -1.375156) (xy 73.340214 -1.408938) (xy 73.354692 -1.434592) (xy 73.380105 -1.480343)
			(xy 73.423865 -1.57542) (xy 73.459277 -1.673911) (xy 73.486081 -1.775085) (xy 73.504075 -1.87819)
			(xy 73.513128 -1.982462) (xy 73.513696 -2.034794) (xy 73.513696 -2.035048) (xy 73.513176 -2.08522)
			(xy 73.504886 -2.185222) (xy 73.488366 -2.284198) (xy 73.463729 -2.381471) (xy 73.431144 -2.476378)
			(xy 73.390833 -2.56827) (xy 73.343071 -2.656519) (xy 73.288185 -2.740523) (xy 73.22655 -2.819707)
			(xy 73.158586 -2.893532) (xy 73.084758 -2.961491) (xy 73.005571 -3.023123) (xy 72.921564 -3.078004)
			(xy 72.833312 -3.125761) (xy 72.741419 -3.166067) (xy 72.64651 -3.198647) (xy 72.549235 -3.223279)
			(xy 72.450259 -3.239794) (xy 72.350256 -3.248079) (xy 72.300084 -3.24866) (xy 72.246171 -3.248028)
			(xy 72.138777 -3.238366) (xy 72.032664 -3.219209) (xy 71.928672 -3.190707) (xy 71.877936 -3.17246)
			(xy 71.87311 -3.170682) (xy 71.861934 -3.168904) (xy 71.86168 -3.168904) (xy 71.851596 -3.167608)
			(xy 71.831803 -3.172182) (xy 71.823326 -3.177794) (xy 71.778368 -3.210814) (xy 71.771733 -3.216026)
			(xy 71.762073 -3.229849) (xy 71.757439 -3.246064) (xy 71.75754 -3.254502) (xy 71.75754 -3.255518)
			(xy 71.759318 -3.304286) (xy 71.759318 -3.305048) (xy 71.758816 -3.343238) (xy 71.750827 -3.419198)
			(xy 71.734942 -3.493908) (xy 71.711335 -3.566548) (xy 71.680265 -3.636322) (xy 71.642072 -3.702467)
			(xy 71.597173 -3.764257) (xy 71.546062 -3.821015) (xy 71.489299 -3.87212) (xy 71.427504 -3.917012)
			(xy 71.361356 -3.955199) (xy 71.291578 -3.986262) (xy 71.218936 -4.009862) (xy 71.144225 -4.025739)
			(xy 71.068263 -4.03372) (xy 70.991884 -4.033717) (xy 70.915923 -4.025731) (xy 70.841213 -4.009848)
			(xy 70.768572 -3.986243) (xy 70.698797 -3.955175) (xy 70.632651 -3.916983) (xy 70.57086 -3.872087)
			(xy 70.5141 -3.820978) (xy 70.462993 -3.764215) (xy 70.418099 -3.702422) (xy 70.379911 -3.636275)
			(xy 70.348845 -3.566498) (xy 70.325244 -3.493856) (xy 70.309364 -3.419146) (xy 70.301381 -3.343184)
			(xy 70.301382 -3.266805) (xy 70.309366 -3.190844) (xy 70.325247 -3.116133) (xy 70.348849 -3.043492)
			(xy 70.379916 -2.973716) (xy 70.418105 -2.907569) (xy 70.463 -2.845776) (xy 70.514107 -2.789015)
			(xy 70.570868 -2.737906) (xy 70.63266 -2.693011) (xy 70.698806 -2.65482) (xy 70.768582 -2.623753)
			(xy 70.841223 -2.600149) (xy 70.915933 -2.584268) (xy 70.991894 -2.576282) (xy 71.030084 -2.575814)
			(xy 71.031354 -2.575814) (xy 71.079614 -2.577592) (xy 71.093076 -2.578608) (xy 71.116444 -2.567686)
			(xy 71.157846 -2.51079) (xy 71.164773 -2.500185) (xy 71.168236 -2.475126) (xy 71.16445 -2.463038)
			(xy 71.16445 -2.462784) (xy 71.145735 -2.411431) (xy 71.116537 -2.306097) (xy 71.096934 -2.198563)
			(xy 71.087087 -2.089701) (xy 71.086472 -2.035048) (xy 71.086472 -2.034794) (xy 71.086905 -1.989003)
			(xy 71.093813 -1.89768) (xy 71.107584 -1.807139) (xy 71.128137 -1.717892) (xy 71.155357 -1.630447)
			(xy 71.189089 -1.545302) (xy 71.22914 -1.462941) (xy 71.251826 -1.423162) (xy 71.258938 -1.411224)
			(xy 71.258938 -1.3843) (xy 71.2089 -1.296416) (xy 71.20451 -1.289301) (xy 71.192074 -1.278143) (xy 71.184516 -1.274572)
			(xy 71.182992 -1.274064) (xy 71.17334 -1.27) (xy 70.22338 -1.27) (xy 70.217284 -1.270254) (xy 70.213982 -1.270762)
			(xy 70.203286 -1.272545) (xy 70.184722 -1.283715) (xy 70.178168 -1.292352) (xy 70.173088 -1.299718)
			(xy 70.170294 -1.309624) (xy 70.145148 -1.390142) (xy 70.145148 -1.39065) (xy 70.1421 -1.399032)
			(xy 70.143624 -1.420368) (xy 70.158864 -1.449324) (xy 70.163182 -1.45415) (xy 70.166992 -1.458468)
			(xy 70.171818 -1.462024) (xy 70.172072 -1.462278) (xy 70.201953 -1.484343) (xy 70.25738 -1.533797)
			(xy 70.307302 -1.588804) (xy 70.351165 -1.648754) (xy 70.388483 -1.712982) (xy 70.418843 -1.780778)
			(xy 70.441908 -1.851389) (xy 70.457423 -1.924034) (xy 70.465216 -1.997906) (xy 70.465696 -2.035048)
			(xy 70.465212 -2.072002) (xy 70.457487 -2.145506) (xy 70.44212 -2.217799) (xy 70.419281 -2.28809)
			(xy 70.38922 -2.355609) (xy 70.352266 -2.419615) (xy 70.308824 -2.479409) (xy 70.259369 -2.534333)
			(xy 70.204445 -2.583788) (xy 70.144651 -2.62723) (xy 70.080645 -2.664184) (xy 70.013126 -2.694245)
			(xy 69.942835 -2.717084) (xy 69.870542 -2.732451) (xy 69.797038 -2.740176) (xy 69.72313 -2.740176)
			(xy 69.649626 -2.732451) (xy 69.577333 -2.717084) (xy 69.507042 -2.694245) (xy 69.439523 -2.664184)
			(xy 69.375517 -2.62723) (xy 69.315723 -2.583788) (xy 69.260799 -2.534333) (xy 69.211344 -2.479409)
			(xy 69.167902 -2.419615) (xy 69.130948 -2.355609) (xy 69.100887 -2.28809) (xy 69.078048 -2.217799)
			(xy 69.062681 -2.145506) (xy 69.054956 -2.072002) (xy 69.054472 -2.035048) (xy 69.054952 -1.997908)
			(xy 69.062761 -1.92404) (xy 69.078288 -1.851402) (xy 69.101361 -1.780796) (xy 69.131723 -1.713006)
			(xy 69.16904 -1.64878) (xy 69.212899 -1.588831) (xy 69.262812 -1.533821) (xy 69.318229 -1.48436)
			(xy 69.348096 -1.462278) (xy 69.34835 -1.462024) (xy 69.353176 -1.458468) (xy 69.356986 -1.45415)
			(xy 69.361304 -1.449324) (xy 69.376036 -1.42113) (xy 69.377052 -1.411732) (xy 69.378322 -1.40081)
			(xy 69.37502 -1.390396) (xy 69.343524 -1.289558) (xy 69.3166 -1.269746) (xy 69.299582 -1.27) (xy 69.29882 -1.27)
			(xy 58.7502 -1.27) (xy 58.740192 -1.270488) (xy 58.721701 -1.278148) (xy 58.707548 -1.292301) (xy 58.699888 -1.310792)
			(xy 58.6994 -1.3208) (xy 58.6994 -3.905403) (xy 59.464945 -3.905403) (xy 59.471334 -3.788566) (xy 59.485672 -3.672436)
			(xy 59.507892 -3.557553) (xy 59.537892 -3.444453) (xy 59.575531 -3.33366) (xy 59.620635 -3.225691)
			(xy 59.672994 -3.121047) (xy 59.732364 -3.020215) (xy 59.798469 -2.923665) (xy 59.871001 -2.831846)
			(xy 59.949623 -2.745184) (xy 60.03397 -2.664083) (xy 60.123649 -2.58892) (xy 60.218243 -2.520045)
			(xy 60.317311 -2.457778) (xy 60.420394 -2.402409) (xy 60.527011 -2.354195) (xy 60.636666 -2.31336)
			(xy 60.74885 -2.280095) (xy 60.863041 -2.254555) (xy 60.978706 -2.236858) (xy 61.095309 -2.227086)
			(xy 61.212307 -2.225285) (xy 61.329156 -2.231463) (xy 61.445312 -2.245591) (xy 61.560234 -2.267605)
			(xy 61.673389 -2.297401) (xy 61.784249 -2.334841) (xy 61.892299 -2.37975) (xy 61.997037 -2.43192)
			(xy 62.097976 -2.491108) (xy 62.194645 -2.557039) (xy 62.286595 -2.629406) (xy 62.33033 -2.66827)
			(xy 62.335664 -2.673096) (xy 62.344554 -2.677414) (xy 62.355476 -2.68478) (xy 62.3697 -2.685542)
			(xy 62.382146 -2.686304) (xy 62.476888 -2.64414) (xy 62.483746 -2.639568) (xy 62.493846 -2.632085)
			(xy 62.505708 -2.609958) (xy 62.506352 -2.597404) (xy 62.506352 -2.590038) (xy 62.506846 -2.540729)
			(xy 62.51485 -2.442437) (xy 62.530805 -2.345119) (xy 62.554605 -2.249417) (xy 62.586094 -2.155962)
			(xy 62.625063 -2.065371) (xy 62.671257 -1.978241) (xy 62.724369 -1.895148) (xy 62.78405 -1.81664)
			(xy 62.849905 -1.743234) (xy 62.921501 -1.675415) (xy 62.998365 -1.61363) (xy 63.079989 -1.558287)
			(xy 63.165836 -1.509752) (xy 63.255339 -1.468343) (xy 63.347907 -1.434336) (xy 63.442929 -1.407953)
			(xy 63.53978 -1.389369) (xy 63.637819 -1.378706) (xy 63.7364 -1.376036) (xy 63.834873 -1.381375)
			(xy 63.932587 -1.394688) (xy 64.028899 -1.415888) (xy 64.123173 -1.444834) (xy 64.214786 -1.481336)
			(xy 64.303134 -1.525153) (xy 64.387635 -1.575996) (xy 64.467731 -1.633528) (xy 64.542894 -1.697372)
			(xy 64.612627 -1.767105) (xy 64.67647 -1.842267) (xy 64.734003 -1.922363) (xy 64.784846 -2.006864)
			(xy 64.828663 -2.095212) (xy 64.865165 -2.186825) (xy 64.894112 -2.281099) (xy 64.915311 -2.377411)
			(xy 64.928625 -2.475125) (xy 64.933964 -2.573598) (xy 64.933519 -2.590038) (xy 65.045847 -2.590038)
			(xy 65.049886 -2.491076) (xy 65.061979 -2.392773) (xy 65.082044 -2.295782) (xy 65.109948 -2.20075)
			(xy 65.145505 -2.108308) (xy 65.188479 -2.019073) (xy 65.238583 -1.933637) (xy 65.295485 -1.852569)
			(xy 65.358805 -1.776408) (xy 65.428121 -1.705663) (xy 65.502974 -1.640803) (xy 65.582864 -1.58226)
			(xy 65.667261 -1.530423) (xy 65.755601 -1.485638) (xy 65.847298 -1.448202) (xy 65.941742 -1.418366)
			(xy 66.038303 -1.396326) (xy 66.136339 -1.382231) (xy 66.235198 -1.376173) (xy 66.334221 -1.378193)
			(xy 66.432751 -1.388278) (xy 66.530131 -1.406361) (xy 66.625712 -1.432321) (xy 66.71886 -1.465985)
			(xy 66.808954 -1.507129) (xy 66.895394 -1.55548) (xy 66.977606 -1.610716) (xy 67.055042 -1.672469)
			(xy 67.127187 -1.740329) (xy 67.19356 -1.813843) (xy 67.253721 -1.892522) (xy 67.307268 -1.975843)
			(xy 67.353846 -2.063252) (xy 67.393144 -2.154167) (xy 67.424901 -2.247982) (xy 67.448906 -2.344073)
			(xy 67.464998 -2.441801) (xy 67.473071 -2.540516) (xy 67.473576 -2.590038) (xy 67.473071 -2.63956)
			(xy 67.464998 -2.738275) (xy 67.448906 -2.836003) (xy 67.424901 -2.932094) (xy 67.393144 -3.025909)
			(xy 67.353846 -3.116824) (xy 67.307268 -3.204233) (xy 67.253721 -3.287554) (xy 67.19356 -3.366233)
			(xy 67.127187 -3.439747) (xy 67.055042 -3.507607) (xy 66.977606 -3.56936) (xy 66.895394 -3.624596)
			(xy 66.808954 -3.672947) (xy 66.71886 -3.714091) (xy 66.625712 -3.747755) (xy 66.530131 -3.773715)
			(xy 66.432751 -3.791798) (xy 66.334221 -3.801883) (xy 66.235198 -3.803903) (xy 66.136339 -3.797845)
			(xy 66.038303 -3.78375) (xy 65.941742 -3.76171) (xy 65.847298 -3.731874) (xy 65.755601 -3.694438)
			(xy 65.667261 -3.649653) (xy 65.582864 -3.597816) (xy 65.502974 -3.539273) (xy 65.428121 -3.474413)
			(xy 65.358805 -3.403668) (xy 65.295485 -3.327507) (xy 65.238583 -3.246439) (xy 65.188479 -3.161003)
			(xy 65.145505 -3.071768) (xy 65.109948 -2.979326) (xy 65.082044 -2.884294) (xy 65.061979 -2.787303)
			(xy 65.049886 -2.689) (xy 65.045847 -2.590038) (xy 64.933519 -2.590038) (xy 64.931294 -2.672179)
			(xy 64.920632 -2.770218) (xy 64.902048 -2.867069) (xy 64.875665 -2.962091) (xy 64.841657 -3.05466)
			(xy 64.800249 -3.144162) (xy 64.751714 -3.230009) (xy 64.696371 -3.311634) (xy 64.634587 -3.388498)
			(xy 64.566768 -3.460094) (xy 64.493362 -3.525949) (xy 64.414854 -3.58563) (xy 64.33176 -3.638742)
			(xy 64.244631 -3.684936) (xy 64.15404 -3.723906) (xy 64.060585 -3.755394) (xy 63.964883 -3.779195)
			(xy 63.867565 -3.79515) (xy 63.769273 -3.803154) (xy 63.719964 -3.80365) (xy 63.668028 -3.803111)
			(xy 63.564538 -3.794224) (xy 63.462185 -3.776525) (xy 63.361719 -3.750144) (xy 63.263875 -3.715275)
			(xy 63.169368 -3.672173) (xy 63.078891 -3.621152) (xy 63.035688 -3.592322) (xy 63.02629 -3.585972)
			(xy 63.015368 -3.584194) (xy 63.003938 -3.582162) (xy 62.983364 -3.58775) (xy 62.97676 -3.592068)
			(xy 62.887352 -3.647948) (xy 62.874652 -3.67538) (xy 62.876938 -3.690366) (xy 62.885006 -3.748315)
			(xy 62.894148 -3.864969) (xy 62.895317 -3.981975) (xy 62.888507 -4.098788) (xy 62.873751 -4.214866)
			(xy 62.851117 -4.329668) (xy 62.82071 -4.44266) (xy 62.782672 -4.553316) (xy 62.773502 -4.575048)
			(xy 69.053972 -4.575048) (xy 69.057972 -4.499993) (xy 69.069927 -4.425788) (xy 69.089702 -4.353275)
			(xy 69.117073 -4.283274) (xy 69.15173 -4.216579) (xy 69.193279 -4.153946) (xy 69.241251 -4.096084)
			(xy 69.295101 -4.043648) (xy 69.354219 -3.997234) (xy 69.417937 -3.957367) (xy 69.48553 -3.924498)
			(xy 69.556235 -3.899) (xy 69.629249 -3.881162) (xy 69.703746 -3.871187) (xy 69.778881 -3.869186)
			(xy 69.853803 -3.875183) (xy 69.927663 -3.889109) (xy 69.999625 -3.910808) (xy 70.068872 -3.940032)
			(xy 70.134621 -3.976452) (xy 70.196126 -4.019654) (xy 70.25269 -4.069149) (xy 70.303673 -4.124376)
			(xy 70.348497 -4.184709) (xy 70.386654 -4.249465) (xy 70.417712 -4.31791) (xy 70.441319 -4.389268)
			(xy 70.457207 -4.462731) (xy 70.465196 -4.537467) (xy 70.465696 -4.575048) (xy 71.593972 -4.575048)
			(xy 71.597972 -4.499993) (xy 71.609927 -4.425788) (xy 71.629702 -4.353275) (xy 71.657073 -4.283274)
			(xy 71.69173 -4.216579) (xy 71.733279 -4.153946) (xy 71.781251 -4.096084) (xy 71.835101 -4.043648)
			(xy 71.894219 -3.997234) (xy 71.957937 -3.957367) (xy 72.02553 -3.924498) (xy 72.096235 -3.899) (xy 72.169249 -3.881162)
			(xy 72.243746 -3.871187) (xy 72.318881 -3.869186) (xy 72.393803 -3.875183) (xy 72.467663 -3.889109)
			(xy 72.539625 -3.910808) (xy 72.608872 -3.940032) (xy 72.674621 -3.976452) (xy 72.736126 -4.019654)
			(xy 72.79269 -4.069149) (xy 72.843673 -4.124376) (xy 72.888497 -4.184709) (xy 72.926654 -4.249465)
			(xy 72.957712 -4.31791) (xy 72.981319 -4.389268) (xy 72.997207 -4.462731) (xy 73.005196 -4.537467)
			(xy 73.005696 -4.575048) (xy 73.005196 -4.612629) (xy 72.997207 -4.687365) (xy 72.981319 -4.760828)
			(xy 72.957712 -4.832186) (xy 72.926654 -4.900631) (xy 72.888497 -4.965387) (xy 72.843673 -5.02572)
			(xy 72.79269 -5.080947) (xy 72.736126 -5.130442) (xy 72.674621 -5.173644) (xy 72.608872 -5.210064)
			(xy 72.539625 -5.239288) (xy 72.467663 -5.260987) (xy 72.393803 -5.274913) (xy 72.318881 -5.28091)
			(xy 72.243746 -5.278909) (xy 72.169249 -5.268934) (xy 72.096235 -5.251096) (xy 72.02553 -5.225598)
			(xy 71.957937 -5.192729) (xy 71.894219 -5.152862) (xy 71.835101 -5.106448) (xy 71.781251 -5.054012)
			(xy 71.733279 -4.99615) (xy 71.69173 -4.933517) (xy 71.657073 -4.866822) (xy 71.629702 -4.796821)
			(xy 71.609927 -4.724308) (xy 71.597972 -4.650103) (xy 71.593972 -4.575048) (xy 70.465696 -4.575048)
			(xy 70.465196 -4.612629) (xy 70.457207 -4.687365) (xy 70.441319 -4.760828) (xy 70.417712 -4.832186)
			(xy 70.386654 -4.900631) (xy 70.348497 -4.965387) (xy 70.303673 -5.02572) (xy 70.25269 -5.080947)
			(xy 70.196126 -5.130442) (xy 70.134621 -5.173644) (xy 70.068872 -5.210064) (xy 69.999625 -5.239288)
			(xy 69.927663 -5.260987) (xy 69.853803 -5.274913) (xy 69.778881 -5.28091) (xy 69.703746 -5.278909)
			(xy 69.629249 -5.268934) (xy 69.556235 -5.251096) (xy 69.48553 -5.225598) (xy 69.417937 -5.192729)
			(xy 69.354219 -5.152862) (xy 69.295101 -5.106448) (xy 69.241251 -5.054012) (xy 69.193279 -4.99615)
			(xy 69.15173 -4.933517) (xy 69.117073 -4.866822) (xy 69.089702 -4.796821) (xy 69.069927 -4.724308)
			(xy 69.057972 -4.650103) (xy 69.053972 -4.575048) (xy 62.773502 -4.575048) (xy 62.73718 -4.661123)
			(xy 62.684444 -4.765577) (xy 62.624712 -4.866194) (xy 62.558259 -4.962505) (xy 62.485397 -5.054063)
			(xy 62.406463 -5.140441) (xy 62.321824 -5.221238) (xy 62.239109 -5.290058) (xy 63.013852 -5.290058)
			(xy 63.017852 -5.215003) (xy 63.029807 -5.140798) (xy 63.049582 -5.068285) (xy 63.076953 -4.998284)
			(xy 63.11161 -4.931589) (xy 63.153159 -4.868956) (xy 63.201131 -4.811094) (xy 63.254981 -4.758658)
			(xy 63.314099 -4.712244) (xy 63.377817 -4.672377) (xy 63.44541 -4.639508) (xy 63.516115 -4.61401)
			(xy 63.589129 -4.596172) (xy 63.663626 -4.586197) (xy 63.738761 -4.584196) (xy 63.813683 -4.590193)
			(xy 63.887543 -4.604119) (xy 63.959505 -4.625818) (xy 64.028752 -4.655042) (xy 64.094501 -4.691462)
			(xy 64.156006 -4.734664) (xy 64.21257 -4.784159) (xy 64.263553 -4.839386) (xy 64.308377 -4.899719)
			(xy 64.346534 -4.964475) (xy 64.377592 -5.03292) (xy 64.401199 -5.104278) (xy 64.417087 -5.177741)
			(xy 64.425076 -5.252477) (xy 64.425576 -5.290058) (xy 65.553852 -5.290058) (xy 65.557852 -5.215003)
			(xy 65.569807 -5.140798) (xy 65.589582 -5.068285) (xy 65.616953 -4.998284) (xy 65.65161 -4.931589)
			(xy 65.693159 -4.868956) (xy 65.741131 -4.811094) (xy 65.794981 -4.758658) (xy 65.854099 -4.712244)
			(xy 65.917817 -4.672377) (xy 65.98541 -4.639508) (xy 66.056115 -4.61401) (xy 66.129129 -4.596172)
			(xy 66.203626 -4.586197) (xy 66.278761 -4.584196) (xy 66.353683 -4.590193) (xy 66.427543 -4.604119)
			(xy 66.499505 -4.625818) (xy 66.568752 -4.655042) (xy 66.634501 -4.691462) (xy 66.696006 -4.734664)
			(xy 66.75257 -4.784159) (xy 66.803553 -4.839386) (xy 66.848377 -4.899719) (xy 66.886534 -4.964475)
			(xy 66.917592 -5.03292) (xy 66.941199 -5.104278) (xy 66.957087 -5.177741) (xy 66.965076 -5.252477)
			(xy 66.965576 -5.290058) (xy 66.965076 -5.327639) (xy 66.957087 -5.402375) (xy 66.941199 -5.475838)
			(xy 66.917592 -5.547196) (xy 66.886534 -5.615641) (xy 66.848377 -5.680397) (xy 66.803553 -5.74073)
			(xy 66.75257 -5.795957) (xy 66.696468 -5.845048) (xy 70.323972 -5.845048) (xy 70.327972 -5.769993)
			(xy 70.339927 -5.695788) (xy 70.359702 -5.623275) (xy 70.387073 -5.553274) (xy 70.42173 -5.486579)
			(xy 70.463279 -5.423946) (xy 70.511251 -5.366084) (xy 70.565101 -5.313648) (xy 70.624219 -5.267234)
			(xy 70.687937 -5.227367) (xy 70.75553 -5.194498) (xy 70.826235 -5.169) (xy 70.899249 -5.151162) (xy 70.973746 -5.141187)
			(xy 71.048881 -5.139186) (xy 71.123803 -5.145183) (xy 71.197663 -5.159109) (xy 71.269625 -5.180808)
			(xy 71.338872 -5.210032) (xy 71.404621 -5.246452) (xy 71.466126 -5.289654) (xy 71.52269 -5.339149)
			(xy 71.573673 -5.394376) (xy 71.618497 -5.454709) (xy 71.656654 -5.519465) (xy 71.687712 -5.58791)
			(xy 71.711319 -5.659268) (xy 71.727207 -5.732731) (xy 71.735196 -5.807467) (xy 71.735696 -5.845048)
			(xy 72.863972 -5.845048) (xy 72.867972 -5.769993) (xy 72.879927 -5.695788) (xy 72.899702 -5.623275)
			(xy 72.927073 -5.553274) (xy 72.96173 -5.486579) (xy 73.003279 -5.423946) (xy 73.051251 -5.366084)
			(xy 73.105101 -5.313648) (xy 73.164219 -5.267234) (xy 73.227937 -5.227367) (xy 73.29553 -5.194498)
			(xy 73.366235 -5.169) (xy 73.439249 -5.151162) (xy 73.513746 -5.141187) (xy 73.588881 -5.139186)
			(xy 73.663803 -5.145183) (xy 73.737663 -5.159109) (xy 73.809625 -5.180808) (xy 73.878872 -5.210032)
			(xy 73.944621 -5.246452) (xy 74.006126 -5.289654) (xy 74.056806 -5.334) (xy 81.787492 -5.334) (xy 81.787492 -5.333492)
			(xy 81.788098 -5.28716) (xy 81.797769 -5.195002) (xy 81.816965 -5.104348) (xy 81.845477 -5.016179)
			(xy 81.863692 -4.973574) (xy 81.867498 -4.963632) (xy 81.867498 -4.942368) (xy 81.863692 -4.932426)
			(xy 81.845459 -4.889793) (xy 81.816928 -4.801564) (xy 81.797735 -4.710843) (xy 81.788088 -4.618618)
			(xy 81.787492 -4.572254) (xy 81.787492 -4.571746) (xy 81.788086 -4.525382) (xy 81.797745 -4.433159)
			(xy 81.81694 -4.34244) (xy 81.845466 -4.254209) (xy 81.863692 -4.211574) (xy 81.867498 -4.201632)
			(xy 81.867498 -4.180368) (xy 81.863692 -4.170426) (xy 81.84547 -4.127823) (xy 81.816952 -4.039656)
			(xy 81.79776 -3.949) (xy 81.7881 -3.85684) (xy 81.787492 -3.810508) (xy 81.787492 -3.81) (xy 81.787967 -3.768898)
			(xy 81.795552 -3.687043) (xy 81.810657 -3.606238) (xy 81.833153 -3.527171) (xy 81.862849 -3.450517)
			(xy 81.899491 -3.37693) (xy 81.942766 -3.307038) (xy 81.992306 -3.241437) (xy 82.047687 -3.180687)
			(xy 82.108437 -3.125306) (xy 82.174038 -3.075766) (xy 82.24393 -3.032491) (xy 82.317517 -2.995849)
			(xy 82.394171 -2.966153) (xy 82.473238 -2.943657) (xy 82.554043 -2.928552) (xy 82.635898 -2.920967)
			(xy 82.677 -2.920492) (xy 82.677508 -2.920492) (xy 82.72384 -2.921098) (xy 82.815998 -2.930769) (xy 82.906652 -2.949965)
			(xy 82.994821 -2.978477) (xy 83.037426 -2.996692) (xy 83.047368 -3.000498) (xy 83.068632 -3.000498)
			(xy 83.078574 -2.996692) (xy 83.121207 -2.978459) (xy 83.209436 -2.949928) (xy 83.300157 -2.930735)
			(xy 83.392382 -2.921088) (xy 83.438746 -2.920492) (xy 83.439254 -2.920492) (xy 83.485618 -2.921086)
			(xy 83.577841 -2.930745) (xy 83.66856 -2.94994) (xy 83.756791 -2.978466) (xy 83.799426 -2.996692)
			(xy 83.809368 -3.000498) (xy 83.830632 -3.000498) (xy 83.840574 -2.996692) (xy 83.883207 -2.978459)
			(xy 83.971436 -2.949928) (xy 84.062157 -2.930735) (xy 84.154382 -2.921088) (xy 84.200746 -2.920492)
			(xy 84.201254 -2.920492) (xy 84.247618 -2.921086) (xy 84.339841 -2.930745) (xy 84.43056 -2.94994)
			(xy 84.518791 -2.978466) (xy 84.561426 -2.996692) (xy 84.571368 -3.000498) (xy 84.592632 -3.000498)
			(xy 84.602574 -2.996692) (xy 84.645207 -2.978459) (xy 84.733436 -2.949928) (xy 84.824157 -2.930735)
			(xy 84.916382 -2.921088) (xy 84.962746 -2.920492) (xy 84.963254 -2.920492) (xy 85.009618 -2.921086)
			(xy 85.101841 -2.930745) (xy 85.19256 -2.94994) (xy 85.280791 -2.978466) (xy 85.323426 -2.996692)
			(xy 85.333368 -3.000498) (xy 85.354632 -3.000498) (xy 85.364574 -2.996692) (xy 85.407207 -2.978459)
			(xy 85.495436 -2.949928) (xy 85.586157 -2.930735) (xy 85.678382 -2.921088) (xy 85.724746 -2.920492)
			(xy 85.725254 -2.920492) (xy 85.771618 -2.921086) (xy 85.863841 -2.930745) (xy 85.95456 -2.94994)
			(xy 86.042791 -2.978466) (xy 86.085426 -2.996692) (xy 86.095368 -3.000498) (xy 86.116632 -3.000498)
			(xy 86.126574 -2.996692) (xy 86.169177 -2.97847) (xy 86.257344 -2.949952) (xy 86.348 -2.93076) (xy 86.44016 -2.9211)
			(xy 86.486492 -2.920492) (xy 86.487 -2.920492) (xy 86.528102 -2.920967) (xy 86.609957 -2.928552)
			(xy 86.690762 -2.943657) (xy 86.769829 -2.966153) (xy 86.846483 -2.995849) (xy 86.92007 -3.032491)
			(xy 86.989962 -3.075766) (xy 87.055563 -3.125306) (xy 87.116313 -3.180687) (xy 87.171694 -3.241437)
			(xy 87.221234 -3.307038) (xy 87.264509 -3.37693) (xy 87.301151 -3.450517) (xy 87.330847 -3.527171)
			(xy 87.353343 -3.606238) (xy 87.368448 -3.687043) (xy 87.376033 -3.768898) (xy 87.376508 -3.81) (xy 87.376508 -3.810508)
			(xy 87.375902 -3.85684) (xy 87.366231 -3.948998) (xy 87.347035 -4.039652) (xy 87.318523 -4.127821)
			(xy 87.300308 -4.170426) (xy 87.296502 -4.180368) (xy 87.296502 -4.201632) (xy 87.300308 -4.211574)
			(xy 87.318541 -4.254207) (xy 87.347072 -4.342436) (xy 87.366265 -4.433157) (xy 87.375912 -4.525382)
			(xy 87.376508 -4.571746) (xy 87.376508 -4.572254) (xy 87.375914 -4.618618) (xy 87.366255 -4.710841)
			(xy 87.34706 -4.80156) (xy 87.318534 -4.889791) (xy 87.300308 -4.932426) (xy 87.296502 -4.942368)
			(xy 87.296502 -4.963632) (xy 87.300308 -4.973574) (xy 87.31853 -5.016177) (xy 87.347048 -5.104344)
			(xy 87.36624 -5.195) (xy 87.3759 -5.28716) (xy 87.376508 -5.333492) (xy 87.376508 -5.334) (xy 87.376285 -5.353304)
			(xy 354.006912 -5.353304) (xy 354.006912 -5.352796) (xy 354.007518 -5.306464) (xy 354.017189 -5.214306)
			(xy 354.036385 -5.123652) (xy 354.064897 -5.035483) (xy 354.083112 -4.992878) (xy 354.086914 -4.982935)
			(xy 354.086915 -4.961672) (xy 354.083112 -4.95173) (xy 354.064881 -4.909096) (xy 354.036349 -4.820867)
			(xy 354.017156 -4.730147) (xy 354.007509 -4.637922) (xy 354.006912 -4.591558) (xy 354.006912 -4.59105)
			(xy 354.007506 -4.544686) (xy 354.017164 -4.452463) (xy 354.03636 -4.361744) (xy 354.064885 -4.273513)
			(xy 354.083112 -4.230878) (xy 354.086914 -4.220935) (xy 354.086915 -4.199672) (xy 354.083112 -4.18973)
			(xy 354.064892 -4.147126) (xy 354.036374 -4.058959) (xy 354.01718 -3.968304) (xy 354.00752 -3.876144)
			(xy 354.006912 -3.829812) (xy 354.006912 -3.829304) (xy 354.007356 -3.7882) (xy 354.014941 -3.706344)
			(xy 354.030046 -3.625536) (xy 354.052543 -3.546467) (xy 354.08224 -3.469811) (xy 354.118884 -3.396222)
			(xy 354.162161 -3.326328) (xy 354.211702 -3.260725) (xy 354.267085 -3.199974) (xy 354.327838 -3.144592)
			(xy 354.393441 -3.095051) (xy 354.463336 -3.051776) (xy 354.536925 -3.015134) (xy 354.613582 -2.985438)
			(xy 354.692652 -2.962943) (xy 354.773459 -2.947839) (xy 354.855316 -2.940255) (xy 354.89642 -2.939796)
			(xy 354.896928 -2.939796) (xy 354.94326 -2.940395) (xy 355.035418 -2.950068) (xy 355.126072 -2.969266)
			(xy 355.214241 -2.99778) (xy 355.256846 -3.015996) (xy 355.266788 -3.019802) (xy 355.288052 -3.019802)
			(xy 355.297994 -3.015996) (xy 355.340624 -2.997756) (xy 355.428855 -2.969227) (xy 355.519576 -2.950036)
			(xy 355.611802 -2.940391) (xy 355.658166 -2.939796) (xy 355.658674 -2.939796) (xy 355.705037 -2.940418)
			(xy 355.797259 -2.950068) (xy 355.887978 -2.969256) (xy 355.97621 -2.997773) (xy 356.018846 -3.015996)
			(xy 356.028788 -3.019802) (xy 356.050052 -3.019802) (xy 356.059994 -3.015996) (xy 356.102624 -2.997756)
			(xy 356.190855 -2.969227) (xy 356.281576 -2.950036) (xy 356.373802 -2.940391) (xy 356.420166 -2.939796)
			(xy 356.420674 -2.939796) (xy 356.467037 -2.940418) (xy 356.559259 -2.950068) (xy 356.649978 -2.969256)
			(xy 356.73821 -2.997773) (xy 356.780846 -3.015996) (xy 356.790788 -3.019802) (xy 356.812052 -3.019802)
			(xy 356.821994 -3.015996) (xy 356.864624 -2.997756) (xy 356.952855 -2.969227) (xy 357.043576 -2.950036)
			(xy 357.135802 -2.940391) (xy 357.182166 -2.939796) (xy 357.182674 -2.939796) (xy 357.229037 -2.940418)
			(xy 357.321259 -2.950068) (xy 357.411978 -2.969256) (xy 357.50021 -2.997773) (xy 357.542846 -3.015996)
			(xy 357.552788 -3.019802) (xy 357.574052 -3.019802) (xy 357.583994 -3.015996) (xy 357.626624 -2.997756)
			(xy 357.714855 -2.969227) (xy 357.805576 -2.950036) (xy 357.897802 -2.940391) (xy 357.944166 -2.939796)
			(xy 357.944674 -2.939796) (xy 357.991037 -2.940418) (xy 358.083259 -2.950068) (xy 358.173978 -2.969256)
			(xy 358.26221 -2.997773) (xy 358.304846 -3.015996) (xy 358.314788 -3.019802) (xy 358.336052 -3.019802)
			(xy 358.345994 -3.015996) (xy 358.388594 -2.997768) (xy 358.476763 -2.969252) (xy 358.567419 -2.950061)
			(xy 358.65958 -2.940403) (xy 358.705912 -2.939796) (xy 358.70642 -2.939796) (xy 358.747523 -2.940248)
			(xy 358.829378 -2.947834) (xy 358.910184 -2.962941) (xy 358.989251 -2.985439) (xy 359.065905 -3.015137)
			(xy 359.139492 -3.051781) (xy 359.209385 -3.095058) (xy 359.274986 -3.144599) (xy 359.335736 -3.199981)
			(xy 359.391117 -3.260733) (xy 359.440656 -3.326335) (xy 359.483931 -3.396229) (xy 359.520573 -3.469817)
			(xy 359.550268 -3.546472) (xy 359.572764 -3.62554) (xy 359.587869 -3.706346) (xy 359.595454 -3.788201)
			(xy 359.595928 -3.829304) (xy 359.595928 -3.829812) (xy 359.595322 -3.876144) (xy 359.592249 -3.905427)
			(xy 361.864976 -3.905427) (xy 361.871362 -3.788592) (xy 361.885698 -3.672464) (xy 361.907917 -3.557584)
			(xy 361.937914 -3.444485) (xy 361.975551 -3.333694) (xy 362.020653 -3.225726) (xy 362.073009 -3.121084)
			(xy 362.132376 -3.020253) (xy 362.198478 -2.923704) (xy 362.271008 -2.831886) (xy 362.349627 -2.745225)
			(xy 362.433971 -2.664124) (xy 362.523647 -2.588961) (xy 362.618237 -2.520086) (xy 362.717303 -2.457819)
			(xy 362.820382 -2.402449) (xy 362.926996 -2.354234) (xy 363.036649 -2.313399) (xy 363.14883 -2.280133)
			(xy 363.263017 -2.254591) (xy 363.37868 -2.236892) (xy 363.495281 -2.227118) (xy 363.612276 -2.225315)
			(xy 363.729122 -2.231491) (xy 363.845276 -2.245617) (xy 363.960196 -2.267628) (xy 364.073349 -2.297421)
			(xy 364.184208 -2.334858) (xy 364.292257 -2.379765) (xy 364.396994 -2.431932) (xy 364.497931 -2.491117)
			(xy 364.594599 -2.557044) (xy 364.686549 -2.629408) (xy 364.730284 -2.66827) (xy 364.735618 -2.673096)
			(xy 364.744508 -2.677414) (xy 364.75543 -2.68478) (xy 364.769654 -2.685542) (xy 364.7821 -2.686304)
			(xy 364.876842 -2.64414) (xy 364.8837 -2.639568) (xy 364.89381 -2.632096) (xy 364.905664 -2.60996)
			(xy 364.906306 -2.597404) (xy 364.906306 -2.590038) (xy 364.906745 -2.540727) (xy 364.914746 -2.442432)
			(xy 364.930698 -2.345109) (xy 364.954496 -2.249403) (xy 364.985983 -2.155943) (xy 365.024951 -2.065347)
			(xy 365.071143 -1.978213) (xy 365.124255 -1.895115) (xy 365.183936 -1.816602) (xy 365.249791 -1.743191)
			(xy 365.321388 -1.675368) (xy 365.398253 -1.613579) (xy 365.479879 -1.558231) (xy 365.565727 -1.509692)
			(xy 365.655232 -1.468279) (xy 365.747803 -1.434268) (xy 365.842828 -1.407881) (xy 365.939682 -1.389294)
			(xy 366.037725 -1.378629) (xy 366.13631 -1.375955) (xy 366.234786 -1.381292) (xy 366.332505 -1.394603)
			(xy 366.42882 -1.415802) (xy 366.523098 -1.444747) (xy 366.614716 -1.481248) (xy 366.703069 -1.525064)
			(xy 366.787574 -1.575907) (xy 366.867674 -1.63344) (xy 366.942841 -1.697284) (xy 367.012578 -1.767018)
			(xy 367.076426 -1.842182) (xy 367.133962 -1.922279) (xy 367.184809 -2.006782) (xy 367.228629 -2.095133)
			(xy 367.265135 -2.186749) (xy 367.294084 -2.281025) (xy 367.315287 -2.37734) (xy 367.328603 -2.475058)
			(xy 367.333944 -2.573534) (xy 367.333497 -2.590038) (xy 367.445801 -2.590038) (xy 367.44984 -2.491076)
			(xy 367.461933 -2.392773) (xy 367.481998 -2.295782) (xy 367.509902 -2.20075) (xy 367.545459 -2.108308)
			(xy 367.588433 -2.019073) (xy 367.638537 -1.933637) (xy 367.695439 -1.852569) (xy 367.758759 -1.776408)
			(xy 367.828075 -1.705663) (xy 367.902928 -1.640803) (xy 367.982818 -1.58226) (xy 368.067215 -1.530423)
			(xy 368.155555 -1.485638) (xy 368.247252 -1.448202) (xy 368.341696 -1.418366) (xy 368.438257 -1.396326)
			(xy 368.536293 -1.382231) (xy 368.635152 -1.376173) (xy 368.734175 -1.378193) (xy 368.832705 -1.388278)
			(xy 368.930085 -1.406361) (xy 369.025666 -1.432321) (xy 369.118814 -1.465985) (xy 369.208908 -1.507129)
			(xy 369.295348 -1.55548) (xy 369.37756 -1.610716) (xy 369.454996 -1.672469) (xy 369.527141 -1.740329)
			(xy 369.593514 -1.813843) (xy 369.653675 -1.892522) (xy 369.707222 -1.975843) (xy 369.7538 -2.063252)
			(xy 369.793098 -2.154167) (xy 369.824855 -2.247982) (xy 369.84886 -2.344073) (xy 369.864952 -2.441801)
			(xy 369.873025 -2.540516) (xy 369.87353 -2.590038) (xy 369.873025 -2.63956) (xy 369.864952 -2.738275)
			(xy 369.84886 -2.836003) (xy 369.824855 -2.932094) (xy 369.793098 -3.025909) (xy 369.7538 -3.116824)
			(xy 369.707222 -3.204233) (xy 369.653675 -3.287554) (xy 369.593514 -3.366233) (xy 369.527141 -3.439747)
			(xy 369.454996 -3.507607) (xy 369.37756 -3.56936) (xy 369.295348 -3.624596) (xy 369.208908 -3.672947)
			(xy 369.118814 -3.714091) (xy 369.025666 -3.747755) (xy 368.930085 -3.773715) (xy 368.832705 -3.791798)
			(xy 368.734175 -3.801883) (xy 368.635152 -3.803903) (xy 368.536293 -3.797845) (xy 368.438257 -3.78375)
			(xy 368.341696 -3.76171) (xy 368.247252 -3.731874) (xy 368.155555 -3.694438) (xy 368.067215 -3.649653)
			(xy 367.982818 -3.597816) (xy 367.902928 -3.539273) (xy 367.828075 -3.474413) (xy 367.758759 -3.403668)
			(xy 367.695439 -3.327507) (xy 367.638537 -3.246439) (xy 367.588433 -3.161003) (xy 367.545459 -3.071768)
			(xy 367.509902 -2.979326) (xy 367.481998 -2.884294) (xy 367.461933 -2.787303) (xy 367.44984 -2.689)
			(xy 367.445801 -2.590038) (xy 367.333497 -2.590038) (xy 367.331275 -2.672119) (xy 367.320614 -2.770162)
			(xy 367.302032 -2.867017) (xy 367.27565 -2.962044) (xy 367.241642 -3.054616) (xy 367.200234 -3.144123)
			(xy 367.151698 -3.229974) (xy 367.096355 -3.311602) (xy 367.034569 -3.38847) (xy 366.966749 -3.460069)
			(xy 366.893341 -3.525929) (xy 366.814831 -3.585613) (xy 366.731735 -3.638728) (xy 366.644603 -3.684925)
			(xy 366.554009 -3.723897) (xy 366.460551 -3.755388) (xy 366.364846 -3.779191) (xy 366.267524 -3.795148)
			(xy 366.169229 -3.803153) (xy 366.119918 -3.80365) (xy 366.067983 -3.803083) (xy 365.964493 -3.7942)
			(xy 365.862141 -3.776506) (xy 365.761675 -3.75013) (xy 365.663831 -3.715265) (xy 365.569324 -3.672167)
			(xy 365.478845 -3.62115) (xy 365.435642 -3.592322) (xy 365.426244 -3.585972) (xy 365.415322 -3.584194)
			(xy 365.403892 -3.582162) (xy 365.383318 -3.58775) (xy 365.376714 -3.592068) (xy 365.287306 -3.647948)
			(xy 365.274606 -3.67538) (xy 365.276892 -3.690366) (xy 365.284975 -3.748311) (xy 365.294117 -3.864963)
			(xy 365.295286 -3.981967) (xy 365.288477 -4.098778) (xy 365.273722 -4.214853) (xy 365.251089 -4.329653)
			(xy 365.220683 -4.442642) (xy 365.182647 -4.553297) (xy 365.173469 -4.575048) (xy 371.453926 -4.575048)
			(xy 371.457926 -4.499993) (xy 371.469881 -4.425788) (xy 371.489656 -4.353275) (xy 371.517027 -4.283274)
			(xy 371.551684 -4.216579) (xy 371.593233 -4.153946) (xy 371.641205 -4.096084) (xy 371.695055 -4.043648)
			(xy 371.754173 -3.997234) (xy 371.817891 -3.957367) (xy 371.885484 -3.924498) (xy 371.956189 -3.899)
			(xy 372.029203 -3.881162) (xy 372.1037 -3.871187) (xy 372.178835 -3.869186) (xy 372.253757 -3.875183)
			(xy 372.327617 -3.889109) (xy 372.399579 -3.910808) (xy 372.468826 -3.940032) (xy 372.534575 -3.976452)
			(xy 372.59608 -4.019654) (xy 372.652644 -4.069149) (xy 372.703627 -4.124376) (xy 372.748451 -4.184709)
			(xy 372.786608 -4.249465) (xy 372.817666 -4.31791) (xy 372.841273 -4.389268) (xy 372.857161 -4.462731)
			(xy 372.86515 -4.537467) (xy 372.86565 -4.575048) (xy 373.993926 -4.575048) (xy 373.997926 -4.499993)
			(xy 374.009881 -4.425788) (xy 374.029656 -4.353275) (xy 374.057027 -4.283274) (xy 374.091684 -4.216579)
			(xy 374.133233 -4.153946) (xy 374.181205 -4.096084) (xy 374.235055 -4.043648) (xy 374.294173 -3.997234)
			(xy 374.357891 -3.957367) (xy 374.425484 -3.924498) (xy 374.496189 -3.899) (xy 374.569203 -3.881162)
			(xy 374.6437 -3.871187) (xy 374.718835 -3.869186) (xy 374.793757 -3.875183) (xy 374.867617 -3.889109)
			(xy 374.939579 -3.910808) (xy 375.008826 -3.940032) (xy 375.074575 -3.976452) (xy 375.13608 -4.019654)
			(xy 375.192644 -4.069149) (xy 375.243627 -4.124376) (xy 375.288451 -4.184709) (xy 375.326608 -4.249465)
			(xy 375.357666 -4.31791) (xy 375.381273 -4.389268) (xy 375.397161 -4.462731) (xy 375.40515 -4.537467)
			(xy 375.40565 -4.575048) (xy 375.40515 -4.612629) (xy 375.397161 -4.687365) (xy 375.381273 -4.760828)
			(xy 375.357666 -4.832186) (xy 375.326608 -4.900631) (xy 375.288451 -4.965387) (xy 375.243627 -5.02572)
			(xy 375.192644 -5.080947) (xy 375.13608 -5.130442) (xy 375.074575 -5.173644) (xy 375.008826 -5.210064)
			(xy 374.939579 -5.239288) (xy 374.867617 -5.260987) (xy 374.793757 -5.274913) (xy 374.718835 -5.28091)
			(xy 374.6437 -5.278909) (xy 374.569203 -5.268934) (xy 374.496189 -5.251096) (xy 374.425484 -5.225598)
			(xy 374.357891 -5.192729) (xy 374.294173 -5.152862) (xy 374.235055 -5.106448) (xy 374.181205 -5.054012)
			(xy 374.133233 -4.99615) (xy 374.091684 -4.933517) (xy 374.057027 -4.866822) (xy 374.029656 -4.796821)
			(xy 374.009881 -4.724308) (xy 373.997926 -4.650103) (xy 373.993926 -4.575048) (xy 372.86565 -4.575048)
			(xy 372.86515 -4.612629) (xy 372.857161 -4.687365) (xy 372.841273 -4.760828) (xy 372.817666 -4.832186)
			(xy 372.786608 -4.900631) (xy 372.748451 -4.965387) (xy 372.703627 -5.02572) (xy 372.652644 -5.080947)
			(xy 372.59608 -5.130442) (xy 372.534575 -5.173644) (xy 372.468826 -5.210064) (xy 372.399579 -5.239288)
			(xy 372.327617 -5.260987) (xy 372.253757 -5.274913) (xy 372.178835 -5.28091) (xy 372.1037 -5.278909)
			(xy 372.029203 -5.268934) (xy 371.956189 -5.251096) (xy 371.885484 -5.225598) (xy 371.817891 -5.192729)
			(xy 371.754173 -5.152862) (xy 371.695055 -5.106448) (xy 371.641205 -5.054012) (xy 371.593233 -4.99615)
			(xy 371.551684 -4.933517) (xy 371.517027 -4.866822) (xy 371.489656 -4.796821) (xy 371.469881 -4.724308)
			(xy 371.457926 -4.650103) (xy 371.453926 -4.575048) (xy 365.173469 -4.575048) (xy 365.137156 -4.661101)
			(xy 365.084422 -4.765554) (xy 365.024691 -4.866169) (xy 364.958241 -4.962478) (xy 364.88538 -5.054035)
			(xy 364.806448 -5.140411) (xy 364.721812 -5.221207) (xy 364.639062 -5.290058) (xy 365.413806 -5.290058)
			(xy 365.417806 -5.215003) (xy 365.429761 -5.140798) (xy 365.449536 -5.068285) (xy 365.476907 -4.998284)
			(xy 365.511564 -4.931589) (xy 365.553113 -4.868956) (xy 365.601085 -4.811094) (xy 365.654935 -4.758658)
			(xy 365.714053 -4.712244) (xy 365.777771 -4.672377) (xy 365.845364 -4.639508) (xy 365.916069 -4.61401)
			(xy 365.989083 -4.596172) (xy 366.06358 -4.586197) (xy 366.138715 -4.584196) (xy 366.213637 -4.590193)
			(xy 366.287497 -4.604119) (xy 366.359459 -4.625818) (xy 366.428706 -4.655042) (xy 366.494455 -4.691462)
			(xy 366.55596 -4.734664) (xy 366.612524 -4.784159) (xy 366.663507 -4.839386) (xy 366.708331 -4.899719)
			(xy 366.746488 -4.964475) (xy 366.777546 -5.03292) (xy 366.801153 -5.104278) (xy 366.817041 -5.177741)
			(xy 366.82503 -5.252477) (xy 366.82553 -5.290058) (xy 367.953806 -5.290058) (xy 367.957806 -5.215003)
			(xy 367.969761 -5.140798) (xy 367.989536 -5.068285) (xy 368.016907 -4.998284) (xy 368.051564 -4.931589)
			(xy 368.093113 -4.868956) (xy 368.141085 -4.811094) (xy 368.194935 -4.758658) (xy 368.254053 -4.712244)
			(xy 368.317771 -4.672377) (xy 368.385364 -4.639508) (xy 368.456069 -4.61401) (xy 368.529083 -4.596172)
			(xy 368.60358 -4.586197) (xy 368.678715 -4.584196) (xy 368.753637 -4.590193) (xy 368.827497 -4.604119)
			(xy 368.899459 -4.625818) (xy 368.968706 -4.655042) (xy 369.034455 -4.691462) (xy 369.09596 -4.734664)
			(xy 369.152524 -4.784159) (xy 369.203507 -4.839386) (xy 369.248331 -4.899719) (xy 369.286488 -4.964475)
			(xy 369.317546 -5.03292) (xy 369.341153 -5.104278) (xy 369.357041 -5.177741) (xy 369.36503 -5.252477)
			(xy 369.36553 -5.290058) (xy 369.36503 -5.327639) (xy 369.357041 -5.402375) (xy 369.341153 -5.475838)
			(xy 369.317546 -5.547196) (xy 369.286488 -5.615641) (xy 369.248331 -5.680397) (xy 369.203507 -5.74073)
			(xy 369.152524 -5.795957) (xy 369.096422 -5.845048) (xy 372.723926 -5.845048) (xy 372.727926 -5.769993)
			(xy 372.739881 -5.695788) (xy 372.759656 -5.623275) (xy 372.787027 -5.553274) (xy 372.821684 -5.486579)
			(xy 372.863233 -5.423946) (xy 372.911205 -5.366084) (xy 372.965055 -5.313648) (xy 373.024173 -5.267234)
			(xy 373.087891 -5.227367) (xy 373.155484 -5.194498) (xy 373.226189 -5.169) (xy 373.299203 -5.151162)
			(xy 373.3737 -5.141187) (xy 373.448835 -5.139186) (xy 373.523757 -5.145183) (xy 373.597617 -5.159109)
			(xy 373.669579 -5.180808) (xy 373.738826 -5.210032) (xy 373.804575 -5.246452) (xy 373.86608 -5.289654)
			(xy 373.922644 -5.339149) (xy 373.973627 -5.394376) (xy 374.018451 -5.454709) (xy 374.056608 -5.519465)
			(xy 374.087666 -5.58791) (xy 374.111273 -5.659268) (xy 374.127161 -5.732731) (xy 374.13515 -5.807467)
			(xy 374.13565 -5.845048) (xy 375.263926 -5.845048) (xy 375.267926 -5.769993) (xy 375.279881 -5.695788)
			(xy 375.299656 -5.623275) (xy 375.327027 -5.553274) (xy 375.361684 -5.486579) (xy 375.403233 -5.423946)
			(xy 375.451205 -5.366084) (xy 375.505055 -5.313648) (xy 375.564173 -5.267234) (xy 375.627891 -5.227367)
			(xy 375.695484 -5.194498) (xy 375.766189 -5.169) (xy 375.839203 -5.151162) (xy 375.9137 -5.141187)
			(xy 375.988835 -5.139186) (xy 376.063757 -5.145183) (xy 376.137617 -5.159109) (xy 376.209579 -5.180808)
			(xy 376.278826 -5.210032) (xy 376.344575 -5.246452) (xy 376.40608 -5.289654) (xy 376.462644 -5.339149)
			(xy 376.513627 -5.394376) (xy 376.558451 -5.454709) (xy 376.596608 -5.519465) (xy 376.627666 -5.58791)
			(xy 376.651273 -5.659268) (xy 376.667161 -5.732731) (xy 376.67515 -5.807467) (xy 376.67565 -5.845048)
			(xy 376.67515 -5.882629) (xy 376.667161 -5.957365) (xy 376.651273 -6.030828) (xy 376.627666 -6.102186)
			(xy 376.596608 -6.170631) (xy 376.558451 -6.235387) (xy 376.513627 -6.29572) (xy 376.462644 -6.350947)
			(xy 376.40608 -6.400442) (xy 376.344575 -6.443644) (xy 376.278826 -6.480064) (xy 376.209579 -6.509288)
			(xy 376.137617 -6.530987) (xy 376.063757 -6.544913) (xy 375.988835 -6.55091) (xy 375.9137 -6.548909)
			(xy 375.839203 -6.538934) (xy 375.766189 -6.521096) (xy 375.695484 -6.495598) (xy 375.627891 -6.462729)
			(xy 375.564173 -6.422862) (xy 375.505055 -6.376448) (xy 375.451205 -6.324012) (xy 375.403233 -6.26615)
			(xy 375.361684 -6.203517) (xy 375.327027 -6.136822) (xy 375.299656 -6.066821) (xy 375.279881 -5.994308)
			(xy 375.267926 -5.920103) (xy 375.263926 -5.845048) (xy 374.13565 -5.845048) (xy 374.13515 -5.882629)
			(xy 374.127161 -5.957365) (xy 374.111273 -6.030828) (xy 374.087666 -6.102186) (xy 374.056608 -6.170631)
			(xy 374.018451 -6.235387) (xy 373.973627 -6.29572) (xy 373.922644 -6.350947) (xy 373.86608 -6.400442)
			(xy 373.804575 -6.443644) (xy 373.738826 -6.480064) (xy 373.669579 -6.509288) (xy 373.597617 -6.530987)
			(xy 373.523757 -6.544913) (xy 373.448835 -6.55091) (xy 373.3737 -6.548909) (xy 373.299203 -6.538934)
			(xy 373.226189 -6.521096) (xy 373.155484 -6.495598) (xy 373.087891 -6.462729) (xy 373.024173 -6.422862)
			(xy 372.965055 -6.376448) (xy 372.911205 -6.324012) (xy 372.863233 -6.26615) (xy 372.821684 -6.203517)
			(xy 372.787027 -6.136822) (xy 372.759656 -6.066821) (xy 372.739881 -5.994308) (xy 372.727926 -5.920103)
			(xy 372.723926 -5.845048) (xy 369.096422 -5.845048) (xy 369.09596 -5.845452) (xy 369.034455 -5.888654)
			(xy 368.968706 -5.925074) (xy 368.899459 -5.954298) (xy 368.827497 -5.975997) (xy 368.753637 -5.989923)
			(xy 368.678715 -5.99592) (xy 368.60358 -5.993919) (xy 368.529083 -5.983944) (xy 368.456069 -5.966106)
			(xy 368.385364 -5.940608) (xy 368.317771 -5.907739) (xy 368.254053 -5.867872) (xy 368.194935 -5.821458)
			(xy 368.141085 -5.769022) (xy 368.093113 -5.71116) (xy 368.051564 -5.648527) (xy 368.016907 -5.581832)
			(xy 367.989536 -5.511831) (xy 367.969761 -5.439318) (xy 367.957806 -5.365113) (xy 367.953806 -5.290058)
			(xy 366.82553 -5.290058) (xy 366.82503 -5.327639) (xy 366.817041 -5.402375) (xy 366.801153 -5.475838)
			(xy 366.777546 -5.547196) (xy 366.746488 -5.615641) (xy 366.708331 -5.680397) (xy 366.663507 -5.74073)
			(xy 366.612524 -5.795957) (xy 366.55596 -5.845452) (xy 366.494455 -5.888654) (xy 366.428706 -5.925074)
			(xy 366.359459 -5.954298) (xy 366.287497 -5.975997) (xy 366.213637 -5.989923) (xy 366.138715 -5.99592)
			(xy 366.06358 -5.993919) (xy 365.989083 -5.983944) (xy 365.916069 -5.966106) (xy 365.845364 -5.940608)
			(xy 365.777771 -5.907739) (xy 365.714053 -5.867872) (xy 365.654935 -5.821458) (xy 365.601085 -5.769022)
			(xy 365.553113 -5.71116) (xy 365.511564 -5.648527) (xy 365.476907 -5.581832) (xy 365.449536 -5.511831)
			(xy 365.429761 -5.439318) (xy 365.417806 -5.365113) (xy 365.413806 -5.290058) (xy 364.639062 -5.290058)
			(xy 364.631866 -5.296045) (xy 364.537027 -5.364578) (xy 364.437737 -5.426488) (xy 364.334458 -5.481485)
			(xy 364.227671 -5.529314) (xy 364.117872 -5.569754) (xy 364.005572 -5.602614) (xy 363.891292 -5.627744)
			(xy 363.775566 -5.645025) (xy 363.658931 -5.654378) (xy 363.54193 -5.655758) (xy 363.425107 -5.64916)
			(xy 363.309005 -5.634615) (xy 363.194165 -5.612189) (xy 363.08112 -5.581987) (xy 362.970398 -5.54415)
			(xy 362.862511 -5.498854) (xy 362.757964 -5.446309) (xy 362.657241 -5.38676) (xy 362.560811 -5.320484)
			(xy 362.469124 -5.247788) (xy 362.382605 -5.169013) (xy 362.301656 -5.084522) (xy 362.226656 -4.994711)
			(xy 362.157951 -4.899996) (xy 362.095863 -4.800819) (xy 362.040679 -4.697639) (xy 361.992657 -4.590938)
			(xy 361.95202 -4.481212) (xy 361.918957 -4.368972) (xy 361.893621 -4.254738) (xy 361.876131 -4.139043)
			(xy 361.866567 -4.022425) (xy 361.864976 -3.905427) (xy 359.592249 -3.905427) (xy 359.58565 -3.968302)
			(xy 359.566455 -4.058956) (xy 359.537943 -4.147125) (xy 359.519728 -4.18973) (xy 359.515919 -4.199671)
			(xy 359.515921 -4.220936) (xy 359.519728 -4.230878) (xy 359.537964 -4.273509) (xy 359.566494 -4.36174)
			(xy 359.585686 -4.45246) (xy 359.595332 -4.544686) (xy 359.595928 -4.59105) (xy 359.595928 -4.591558)
			(xy 359.595333 -4.637922) (xy 359.585675 -4.730145) (xy 359.566479 -4.820864) (xy 359.537954 -4.909095)
			(xy 359.519728 -4.95173) (xy 359.515919 -4.961671) (xy 359.515921 -4.982936) (xy 359.519728 -4.992878)
			(xy 359.537953 -5.03548) (xy 359.566469 -5.123648) (xy 359.585661 -5.214303) (xy 359.59532 -5.306464)
			(xy 359.595928 -5.352796) (xy 359.595928 -5.353304) (xy 359.595437 -5.394406) (xy 359.587852 -5.476259)
			(xy 359.572747 -5.557063) (xy 359.550251 -5.636129) (xy 359.520556 -5.712782) (xy 359.483914 -5.786368)
			(xy 359.44064 -5.85626) (xy 359.391101 -5.92186) (xy 359.335722 -5.98261) (xy 359.274973 -6.037991)
			(xy 359.209373 -6.087531) (xy 359.139482 -6.130807) (xy 359.065897 -6.167449) (xy 358.989245 -6.197146)
			(xy 358.910179 -6.219643) (xy 358.829375 -6.23475) (xy 358.747522 -6.242336) (xy 358.70642 -6.242812)
			(xy 358.705912 -6.242812) (xy 358.65958 -6.242199) (xy 358.567423 -6.232529) (xy 358.476769 -6.213336)
			(xy 358.3886 -6.184826) (xy 358.345994 -6.166612) (xy 358.336052 -6.162806) (xy 358.314788 -6.162806)
			(xy 358.304846 -6.166612) (xy 358.262211 -6.184839) (xy 358.173982 -6.213371) (xy 358.083262 -6.232566)
			(xy 357.991038 -6.242215) (xy 357.944674 -6.242812) (xy 357.944166 -6.242812) (xy 357.897803 -6.24221)
			(xy 357.80558 -6.232554) (xy 357.714861 -6.21336) (xy 357.626629 -6.184837) (xy 357.583994 -6.166612)
			(xy 357.574052 -6.162806) (xy 357.552788 -6.162806) (xy 357.542846 -6.166612) (xy 357.500211 -6.184839)
			(xy 357.411982 -6.213371) (xy 357.321262 -6.232566) (xy 357.229038 -6.242215) (xy 357.182674 -6.242812)
			(xy 357.182166 -6.242812) (xy 357.135803 -6.24221) (xy 357.04358 -6.232554) (xy 356.952861 -6.21336)
			(xy 356.864629 -6.184837) (xy 356.821994 -6.166612) (xy 356.812052 -6.162806) (xy 356.790788 -6.162806)
			(xy 356.780846 -6.166612) (xy 356.738211 -6.184839) (xy 356.649982 -6.213371) (xy 356.559262 -6.232566)
			(xy 356.467038 -6.242215) (xy 356.420674 -6.242812) (xy 356.420166 -6.242812) (xy 356.373803 -6.24221)
			(xy 356.28158 -6.232554) (xy 356.190861 -6.21336) (xy 356.102629 -6.184837) (xy 356.059994 -6.166612)
			(xy 356.050052 -6.162806) (xy 356.028788 -6.162806) (xy 356.018846 -6.166612) (xy 355.976211 -6.184839)
			(xy 355.887982 -6.213371) (xy 355.797262 -6.232566) (xy 355.705038 -6.242215) (xy 355.658674 -6.242812)
			(xy 355.658166 -6.242812) (xy 355.611803 -6.24221) (xy 355.51958 -6.232554) (xy 355.428861 -6.21336)
			(xy 355.340629 -6.184837) (xy 355.297994 -6.166612) (xy 355.288052 -6.162806) (xy 355.266788 -6.162806)
			(xy 355.256846 -6.166612) (xy 355.214241 -6.184828) (xy 355.126074 -6.213347) (xy 355.035419 -6.232541)
			(xy 354.94326 -6.242203) (xy 354.896928 -6.242812) (xy 354.89642 -6.242812) (xy 354.855317 -6.242329)
			(xy 354.773462 -6.234746) (xy 354.692656 -6.219642) (xy 354.613589 -6.197147) (xy 354.536934 -6.167452)
			(xy 354.463346 -6.130811) (xy 354.393453 -6.087537) (xy 354.327851 -6.037998) (xy 354.267099 -5.982618)
			(xy 354.211717 -5.921868) (xy 354.162177 -5.856267) (xy 354.1189 -5.786375) (xy 354.082257 -5.712788)
			(xy 354.052561 -5.636134) (xy 354.030063 -5.557067) (xy 354.014958 -5.476261) (xy 354.007372 -5.394407)
			(xy 354.006912 -5.353304) (xy 87.376285 -5.353304) (xy 87.376033 -5.375102) (xy 87.368448 -5.456957)
			(xy 87.353343 -5.537762) (xy 87.330847 -5.616829) (xy 87.301151 -5.693483) (xy 87.264509 -5.76707)
			(xy 87.221234 -5.836962) (xy 87.171694 -5.902563) (xy 87.116313 -5.963313) (xy 87.055563 -6.018694)
			(xy 86.989962 -6.068234) (xy 86.92007 -6.111509) (xy 86.846483 -6.148151) (xy 86.769829 -6.177847)
			(xy 86.690762 -6.200343) (xy 86.609957 -6.215448) (xy 86.528102 -6.223033) (xy 86.487 -6.223508)
			(xy 86.486492 -6.223508) (xy 86.44016 -6.222902) (xy 86.348002 -6.213231) (xy 86.257348 -6.194035)
			(xy 86.169179 -6.165523) (xy 86.126574 -6.147308) (xy 86.116632 -6.143502) (xy 86.095368 -6.143502)
			(xy 86.085426 -6.147308) (xy 86.042793 -6.165541) (xy 85.954564 -6.194072) (xy 85.863843 -6.213265)
			(xy 85.771618 -6.222912) (xy 85.725254 -6.223508) (xy 85.724746 -6.223508) (xy 85.678382 -6.222914)
			(xy 85.586159 -6.213255) (xy 85.49544 -6.19406) (xy 85.407209 -6.165534) (xy 85.364574 -6.147308)
			(xy 85.354632 -6.143502) (xy 85.333368 -6.143502) (xy 85.323426 -6.147308) (xy 85.280793 -6.165541)
			(xy 85.192564 -6.194072) (xy 85.101843 -6.213265) (xy 85.009618 -6.222912) (xy 84.963254 -6.223508)
			(xy 84.962746 -6.223508) (xy 84.916382 -6.222914) (xy 84.824159 -6.213255) (xy 84.73344 -6.19406)
			(xy 84.645209 -6.165534) (xy 84.602574 -6.147308) (xy 84.592632 -6.143502) (xy 84.571368 -6.143502)
			(xy 84.561426 -6.147308) (xy 84.518793 -6.165541) (xy 84.430564 -6.194072) (xy 84.339843 -6.213265)
			(xy 84.247618 -6.222912) (xy 84.201254 -6.223508) (xy 84.200746 -6.223508) (xy 84.154382 -6.222914)
			(xy 84.062159 -6.213255) (xy 83.97144 -6.19406) (xy 83.883209 -6.165534) (xy 83.840574 -6.147308)
			(xy 83.830632 -6.143502) (xy 83.809368 -6.143502) (xy 83.799426 -6.147308) (xy 83.756793 -6.165541)
			(xy 83.668564 -6.194072) (xy 83.577843 -6.213265) (xy 83.485618 -6.222912) (xy 83.439254 -6.223508)
			(xy 83.438746 -6.223508) (xy 83.392382 -6.222914) (xy 83.300159 -6.213255) (xy 83.20944 -6.19406)
			(xy 83.121209 -6.165534) (xy 83.078574 -6.147308) (xy 83.068632 -6.143502) (xy 83.047368 -6.143502)
			(xy 83.037426 -6.147308) (xy 82.994823 -6.16553) (xy 82.906656 -6.194048) (xy 82.816 -6.21324) (xy 82.72384 -6.2229)
			(xy 82.677508 -6.223508) (xy 82.677 -6.223508) (xy 82.635898 -6.223033) (xy 82.554043 -6.215448)
			(xy 82.473238 -6.200343) (xy 82.394171 -6.177847) (xy 82.317517 -6.148151) (xy 82.24393 -6.111509)
			(xy 82.174038 -6.068234) (xy 82.108437 -6.018694) (xy 82.047687 -5.963313) (xy 81.992306 -5.902563)
			(xy 81.942766 -5.836962) (xy 81.899491 -5.76707) (xy 81.862849 -5.693483) (xy 81.833153 -5.616829)
			(xy 81.810657 -5.537762) (xy 81.795552 -5.456957) (xy 81.787967 -5.375102) (xy 81.787492 -5.334)
			(xy 74.056806 -5.334) (xy 74.06269 -5.339149) (xy 74.113673 -5.394376) (xy 74.158497 -5.454709) (xy 74.196654 -5.519465)
			(xy 74.227712 -5.58791) (xy 74.251319 -5.659268) (xy 74.267207 -5.732731) (xy 74.275196 -5.807467)
			(xy 74.275696 -5.845048) (xy 74.275196 -5.882629) (xy 74.267207 -5.957365) (xy 74.251319 -6.030828)
			(xy 74.227712 -6.102186) (xy 74.196654 -6.170631) (xy 74.158497 -6.235387) (xy 74.113673 -6.29572)
			(xy 74.06269 -6.350947) (xy 74.006126 -6.400442) (xy 73.944621 -6.443644) (xy 73.878872 -6.480064)
			(xy 73.809625 -6.509288) (xy 73.737663 -6.530987) (xy 73.663803 -6.544913) (xy 73.588881 -6.55091)
			(xy 73.513746 -6.548909) (xy 73.439249 -6.538934) (xy 73.366235 -6.521096) (xy 73.29553 -6.495598)
			(xy 73.227937 -6.462729) (xy 73.164219 -6.422862) (xy 73.105101 -6.376448) (xy 73.051251 -6.324012)
			(xy 73.003279 -6.26615) (xy 72.96173 -6.203517) (xy 72.927073 -6.136822) (xy 72.899702 -6.066821)
			(xy 72.879927 -5.994308) (xy 72.867972 -5.920103) (xy 72.863972 -5.845048) (xy 71.735696 -5.845048)
			(xy 71.735196 -5.882629) (xy 71.727207 -5.957365) (xy 71.711319 -6.030828) (xy 71.687712 -6.102186)
			(xy 71.656654 -6.170631) (xy 71.618497 -6.235387) (xy 71.573673 -6.29572) (xy 71.52269 -6.350947)
			(xy 71.466126 -6.400442) (xy 71.404621 -6.443644) (xy 71.338872 -6.480064) (xy 71.269625 -6.509288)
			(xy 71.197663 -6.530987) (xy 71.123803 -6.544913) (xy 71.048881 -6.55091) (xy 70.973746 -6.548909)
			(xy 70.899249 -6.538934) (xy 70.826235 -6.521096) (xy 70.75553 -6.495598) (xy 70.687937 -6.462729)
			(xy 70.624219 -6.422862) (xy 70.565101 -6.376448) (xy 70.511251 -6.324012) (xy 70.463279 -6.26615)
			(xy 70.42173 -6.203517) (xy 70.387073 -6.136822) (xy 70.359702 -6.066821) (xy 70.339927 -5.994308)
			(xy 70.327972 -5.920103) (xy 70.323972 -5.845048) (xy 66.696468 -5.845048) (xy 66.696006 -5.845452)
			(xy 66.634501 -5.888654) (xy 66.568752 -5.925074) (xy 66.499505 -5.954298) (xy 66.427543 -5.975997)
			(xy 66.353683 -5.989923) (xy 66.278761 -5.99592) (xy 66.203626 -5.993919) (xy 66.129129 -5.983944)
			(xy 66.056115 -5.966106) (xy 65.98541 -5.940608) (xy 65.917817 -5.907739) (xy 65.854099 -5.867872)
			(xy 65.794981 -5.821458) (xy 65.741131 -5.769022) (xy 65.693159 -5.71116) (xy 65.65161 -5.648527)
			(xy 65.616953 -5.581832) (xy 65.589582 -5.511831) (xy 65.569807 -5.439318) (xy 65.557852 -5.365113)
			(xy 65.553852 -5.290058) (xy 64.425576 -5.290058) (xy 64.425076 -5.327639) (xy 64.417087 -5.402375)
			(xy 64.401199 -5.475838) (xy 64.377592 -5.547196) (xy 64.346534 -5.615641) (xy 64.308377 -5.680397)
			(xy 64.263553 -5.74073) (xy 64.21257 -5.795957) (xy 64.156006 -5.845452) (xy 64.094501 -5.888654)
			(xy 64.028752 -5.925074) (xy 63.959505 -5.954298) (xy 63.887543 -5.975997) (xy 63.813683 -5.989923)
			(xy 63.738761 -5.99592) (xy 63.663626 -5.993919) (xy 63.589129 -5.983944) (xy 63.516115 -5.966106)
			(xy 63.44541 -5.940608) (xy 63.377817 -5.907739) (xy 63.314099 -5.867872) (xy 63.254981 -5.821458)
			(xy 63.201131 -5.769022) (xy 63.153159 -5.71116) (xy 63.11161 -5.648527) (xy 63.076953 -5.581832)
			(xy 63.049582 -5.511831) (xy 63.029807 -5.439318) (xy 63.017852 -5.365113) (xy 63.013852 -5.290058)
			(xy 62.239109 -5.290058) (xy 62.231875 -5.296077) (xy 62.137034 -5.364611) (xy 62.037742 -5.426521)
			(xy 61.93446 -5.481518) (xy 61.82767 -5.529348) (xy 61.717869 -5.569787) (xy 61.605566 -5.602648)
			(xy 61.491284 -5.627777) (xy 61.375555 -5.645057) (xy 61.258918 -5.654409) (xy 61.141914 -5.655789)
			(xy 61.025089 -5.64919) (xy 60.908985 -5.634643) (xy 60.794142 -5.612215) (xy 60.681096 -5.582012)
			(xy 60.570371 -5.544173) (xy 60.462483 -5.498875) (xy 60.357933 -5.446328) (xy 60.257209 -5.386776)
			(xy 60.160778 -5.320498) (xy 60.06909 -5.2478) (xy 59.98257 -5.169022) (xy 59.901621 -5.084529) (xy 59.826619 -4.994715)
			(xy 59.757915 -4.899997) (xy 59.695826 -4.800816) (xy 59.640643 -4.697634) (xy 59.592621 -4.590931)
			(xy 59.551984 -4.481202) (xy 59.518921 -4.368958) (xy 59.493586 -4.254722) (xy 59.476097 -4.139025)
			(xy 59.466535 -4.022404) (xy 59.464945 -3.905403) (xy 58.6994 -3.905403) (xy 58.6994 -7.370318) (xy 58.699827 -7.380387)
			(xy 58.707546 -7.398986) (xy 58.714386 -7.406386) (xy 60.208414 -8.900414) (xy 60.215809 -8.907268)
			(xy 60.234408 -8.91501) (xy 60.244482 -8.9154) (xy 84.515452 -8.9154) (xy 84.524088 -8.914638) (xy 84.531611 -8.913044)
			(xy 84.545311 -8.90608) (xy 84.551012 -8.900922) (xy 87.213948 -6.237986) (xy 87.221345 -6.231138)
			(xy 87.239944 -6.223407) (xy 87.250016 -6.223) (xy 212.221318 -6.223) (xy 212.231387 -6.223427) (xy 212.249986 -6.231146)
			(xy 212.257386 -6.237986) (xy 213.03742 -7.01802) (xy 213.044272 -7.025416) (xy 213.052012 -7.044015)
			(xy 213.052406 -7.054088) (xy 213.052406 -7.493) (xy 218.718382 -7.493) (xy 218.722453 -7.437378)
			(xy 218.734579 -7.382941) (xy 218.754502 -7.33085) (xy 218.781798 -7.282215) (xy 218.815884 -7.238072)
			(xy 218.856033 -7.199363) (xy 218.901391 -7.166912) (xy 218.950991 -7.141411) (xy 219.003775 -7.123404)
			(xy 219.058618 -7.113274) (xy 219.114352 -7.111237) (xy 219.121286 -7.112) (xy 219.861382 -7.112)
			(xy 219.865453 -7.056378) (xy 219.877579 -7.001941) (xy 219.897502 -6.94985) (xy 219.924798 -6.901215)
			(xy 219.958884 -6.857072) (xy 219.999033 -6.818363) (xy 220.044391 -6.785912) (xy 220.093991 -6.760411)
			(xy 220.146775 -6.742404) (xy 220.201618 -6.732274) (xy 220.257352 -6.730237) (xy 220.312789 -6.736337)
			(xy 220.366746 -6.750443) (xy 220.418075 -6.772255) (xy 220.465681 -6.801309) (xy 220.508549 -6.836984)
			(xy 220.545766 -6.878521) (xy 220.576539 -6.925034) (xy 220.600211 -6.975531) (xy 220.616279 -7.028938)
			(xy 220.624399 -7.084114) (xy 220.624908 -7.112) (xy 220.624399 -7.139886) (xy 220.616279 -7.195062)
			(xy 220.600211 -7.248469) (xy 220.576539 -7.298966) (xy 220.545766 -7.345479) (xy 220.508549 -7.387016)
			(xy 220.465681 -7.422691) (xy 220.418075 -7.451745) (xy 220.366746 -7.473557) (xy 220.358442 -7.475728)
			(xy 221.241364 -7.475728) (xy 221.245435 -7.420106) (xy 221.257561 -7.365669) (xy 221.277484 -7.313578)
			(xy 221.30478 -7.264943) (xy 221.338866 -7.2208) (xy 221.379015 -7.182091) (xy 221.424373 -7.14964)
			(xy 221.473973 -7.124139) (xy 221.526757 -7.106132) (xy 221.5816 -7.096002) (xy 221.637334 -7.093965)
			(xy 221.692771 -7.100065) (xy 221.746728 -7.114171) (xy 221.798057 -7.135983) (xy 221.845663 -7.165037)
			(xy 221.888531 -7.200712) (xy 221.925748 -7.242249) (xy 221.956521 -7.288762) (xy 221.980193 -7.339259)
			(xy 221.996261 -7.392666) (xy 222.004381 -7.447842) (xy 222.00489 -7.475728) (xy 222.004381 -7.503614)
			(xy 221.996261 -7.55879) (xy 221.980193 -7.612197) (xy 221.956521 -7.662694) (xy 221.925748 -7.709207)
			(xy 221.888531 -7.750744) (xy 221.845663 -7.786419) (xy 221.798057 -7.815473) (xy 221.746728 -7.837285)
			(xy 221.692771 -7.851391) (xy 221.637334 -7.857491) (xy 221.5816 -7.855454) (xy 221.526757 -7.845324)
			(xy 221.473973 -7.827317) (xy 221.424373 -7.801816) (xy 221.379015 -7.769365) (xy 221.338866 -7.730656)
			(xy 221.30478 -7.686513) (xy 221.277484 -7.637878) (xy 221.257561 -7.585787) (xy 221.245435 -7.53135)
			(xy 221.241364 -7.475728) (xy 220.358442 -7.475728) (xy 220.312789 -7.487663) (xy 220.257352 -7.493763)
			(xy 220.201618 -7.491726) (xy 220.146775 -7.481596) (xy 220.093991 -7.463589) (xy 220.044391 -7.438088)
			(xy 219.999033 -7.405637) (xy 219.958884 -7.366928) (xy 219.924798 -7.322785) (xy 219.897502 -7.27415)
			(xy 219.877579 -7.222059) (xy 219.865453 -7.167622) (xy 219.861382 -7.112) (xy 219.121286 -7.112)
			(xy 219.169789 -7.117337) (xy 219.223746 -7.131443) (xy 219.275075 -7.153255) (xy 219.322681 -7.182309)
			(xy 219.365549 -7.217984) (xy 219.402766 -7.259521) (xy 219.433539 -7.306034) (xy 219.457211 -7.356531)
			(xy 219.473279 -7.409938) (xy 219.481399 -7.465114) (xy 219.481908 -7.493) (xy 219.481399 -7.520886)
			(xy 219.473279 -7.576062) (xy 219.457211 -7.629469) (xy 219.433539 -7.679966) (xy 219.402766 -7.726479)
			(xy 219.365549 -7.768016) (xy 219.322681 -7.803691) (xy 219.275075 -7.832745) (xy 219.223746 -7.854557)
			(xy 219.169789 -7.868663) (xy 219.114352 -7.874763) (xy 219.058618 -7.872726) (xy 219.003775 -7.862596)
			(xy 218.950991 -7.844589) (xy 218.901391 -7.819088) (xy 218.856033 -7.786637) (xy 218.815884 -7.747928)
			(xy 218.781798 -7.703785) (xy 218.754502 -7.65515) (xy 218.734579 -7.603059) (xy 218.722453 -7.548622)
			(xy 218.718382 -7.493) (xy 213.052406 -7.493) (xy 213.052406 -8.001) (xy 219.861382 -8.001) (xy 219.865453 -7.945378)
			(xy 219.877579 -7.890941) (xy 219.897502 -7.83885) (xy 219.924798 -7.790215) (xy 219.958884 -7.746072)
			(xy 219.999033 -7.707363) (xy 220.044391 -7.674912) (xy 220.093991 -7.649411) (xy 220.146775 -7.631404)
			(xy 220.201618 -7.621274) (xy 220.257352 -7.619237) (xy 220.312789 -7.625337) (xy 220.366746 -7.639443)
			(xy 220.418075 -7.661255) (xy 220.465681 -7.690309) (xy 220.508549 -7.725984) (xy 220.545766 -7.767521)
			(xy 220.576539 -7.814034) (xy 220.600211 -7.864531) (xy 220.616279 -7.917938) (xy 220.624399 -7.973114)
			(xy 220.624908 -8.001) (xy 220.624399 -8.028886) (xy 220.616279 -8.084062) (xy 220.600211 -8.137469)
			(xy 220.576539 -8.187966) (xy 220.545766 -8.234479) (xy 220.508549 -8.276016) (xy 220.465681 -8.311691)
			(xy 220.418075 -8.340745) (xy 220.366746 -8.362557) (xy 220.312789 -8.376663) (xy 220.257352 -8.382763)
			(xy 220.201618 -8.380726) (xy 220.146775 -8.370596) (xy 220.093991 -8.352589) (xy 220.044391 -8.327088)
			(xy 219.999033 -8.294637) (xy 219.958884 -8.255928) (xy 219.924798 -8.211785) (xy 219.897502 -8.16315)
			(xy 219.877579 -8.111059) (xy 219.865453 -8.056622) (xy 219.861382 -8.001) (xy 213.052406 -8.001)
			(xy 213.052406 -11.049) (xy 272.541492 -11.049) (xy 272.541975 -11.020081) (xy 272.550707 -10.962907)
			(xy 272.567969 -10.907706) (xy 272.593367 -10.855744) (xy 272.626319 -10.808211) (xy 272.666068 -10.766197)
			(xy 272.688558 -10.74801) (xy 272.697321 -10.740449) (xy 272.707501 -10.719689) (xy 272.708116 -10.708132)
			(xy 272.708116 -10.627868) (xy 272.707501 -10.616306) (xy 272.697337 -10.595535) (xy 272.688558 -10.58799)
			(xy 272.666061 -10.569815) (xy 272.626329 -10.527791) (xy 272.593392 -10.480252) (xy 272.568007 -10.428288)
			(xy 272.550753 -10.373088) (xy 272.542026 -10.315917) (xy 272.541492 -10.287) (xy 272.541978 -10.259749)
			(xy 272.549734 -10.205801) (xy 272.565089 -10.153506) (xy 272.587731 -10.103929) (xy 272.617197 -10.058079)
			(xy 272.652888 -10.016888) (xy 272.694079 -9.981197) (xy 272.739929 -9.951731) (xy 272.789506 -9.929089)
			(xy 272.841801 -9.913734) (xy 272.895749 -9.905978) (xy 272.923 -9.905492) (xy 272.951919 -9.905975)
			(xy 273.009093 -9.914707) (xy 273.064294 -9.931969) (xy 273.116256 -9.957367) (xy 273.163789 -9.990319)
			(xy 273.205803 -10.030068) (xy 273.22399 -10.052558) (xy 273.231551 -10.061321) (xy 273.252311 -10.071501)
			(xy 273.263868 -10.072116) (xy 273.344132 -10.072116) (xy 273.355694 -10.071501) (xy 273.376465 -10.061337)
			(xy 273.38401 -10.052558) (xy 273.400763 -10.031775) (xy 273.439117 -9.994645) (xy 273.482271 -9.963223)
			(xy 273.529385 -9.938124) (xy 273.579537 -9.919838) (xy 273.631748 -9.908721) (xy 273.685 -9.904991)
			(xy 273.738252 -9.908721) (xy 273.790463 -9.919838) (xy 273.840615 -9.938124) (xy 273.887729 -9.963223)
			(xy 273.930883 -9.994645) (xy 273.969237 -10.031775) (xy 273.98599 -10.052558) (xy 273.993551 -10.061321)
			(xy 274.014311 -10.071501) (xy 274.025868 -10.072116) (xy 274.106132 -10.072116) (xy 274.117694 -10.071501)
			(xy 274.138465 -10.061337) (xy 274.14601 -10.052558) (xy 274.162763 -10.031775) (xy 274.201117 -9.994645)
			(xy 274.244271 -9.963223) (xy 274.291385 -9.938124) (xy 274.341537 -9.919838) (xy 274.393748 -9.908721)
			(xy 274.447 -9.904991) (xy 274.500252 -9.908721) (xy 274.552463 -9.919838) (xy 274.602615 -9.938124)
			(xy 274.649729 -9.963223) (xy 274.692883 -9.994645) (xy 274.731237 -10.031775) (xy 274.74799 -10.052558)
			(xy 274.755551 -10.061321) (xy 274.776311 -10.071501) (xy 274.787868 -10.072116) (xy 274.868132 -10.072116)
			(xy 274.879694 -10.071501) (xy 274.900465 -10.061337) (xy 274.90801 -10.052558) (xy 274.924763 -10.031775)
			(xy 274.963117 -9.994645) (xy 275.006271 -9.963223) (xy 275.053385 -9.938124) (xy 275.103537 -9.919838)
			(xy 275.155748 -9.908721) (xy 275.209 -9.904991) (xy 275.262252 -9.908721) (xy 275.314463 -9.919838)
			(xy 275.364615 -9.938124) (xy 275.411729 -9.963223) (xy 275.454883 -9.994645) (xy 275.493237 -10.031775)
			(xy 275.50999 -10.052558) (xy 275.517551 -10.061321) (xy 275.538311 -10.071501) (xy 275.549868 -10.072116)
			(xy 275.630132 -10.072116) (xy 275.641694 -10.071501) (xy 275.662465 -10.061337) (xy 275.67001 -10.052558)
			(xy 275.688185 -10.030061) (xy 275.730209 -9.990329) (xy 275.777748 -9.957392) (xy 275.829712 -9.932007)
			(xy 275.884912 -9.914753) (xy 275.942083 -9.906026) (xy 275.971 -9.905492) (xy 275.998251 -9.905978)
			(xy 276.052199 -9.913734) (xy 276.103053 -9.928666) (xy 292.319752 -9.928666) (xy 292.319752 -9.874134)
			(xy 292.327512 -9.820158) (xy 292.342875 -9.767835) (xy 292.365527 -9.718231) (xy 292.395007 -9.672355)
			(xy 292.430716 -9.631141) (xy 292.471926 -9.595429) (xy 292.517799 -9.565944) (xy 292.567401 -9.543287)
			(xy 292.619723 -9.52792) (xy 292.673698 -9.520155) (xy 292.700964 -9.519666) (xy 292.729866 -9.520223)
			(xy 292.787008 -9.528939) (xy 292.842186 -9.546163) (xy 292.89414 -9.5715) (xy 292.941685 -9.604374)
			(xy 292.983737 -9.644034) (xy 293.001954 -9.666478) (xy 293.011851 -9.678283) (xy 293.037175 -9.695802)
			(xy 293.066568 -9.704978) (xy 293.09736 -9.704978) (xy 293.126753 -9.695802) (xy 293.152077 -9.678283)
			(xy 293.161974 -9.666478) (xy 293.178766 -9.645745) (xy 293.217147 -9.608686) (xy 293.260312 -9.57733)
			(xy 293.30742 -9.552285) (xy 293.357555 -9.534039) (xy 293.409742 -9.522948) (xy 293.462964 -9.519226)
			(xy 293.516186 -9.522948) (xy 293.568373 -9.534039) (xy 293.618508 -9.552285) (xy 293.665616 -9.57733)
			(xy 293.708781 -9.608686) (xy 293.747162 -9.645745) (xy 293.763954 -9.666478) (xy 293.773851 -9.678283)
			(xy 293.799175 -9.695802) (xy 293.828568 -9.704978) (xy 293.85936 -9.704978) (xy 293.888753 -9.695802)
			(xy 293.914077 -9.678283) (xy 293.923974 -9.666478) (xy 293.940766 -9.645745) (xy 293.979147 -9.608686)
			(xy 294.022312 -9.57733) (xy 294.06942 -9.552285) (xy 294.119555 -9.534039) (xy 294.171742 -9.522948)
			(xy 294.224964 -9.519226) (xy 294.278186 -9.522948) (xy 294.330373 -9.534039) (xy 294.380508 -9.552285)
			(xy 294.427616 -9.57733) (xy 294.470781 -9.608686) (xy 294.509162 -9.645745) (xy 294.525954 -9.666478)
			(xy 294.535851 -9.678283) (xy 294.561175 -9.695802) (xy 294.590568 -9.704978) (xy 294.62136 -9.704978)
			(xy 294.650753 -9.695802) (xy 294.676077 -9.678283) (xy 294.685974 -9.666478) (xy 294.704154 -9.644)
			(xy 294.746206 -9.60433) (xy 294.793756 -9.571451) (xy 294.845719 -9.546113) (xy 294.900906 -9.528896)
			(xy 294.958058 -9.520193) (xy 294.986964 -9.519666) (xy 295.014239 -9.520071) (xy 295.068233 -9.52783)
			(xy 295.120574 -9.543194) (xy 295.170196 -9.565851) (xy 295.216087 -9.59534) (xy 295.257315 -9.63106)
			(xy 295.293038 -9.672284) (xy 295.322532 -9.718173) (xy 295.345193 -9.767792) (xy 295.355141 -9.801666)
			(xy 309.718752 -9.801666) (xy 309.718752 -9.747134) (xy 309.726512 -9.693158) (xy 309.741875 -9.640835)
			(xy 309.764527 -9.591231) (xy 309.794007 -9.545355) (xy 309.829716 -9.504141) (xy 309.870926 -9.468429)
			(xy 309.916799 -9.438944) (xy 309.966401 -9.416287) (xy 310.018723 -9.40092) (xy 310.072698 -9.393155)
			(xy 310.099964 -9.392666) (xy 310.12891 -9.393191) (xy 310.186135 -9.401952) (xy 310.241383 -9.419249)
			(xy 310.293388 -9.444685) (xy 310.340959 -9.477678) (xy 310.383006 -9.517473) (xy 310.401208 -9.539986)
			(xy 310.408773 -9.548745) (xy 310.429529 -9.558931) (xy 310.441086 -9.559544) (xy 310.520842 -9.559544)
			(xy 310.532409 -9.55896) (xy 310.553181 -9.548777) (xy 310.56072 -9.539986) (xy 310.577482 -9.519176)
			(xy 310.61586 -9.481997) (xy 310.659047 -9.450533) (xy 310.706201 -9.425399) (xy 310.756399 -9.407087)
			(xy 310.808661 -9.395955) (xy 310.861964 -9.392219) (xy 310.915267 -9.395955) (xy 310.967529 -9.407087)
			(xy 311.017727 -9.425399) (xy 311.064881 -9.450533) (xy 311.108068 -9.481997) (xy 311.146446 -9.519176)
			(xy 311.163208 -9.539986) (xy 311.170773 -9.548745) (xy 311.191529 -9.558931) (xy 311.203086 -9.559544)
			(xy 311.282842 -9.559544) (xy 311.294409 -9.55896) (xy 311.315181 -9.548777) (xy 311.32272 -9.539986)
			(xy 311.339482 -9.519176) (xy 311.37786 -9.481997) (xy 311.421047 -9.450533) (xy 311.468201 -9.425399)
			(xy 311.518399 -9.407087) (xy 311.570661 -9.395955) (xy 311.623964 -9.392219) (xy 311.677267 -9.395955)
			(xy 311.729529 -9.407087) (xy 311.779727 -9.425399) (xy 311.826881 -9.450533) (xy 311.870068 -9.481997)
			(xy 311.908446 -9.519176) (xy 311.925208 -9.539986) (xy 311.932773 -9.548745) (xy 311.953529 -9.558931)
			(xy 311.965086 -9.559544) (xy 312.044842 -9.559544) (xy 312.056409 -9.55896) (xy 312.077181 -9.548777)
			(xy 312.08472 -9.539986) (xy 312.102911 -9.517462) (xy 312.144949 -9.477654) (xy 312.192519 -9.444654)
			(xy 312.244529 -9.41922) (xy 312.299784 -9.401935) (xy 312.357016 -9.393198) (xy 312.385964 -9.392666)
			(xy 312.413239 -9.393071) (xy 312.467233 -9.40083) (xy 312.519574 -9.416194) (xy 312.569196 -9.438851)
			(xy 312.615087 -9.46834) (xy 312.656315 -9.50406) (xy 312.692038 -9.545284) (xy 312.721532 -9.591173)
			(xy 312.744193 -9.640792) (xy 312.759563 -9.693131) (xy 312.767326 -9.747125) (xy 312.767326 -9.801666)
			(xy 320.005752 -9.801666) (xy 320.005752 -9.747134) (xy 320.013512 -9.693158) (xy 320.028875 -9.640835)
			(xy 320.051527 -9.591231) (xy 320.081007 -9.545355) (xy 320.116716 -9.504141) (xy 320.157926 -9.468429)
			(xy 320.203799 -9.438944) (xy 320.253401 -9.416287) (xy 320.305723 -9.40092) (xy 320.359698 -9.393155)
			(xy 320.386964 -9.392666) (xy 320.415866 -9.393223) (xy 320.473008 -9.401939) (xy 320.528186 -9.419163)
			(xy 320.58014 -9.4445) (xy 320.627685 -9.477374) (xy 320.669737 -9.517034) (xy 320.687954 -9.539478)
			(xy 320.697851 -9.551283) (xy 320.723175 -9.568802) (xy 320.752568 -9.577978) (xy 320.78336 -9.577978)
			(xy 320.812753 -9.568802) (xy 320.838077 -9.551283) (xy 320.847974 -9.539478) (xy 320.864766 -9.518745)
			(xy 320.903147 -9.481686) (xy 320.946312 -9.45033) (xy 320.99342 -9.425285) (xy 321.043555 -9.407039)
			(xy 321.095742 -9.395948) (xy 321.148964 -9.392226) (xy 321.202186 -9.395948) (xy 321.254373 -9.407039)
			(xy 321.304508 -9.425285) (xy 321.351616 -9.45033) (xy 321.394781 -9.481686) (xy 321.433162 -9.518745)
			(xy 321.449954 -9.539478) (xy 321.459851 -9.551283) (xy 321.485175 -9.568802) (xy 321.514568 -9.577978)
			(xy 321.54536 -9.577978) (xy 321.574753 -9.568802) (xy 321.600077 -9.551283) (xy 321.609974 -9.539478)
			(xy 321.626766 -9.518745) (xy 321.665147 -9.481686) (xy 321.708312 -9.45033) (xy 321.75542 -9.425285)
			(xy 321.805555 -9.407039) (xy 321.857742 -9.395948) (xy 321.910964 -9.392226) (xy 321.964186 -9.395948)
			(xy 322.016373 -9.407039) (xy 322.066508 -9.425285) (xy 322.113616 -9.45033) (xy 322.156781 -9.481686)
			(xy 322.195162 -9.518745) (xy 322.211954 -9.539478) (xy 322.221851 -9.551283) (xy 322.247175 -9.568802)
			(xy 322.276568 -9.577978) (xy 322.30736 -9.577978) (xy 322.336753 -9.568802) (xy 322.362077 -9.551283)
			(xy 322.371974 -9.539478) (xy 322.390154 -9.517) (xy 322.432206 -9.47733) (xy 322.479756 -9.444451)
			(xy 322.531719 -9.419113) (xy 322.586906 -9.401896) (xy 322.644058 -9.393193) (xy 322.672964 -9.392666)
			(xy 322.700239 -9.393071) (xy 322.754233 -9.40083) (xy 322.806574 -9.416194) (xy 322.856196 -9.438851)
			(xy 322.902087 -9.46834) (xy 322.943315 -9.50406) (xy 322.979038 -9.545284) (xy 323.008532 -9.591173)
			(xy 323.031193 -9.640792) (xy 323.046563 -9.693131) (xy 323.054326 -9.747125) (xy 323.054326 -9.801666)
			(xy 331.689752 -9.801666) (xy 331.689752 -9.747134) (xy 331.697512 -9.693158) (xy 331.712875 -9.640835)
			(xy 331.735527 -9.591231) (xy 331.765007 -9.545355) (xy 331.800716 -9.504141) (xy 331.841926 -9.468429)
			(xy 331.887799 -9.438944) (xy 331.937401 -9.416287) (xy 331.989723 -9.40092) (xy 332.043698 -9.393155)
			(xy 332.070964 -9.392666) (xy 332.099866 -9.393223) (xy 332.157008 -9.401939) (xy 332.212186 -9.419163)
			(xy 332.26414 -9.4445) (xy 332.311685 -9.477374) (xy 332.353737 -9.517034) (xy 332.371954 -9.539478)
			(xy 332.381851 -9.551283) (xy 332.407175 -9.568802) (xy 332.436568 -9.577978) (xy 332.46736 -9.577978)
			(xy 332.496753 -9.568802) (xy 332.522077 -9.551283) (xy 332.531974 -9.539478) (xy 332.548766 -9.518745)
			(xy 332.587147 -9.481686) (xy 332.630312 -9.45033) (xy 332.67742 -9.425285) (xy 332.727555 -9.407039)
			(xy 332.779742 -9.395948) (xy 332.832964 -9.392226) (xy 332.886186 -9.395948) (xy 332.938373 -9.407039)
			(xy 332.988508 -9.425285) (xy 333.035616 -9.45033) (xy 333.078781 -9.481686) (xy 333.117162 -9.518745)
			(xy 333.133954 -9.539478) (xy 333.143851 -9.551283) (xy 333.169175 -9.568802) (xy 333.198568 -9.577978)
			(xy 333.22936 -9.577978) (xy 333.258753 -9.568802) (xy 333.284077 -9.551283) (xy 333.293974 -9.539478)
			(xy 333.310766 -9.518745) (xy 333.349147 -9.481686) (xy 333.392312 -9.45033) (xy 333.43942 -9.425285)
			(xy 333.489555 -9.407039) (xy 333.541742 -9.395948) (xy 333.594964 -9.392226) (xy 333.648186 -9.395948)
			(xy 333.700373 -9.407039) (xy 333.750508 -9.425285) (xy 333.797616 -9.45033) (xy 333.840781 -9.481686)
			(xy 333.879162 -9.518745) (xy 333.895954 -9.539478) (xy 333.905851 -9.551283) (xy 333.931175 -9.568802)
			(xy 333.960568 -9.577978) (xy 333.99136 -9.577978) (xy 334.020753 -9.568802) (xy 334.046077 -9.551283)
			(xy 334.055974 -9.539478) (xy 334.074154 -9.517) (xy 334.116206 -9.47733) (xy 334.163756 -9.444451)
			(xy 334.215719 -9.419113) (xy 334.270906 -9.401896) (xy 334.328058 -9.393193) (xy 334.356964 -9.392666)
			(xy 334.384239 -9.393071) (xy 334.438233 -9.40083) (xy 334.490574 -9.416194) (xy 334.540196 -9.438851)
			(xy 334.586087 -9.46834) (xy 334.627315 -9.50406) (xy 334.663038 -9.545284) (xy 334.692532 -9.591173)
			(xy 334.715193 -9.640792) (xy 334.730563 -9.693131) (xy 334.738326 -9.747125) (xy 334.738326 -9.801675)
			(xy 334.730563 -9.855669) (xy 334.715762 -9.906071) (xy 342.343424 -9.906071) (xy 342.343424 -9.851529)
			(xy 342.351186 -9.797541) (xy 342.366554 -9.745209) (xy 342.389213 -9.695596) (xy 342.418703 -9.649713)
			(xy 342.454422 -9.608494) (xy 342.495645 -9.572779) (xy 342.541531 -9.543294) (xy 342.591146 -9.52064)
			(xy 342.643481 -9.505278) (xy 342.697469 -9.497521) (xy 342.72474 -9.49706) (xy 342.753685 -9.497604)
			(xy 342.81091 -9.506362) (xy 342.866157 -9.523655) (xy 342.918162 -9.549088) (xy 342.965733 -9.582077)
			(xy 343.007781 -9.621868) (xy 343.025984 -9.64438) (xy 343.033544 -9.653143) (xy 343.054305 -9.663323)
			(xy 343.065862 -9.663938) (xy 343.145618 -9.663938) (xy 343.157191 -9.663399) (xy 343.177962 -9.653184)
			(xy 343.185496 -9.64438) (xy 343.202258 -9.62357) (xy 343.240636 -9.586391) (xy 343.283823 -9.554927)
			(xy 343.330977 -9.529793) (xy 343.381175 -9.511481) (xy 343.433437 -9.500349) (xy 343.48674 -9.496613)
			(xy 343.540043 -9.500349) (xy 343.592305 -9.511481) (xy 343.642503 -9.529793) (xy 343.689657 -9.554927)
			(xy 343.732844 -9.586391) (xy 343.771222 -9.62357) (xy 343.787984 -9.64438) (xy 343.795544 -9.653143)
			(xy 343.816305 -9.663323) (xy 343.827862 -9.663938) (xy 343.907872 -9.663938) (xy 343.919441 -9.663373)
			(xy 343.940213 -9.653177) (xy 343.94775 -9.64438) (xy 343.964503 -9.623597) (xy 344.002857 -9.586467)
			(xy 344.046011 -9.555045) (xy 344.093125 -9.529946) (xy 344.143277 -9.51166) (xy 344.195488 -9.500543)
			(xy 344.24874 -9.496813) (xy 344.301992 -9.500543) (xy 344.354203 -9.51166) (xy 344.404355 -9.529946)
			(xy 344.451469 -9.555045) (xy 344.494623 -9.586467) (xy 344.532977 -9.623597) (xy 344.54973 -9.64438)
			(xy 344.55727 -9.653164) (xy 344.578046 -9.663332) (xy 344.589608 -9.663938) (xy 344.669872 -9.663938)
			(xy 344.681441 -9.663373) (xy 344.702213 -9.653177) (xy 344.70975 -9.64438) (xy 344.727964 -9.621916)
			(xy 344.76998 -9.582181) (xy 344.81751 -9.54924) (xy 344.869467 -9.523848) (xy 344.92466 -9.506588)
			(xy 344.981825 -9.497853) (xy 345.01074 -9.497314) (xy 345.037991 -9.497759) (xy 345.091937 -9.50552)
			(xy 345.14423 -9.52088) (xy 345.193805 -9.543524) (xy 345.239654 -9.572993) (xy 345.280841 -9.608687)
			(xy 345.316531 -9.649879) (xy 345.345995 -9.69573) (xy 345.368634 -9.745307) (xy 345.383988 -9.797602)
			(xy 345.391744 -9.851549) (xy 345.391744 -9.906051) (xy 345.383988 -9.959998) (xy 345.368634 -10.012293)
			(xy 345.345995 -10.06187) (xy 345.316531 -10.107721) (xy 345.280841 -10.148913) (xy 345.239654 -10.184607)
			(xy 345.193805 -10.214076) (xy 345.14423 -10.23672) (xy 345.091937 -10.25208) (xy 345.037991 -10.259841)
			(xy 345.01074 -10.26033) (xy 344.981823 -10.25981) (xy 344.924651 -10.251085) (xy 344.869451 -10.233829)
			(xy 344.817488 -10.208438) (xy 344.769954 -10.175493) (xy 344.727939 -10.135751) (xy 344.70975 -10.113264)
			(xy 344.702168 -10.104523) (xy 344.681424 -10.09433) (xy 344.669872 -10.093706) (xy 344.589608 -10.093706)
			(xy 344.578041 -10.094279) (xy 344.55727 -10.104472) (xy 344.54973 -10.113264) (xy 344.532977 -10.134047)
			(xy 344.494623 -10.171177) (xy 344.451469 -10.202599) (xy 344.404355 -10.227698) (xy 344.354203 -10.245984)
			(xy 344.301992 -10.257101) (xy 344.24874 -10.260831) (xy 344.195488 -10.257101) (xy 344.143277 -10.245984)
			(xy 344.093125 -10.227698) (xy 344.046011 -10.202599) (xy 344.002857 -10.171177) (xy 343.964503 -10.134047)
			(xy 343.94775 -10.113264) (xy 343.940168 -10.104523) (xy 343.919424 -10.09433) (xy 343.907872 -10.093706)
			(xy 343.827862 -10.093706) (xy 343.816298 -10.09431) (xy 343.795527 -10.104481) (xy 343.787984 -10.113264)
			(xy 343.771222 -10.134074) (xy 343.732844 -10.171253) (xy 343.689657 -10.202717) (xy 343.642503 -10.227851)
			(xy 343.592305 -10.246163) (xy 343.540043 -10.257295) (xy 343.48674 -10.261031) (xy 343.433437 -10.257295)
			(xy 343.381175 -10.246163) (xy 343.330977 -10.227851) (xy 343.283823 -10.202717) (xy 343.240636 -10.171253)
			(xy 343.202258 -10.134074) (xy 343.185496 -10.113264) (xy 343.177938 -10.104499) (xy 343.157176 -10.094319)
			(xy 343.145618 -10.093706) (xy 343.065862 -10.093706) (xy 343.054298 -10.09431) (xy 343.033527 -10.104481)
			(xy 343.025984 -10.113264) (xy 343.007803 -10.135797) (xy 342.965761 -10.175602) (xy 342.918189 -10.2086)
			(xy 342.866178 -10.234032) (xy 342.810921 -10.251315) (xy 342.753688 -10.260052) (xy 342.72474 -10.260584)
			(xy 342.697469 -10.260079) (xy 342.643481 -10.252322) (xy 342.591146 -10.23696) (xy 342.541531 -10.214306)
			(xy 342.495645 -10.184821) (xy 342.454422 -10.149106) (xy 342.418703 -10.107887) (xy 342.389213 -10.062004)
			(xy 342.366554 -10.012391) (xy 342.351186 -9.960059) (xy 342.343424 -9.906071) (xy 334.715762 -9.906071)
			(xy 334.715193 -9.908008) (xy 334.692532 -9.957627) (xy 334.663038 -10.003516) (xy 334.627315 -10.04474)
			(xy 334.586087 -10.08046) (xy 334.540196 -10.109949) (xy 334.490574 -10.132606) (xy 334.438233 -10.14797)
			(xy 334.384239 -10.155729) (xy 334.356964 -10.15619) (xy 334.328062 -10.155629) (xy 334.270919 -10.146917)
			(xy 334.215741 -10.129695) (xy 334.163786 -10.104358) (xy 334.116241 -10.071484) (xy 334.07419 -10.031823)
			(xy 334.055974 -10.009378) (xy 334.046077 -9.997573) (xy 334.020753 -9.980054) (xy 333.99136 -9.970878)
			(xy 333.960568 -9.970878) (xy 333.931175 -9.980054) (xy 333.905851 -9.997573) (xy 333.895954 -10.009378)
			(xy 333.879162 -10.030111) (xy 333.840781 -10.06717) (xy 333.797616 -10.098526) (xy 333.750508 -10.123571)
			(xy 333.700373 -10.141817) (xy 333.648186 -10.152908) (xy 333.594964 -10.15663) (xy 333.541742 -10.152908)
			(xy 333.489555 -10.141817) (xy 333.43942 -10.123571) (xy 333.392312 -10.098526) (xy 333.349147 -10.06717)
			(xy 333.310766 -10.030111) (xy 333.293974 -10.009378) (xy 333.284077 -9.997573) (xy 333.258753 -9.980054)
			(xy 333.22936 -9.970878) (xy 333.198568 -9.970878) (xy 333.169175 -9.980054) (xy 333.143851 -9.997573)
			(xy 333.133954 -10.009378) (xy 333.117162 -10.030111) (xy 333.078781 -10.06717) (xy 333.035616 -10.098526)
			(xy 332.988508 -10.123571) (xy 332.938373 -10.141817) (xy 332.886186 -10.152908) (xy 332.832964 -10.15663)
			(xy 332.779742 -10.152908) (xy 332.727555 -10.141817) (xy 332.67742 -10.123571) (xy 332.630312 -10.098526)
			(xy 332.587147 -10.06717) (xy 332.548766 -10.030111) (xy 332.531974 -10.009378) (xy 332.522077 -9.997573)
			(xy 332.496753 -9.980054) (xy 332.46736 -9.970878) (xy 332.436568 -9.970878) (xy 332.407175 -9.980054)
			(xy 332.381851 -9.997573) (xy 332.371954 -10.009378) (xy 332.353747 -10.031833) (xy 332.311702 -10.071507)
			(xy 332.264158 -10.10439) (xy 332.2122 -10.129732) (xy 332.157017 -10.146954) (xy 332.099868 -10.155661)
			(xy 332.070964 -10.15619) (xy 332.043698 -10.155645) (xy 331.989723 -10.14788) (xy 331.937401 -10.132513)
			(xy 331.887799 -10.109856) (xy 331.841926 -10.080371) (xy 331.800716 -10.044659) (xy 331.765007 -10.003445)
			(xy 331.735527 -9.957569) (xy 331.712875 -9.907965) (xy 331.697512 -9.855642) (xy 331.689752 -9.801666)
			(xy 323.054326 -9.801666) (xy 323.054326 -9.801675) (xy 323.046563 -9.855669) (xy 323.031193 -9.908008)
			(xy 323.008532 -9.957627) (xy 322.979038 -10.003516) (xy 322.943315 -10.04474) (xy 322.902087 -10.08046)
			(xy 322.856196 -10.109949) (xy 322.806574 -10.132606) (xy 322.754233 -10.14797) (xy 322.700239 -10.155729)
			(xy 322.672964 -10.15619) (xy 322.644062 -10.155629) (xy 322.586919 -10.146917) (xy 322.531741 -10.129695)
			(xy 322.479786 -10.104358) (xy 322.432241 -10.071484) (xy 322.39019 -10.031823) (xy 322.371974 -10.009378)
			(xy 322.362077 -9.997573) (xy 322.336753 -9.980054) (xy 322.30736 -9.970878) (xy 322.276568 -9.970878)
			(xy 322.247175 -9.980054) (xy 322.221851 -9.997573) (xy 322.211954 -10.009378) (xy 322.195162 -10.030111)
			(xy 322.156781 -10.06717) (xy 322.113616 -10.098526) (xy 322.066508 -10.123571) (xy 322.016373 -10.141817)
			(xy 321.964186 -10.152908) (xy 321.910964 -10.15663) (xy 321.857742 -10.152908) (xy 321.805555 -10.141817)
			(xy 321.75542 -10.123571) (xy 321.708312 -10.098526) (xy 321.665147 -10.06717) (xy 321.626766 -10.030111)
			(xy 321.609974 -10.009378) (xy 321.600077 -9.997573) (xy 321.574753 -9.980054) (xy 321.54536 -9.970878)
			(xy 321.514568 -9.970878) (xy 321.485175 -9.980054) (xy 321.459851 -9.997573) (xy 321.449954 -10.009378)
			(xy 321.433162 -10.030111) (xy 321.394781 -10.06717) (xy 321.351616 -10.098526) (xy 321.304508 -10.123571)
			(xy 321.254373 -10.141817) (xy 321.202186 -10.152908) (xy 321.148964 -10.15663) (xy 321.095742 -10.152908)
			(xy 321.043555 -10.141817) (xy 320.99342 -10.123571) (xy 320.946312 -10.098526) (xy 320.903147 -10.06717)
			(xy 320.864766 -10.030111) (xy 320.847974 -10.009378) (xy 320.838077 -9.997573) (xy 320.812753 -9.980054)
			(xy 320.78336 -9.970878) (xy 320.752568 -9.970878) (xy 320.723175 -9.980054) (xy 320.697851 -9.997573)
			(xy 320.687954 -10.009378) (xy 320.669747 -10.031833) (xy 320.627702 -10.071507) (xy 320.580158 -10.10439)
			(xy 320.5282 -10.129732) (xy 320.473017 -10.146954) (xy 320.415868 -10.155661) (xy 320.386964 -10.15619)
			(xy 320.359698 -10.155645) (xy 320.305723 -10.14788) (xy 320.253401 -10.132513) (xy 320.203799 -10.109856)
			(xy 320.157926 -10.080371) (xy 320.116716 -10.044659) (xy 320.081007 -10.003445) (xy 320.051527 -9.957569)
			(xy 320.028875 -9.907965) (xy 320.013512 -9.855642) (xy 320.005752 -9.801666) (xy 312.767326 -9.801666)
			(xy 312.767326 -9.801675) (xy 312.759563 -9.855669) (xy 312.744193 -9.908008) (xy 312.721532 -9.957627)
			(xy 312.692038 -10.003516) (xy 312.656315 -10.04474) (xy 312.615087 -10.08046) (xy 312.569196 -10.109949)
			(xy 312.519574 -10.132606) (xy 312.467233 -10.14797) (xy 312.413239 -10.155729) (xy 312.385964 -10.15619)
			(xy 312.357018 -10.155662) (xy 312.299792 -10.146904) (xy 312.244543 -10.129609) (xy 312.192538 -10.104173)
			(xy 312.144967 -10.07118) (xy 312.102921 -10.031384) (xy 312.08472 -10.00887) (xy 312.07715 -10.000117)
			(xy 312.056397 -9.98993) (xy 312.044842 -9.989312) (xy 311.965086 -9.989312) (xy 311.953516 -9.98987)
			(xy 311.932745 -10.000073) (xy 311.925208 -10.00887) (xy 311.908446 -10.02968) (xy 311.870068 -10.066859)
			(xy 311.826881 -10.098323) (xy 311.779727 -10.123457) (xy 311.729529 -10.141769) (xy 311.677267 -10.152901)
			(xy 311.623964 -10.156637) (xy 311.570661 -10.152901) (xy 311.518399 -10.141769) (xy 311.468201 -10.123457)
			(xy 311.421047 -10.098323) (xy 311.37786 -10.066859) (xy 311.339482 -10.02968) (xy 311.32272 -10.00887)
			(xy 311.31515 -10.000117) (xy 311.294397 -9.98993) (xy 311.282842 -9.989312) (xy 311.203086 -9.989312)
			(xy 311.191516 -9.98987) (xy 311.170745 -10.000073) (xy 311.163208 -10.00887) (xy 311.146446 -10.02968)
			(xy 311.108068 -10.066859) (xy 311.064881 -10.098323) (xy 311.017727 -10.123457) (xy 310.967529 -10.141769)
			(xy 310.915267 -10.152901) (xy 310.861964 -10.156637) (xy 310.808661 -10.152901) (xy 310.756399 -10.141769)
			(xy 310.706201 -10.123457) (xy 310.659047 -10.098323) (xy 310.61586 -10.066859) (xy 310.577482 -10.02968)
			(xy 310.56072 -10.00887) (xy 310.55315 -10.000117) (xy 310.532397 -9.98993) (xy 310.520842 -9.989312)
			(xy 310.441086 -9.989312) (xy 310.429516 -9.98987) (xy 310.408745 -10.000073) (xy 310.401208 -10.00887)
			(xy 310.383015 -10.031392) (xy 310.340976 -10.071198) (xy 310.293406 -10.104197) (xy 310.241397 -10.129631)
			(xy 310.186143 -10.146916) (xy 310.128911 -10.155656) (xy 310.099964 -10.15619) (xy 310.072698 -10.155645)
			(xy 310.018723 -10.14788) (xy 309.966401 -10.132513) (xy 309.916799 -10.109856) (xy 309.870926 -10.080371)
			(xy 309.829716 -10.044659) (xy 309.794007 -10.003445) (xy 309.764527 -9.957569) (xy 309.741875 -9.907965)
			(xy 309.726512 -9.855642) (xy 309.718752 -9.801666) (xy 295.355141 -9.801666) (xy 295.360563 -9.820131)
			(xy 295.368326 -9.874125) (xy 295.368326 -9.928675) (xy 295.360563 -9.982669) (xy 295.345193 -10.035008)
			(xy 295.322532 -10.084627) (xy 295.293038 -10.130516) (xy 295.257315 -10.17174) (xy 295.216087 -10.20746)
			(xy 295.170196 -10.236949) (xy 295.120574 -10.259606) (xy 295.068233 -10.27497) (xy 295.014239 -10.282729)
			(xy 294.986964 -10.28319) (xy 294.958062 -10.282629) (xy 294.900919 -10.273917) (xy 294.845741 -10.256695)
			(xy 294.793786 -10.231358) (xy 294.746241 -10.198484) (xy 294.70419 -10.158823) (xy 294.685974 -10.136378)
			(xy 294.676077 -10.124573) (xy 294.650753 -10.107054) (xy 294.62136 -10.097878) (xy 294.590568 -10.097878)
			(xy 294.561175 -10.107054) (xy 294.535851 -10.124573) (xy 294.525954 -10.136378) (xy 294.509162 -10.157111)
			(xy 294.470781 -10.19417) (xy 294.427616 -10.225526) (xy 294.380508 -10.250571) (xy 294.330373 -10.268817)
			(xy 294.278186 -10.279908) (xy 294.224964 -10.28363) (xy 294.171742 -10.279908) (xy 294.119555 -10.268817)
			(xy 294.06942 -10.250571) (xy 294.022312 -10.225526) (xy 293.979147 -10.19417) (xy 293.940766 -10.157111)
			(xy 293.923974 -10.136378) (xy 293.914077 -10.124573) (xy 293.888753 -10.107054) (xy 293.85936 -10.097878)
			(xy 293.828568 -10.097878) (xy 293.799175 -10.107054) (xy 293.773851 -10.124573) (xy 293.763954 -10.136378)
			(xy 293.747162 -10.157111) (xy 293.708781 -10.19417) (xy 293.665616 -10.225526) (xy 293.618508 -10.250571)
			(xy 293.568373 -10.268817) (xy 293.516186 -10.279908) (xy 293.462964 -10.28363) (xy 293.409742 -10.279908)
			(xy 293.357555 -10.268817) (xy 293.30742 -10.250571) (xy 293.260312 -10.225526) (xy 293.217147 -10.19417)
			(xy 293.178766 -10.157111) (xy 293.161974 -10.136378) (xy 293.152077 -10.124573) (xy 293.126753 -10.107054)
			(xy 293.09736 -10.097878) (xy 293.066568 -10.097878) (xy 293.037175 -10.107054) (xy 293.011851 -10.124573)
			(xy 293.001954 -10.136378) (xy 292.983747 -10.158833) (xy 292.941702 -10.198507) (xy 292.894158 -10.23139)
			(xy 292.8422 -10.256732) (xy 292.787017 -10.273954) (xy 292.729868 -10.282661) (xy 292.700964 -10.28319)
			(xy 292.673698 -10.282645) (xy 292.619723 -10.27488) (xy 292.567401 -10.259513) (xy 292.517799 -10.236856)
			(xy 292.471926 -10.207371) (xy 292.430716 -10.171659) (xy 292.395007 -10.130445) (xy 292.365527 -10.084569)
			(xy 292.342875 -10.034965) (xy 292.327512 -9.982642) (xy 292.319752 -9.928666) (xy 276.103053 -9.928666)
			(xy 276.104494 -9.929089) (xy 276.154071 -9.951731) (xy 276.199921 -9.981197) (xy 276.241112 -10.016888)
			(xy 276.276803 -10.058079) (xy 276.306269 -10.103929) (xy 276.328911 -10.153506) (xy 276.344266 -10.205801)
			(xy 276.352022 -10.259749) (xy 276.352508 -10.287) (xy 276.352133 -10.309457) (xy 359.361629 -10.309457)
			(xy 359.361629 -10.254943) (xy 359.369388 -10.200985) (xy 359.384747 -10.148681) (xy 359.407394 -10.099094)
			(xy 359.436867 -10.053236) (xy 359.472568 -10.01204) (xy 359.513768 -9.976343) (xy 359.55963 -9.946874)
			(xy 359.609218 -9.924233) (xy 359.661524 -9.908879) (xy 359.715483 -9.901126) (xy 359.74274 -9.900666)
			(xy 359.771657 -9.901203) (xy 359.828828 -9.909924) (xy 359.884027 -9.927177) (xy 359.93599 -9.952565)
			(xy 359.983524 -9.985507) (xy 360.02554 -10.025247) (xy 360.04373 -10.047732) (xy 360.051278 -10.056508)
			(xy 360.072047 -10.066683) (xy 360.083608 -10.06729) (xy 360.163872 -10.06729) (xy 360.175438 -10.066707)
			(xy 360.19621 -10.056522) (xy 360.20375 -10.047732) (xy 360.220503 -10.026949) (xy 360.258857 -9.989819)
			(xy 360.302011 -9.958397) (xy 360.349125 -9.933298) (xy 360.399277 -9.915012) (xy 360.451488 -9.903895)
			(xy 360.50474 -9.900165) (xy 360.557992 -9.903895) (xy 360.610203 -9.915012) (xy 360.660355 -9.933298)
			(xy 360.707469 -9.958397) (xy 360.750623 -9.989819) (xy 360.788977 -10.026949) (xy 360.80573 -10.047732)
			(xy 360.813278 -10.056508) (xy 360.834047 -10.066683) (xy 360.845608 -10.06729) (xy 360.925872 -10.06729)
			(xy 360.937438 -10.066707) (xy 360.95821 -10.056522) (xy 360.96575 -10.047732) (xy 360.982503 -10.026949)
			(xy 361.020857 -9.989819) (xy 361.064011 -9.958397) (xy 361.111125 -9.933298) (xy 361.161277 -9.915012)
			(xy 361.213488 -9.903895) (xy 361.26674 -9.900165) (xy 361.319992 -9.903895) (xy 361.372203 -9.915012)
			(xy 361.422355 -9.933298) (xy 361.469469 -9.958397) (xy 361.512623 -9.989819) (xy 361.550977 -10.026949)
			(xy 361.56773 -10.047732) (xy 361.575278 -10.056508) (xy 361.596047 -10.066683) (xy 361.607608 -10.06729)
			(xy 361.687872 -10.06729) (xy 361.699438 -10.066707) (xy 361.72021 -10.056522) (xy 361.72775 -10.047732)
			(xy 361.745977 -10.025279) (xy 361.787989 -9.985541) (xy 361.835516 -9.952597) (xy 361.88747 -9.927203)
			(xy 361.942661 -9.909941) (xy 361.999826 -9.901205) (xy 362.02874 -9.900666) (xy 362.055987 -9.901207)
			(xy 362.109927 -9.908968) (xy 362.162213 -9.924325) (xy 362.211782 -9.946967) (xy 362.257624 -9.976432)
			(xy 362.298807 -10.012121) (xy 362.334492 -10.053308) (xy 362.363952 -10.099153) (xy 362.386589 -10.148724)
			(xy 362.401941 -10.201012) (xy 362.409696 -10.254952) (xy 362.409696 -10.309448) (xy 362.401941 -10.363388)
			(xy 362.386589 -10.415676) (xy 362.363952 -10.465247) (xy 362.334492 -10.511092) (xy 362.298807 -10.552279)
			(xy 362.257624 -10.587968) (xy 362.211782 -10.617433) (xy 362.162213 -10.640075) (xy 362.109927 -10.655432)
			(xy 362.055987 -10.663193) (xy 362.02874 -10.663682) (xy 361.999824 -10.663142) (xy 361.942653 -10.654418)
			(xy 361.887455 -10.637165) (xy 361.835493 -10.611778) (xy 361.787958 -10.578838) (xy 361.745941 -10.5391)
			(xy 361.72775 -10.516616) (xy 361.720177 -10.507867) (xy 361.699426 -10.49768) (xy 361.687872 -10.497058)
			(xy 361.607608 -10.497058) (xy 361.596038 -10.497613) (xy 361.575265 -10.507816) (xy 361.56773 -10.516616)
			(xy 361.550977 -10.537399) (xy 361.512623 -10.574529) (xy 361.469469 -10.605951) (xy 361.422355 -10.63105)
			(xy 361.372203 -10.649336) (xy 361.319992 -10.660453) (xy 361.26674 -10.664183) (xy 361.213488 -10.660453)
			(xy 361.161277 -10.649336) (xy 361.111125 -10.63105) (xy 361.064011 -10.605951) (xy 361.020857 -10.574529)
			(xy 360.982503 -10.537399) (xy 360.96575 -10.516616) (xy 360.958177 -10.507867) (xy 360.937426 -10.49768)
			(xy 360.925872 -10.497058) (xy 360.845608 -10.497058) (xy 360.834038 -10.497613) (xy 360.813265 -10.507816)
			(xy 360.80573 -10.516616) (xy 360.788977 -10.537399) (xy 360.750623 -10.574529) (xy 360.707469 -10.605951)
			(xy 360.660355 -10.63105) (xy 360.610203 -10.649336) (xy 360.557992 -10.660453) (xy 360.50474 -10.664183)
			(xy 360.451488 -10.660453) (xy 360.399277 -10.649336) (xy 360.349125 -10.63105) (xy 360.302011 -10.605951)
			(xy 360.258857 -10.574529) (xy 360.220503 -10.537399) (xy 360.20375 -10.516616) (xy 360.196177 -10.507867)
			(xy 360.175426 -10.49768) (xy 360.163872 -10.497058) (xy 360.083608 -10.497058) (xy 360.072038 -10.497613)
			(xy 360.051265 -10.507816) (xy 360.04373 -10.516616) (xy 360.025526 -10.539088) (xy 359.983509 -10.578824)
			(xy 359.935976 -10.611763) (xy 359.884018 -10.637154) (xy 359.828822 -10.654412) (xy 359.771655 -10.663145)
			(xy 359.74274 -10.663682) (xy 359.715483 -10.663274) (xy 359.661524 -10.655521) (xy 359.609218 -10.640167)
			(xy 359.55963 -10.617526) (xy 359.513768 -10.588057) (xy 359.472568 -10.55236) (xy 359.436867 -10.511164)
			(xy 359.407394 -10.465306) (xy 359.384747 -10.415719) (xy 359.369388 -10.363415) (xy 359.361629 -10.309457)
			(xy 276.352133 -10.309457) (xy 276.352025 -10.315919) (xy 276.343293 -10.373093) (xy 276.326031 -10.428294)
			(xy 276.300633 -10.480256) (xy 276.267681 -10.527789) (xy 276.227932 -10.569803) (xy 276.205442 -10.58799)
			(xy 276.196679 -10.595551) (xy 276.186499 -10.616311) (xy 276.185884 -10.627868) (xy 276.185884 -10.708132)
			(xy 276.186499 -10.719694) (xy 276.196663 -10.740465) (xy 276.205442 -10.74801) (xy 276.227939 -10.766185)
			(xy 276.267671 -10.808209) (xy 276.300608 -10.855748) (xy 276.325993 -10.907712) (xy 276.343247 -10.962912)
			(xy 276.351974 -11.020083) (xy 276.352508 -11.049) (xy 276.352022 -11.076251) (xy 276.344266 -11.130199)
			(xy 276.328911 -11.182494) (xy 276.306269 -11.232071) (xy 276.276803 -11.277921) (xy 276.241112 -11.319112)
			(xy 276.199921 -11.354803) (xy 276.154071 -11.384269) (xy 276.104494 -11.406911) (xy 276.052199 -11.422266)
			(xy 275.998251 -11.430022) (xy 275.971 -11.430508) (xy 275.942081 -11.430025) (xy 275.884907 -11.421293)
			(xy 275.829706 -11.404031) (xy 275.777744 -11.378633) (xy 275.730211 -11.345681) (xy 275.688197 -11.305932)
			(xy 275.67001 -11.283442) (xy 275.662449 -11.274679) (xy 275.641689 -11.264499) (xy 275.630132 -11.263884)
			(xy 275.549868 -11.263884) (xy 275.538306 -11.264499) (xy 275.517535 -11.274663) (xy 275.50999 -11.283442)
			(xy 275.493237 -11.304225) (xy 275.454883 -11.341355) (xy 275.411729 -11.372777) (xy 275.364615 -11.397876)
			(xy 275.314463 -11.416162) (xy 275.262252 -11.427279) (xy 275.209 -11.431009) (xy 275.155748 -11.427279)
			(xy 275.103537 -11.416162) (xy 275.053385 -11.397876) (xy 275.006271 -11.372777) (xy 274.963117 -11.341355)
			(xy 274.924763 -11.304225) (xy 274.90801 -11.283442) (xy 274.900449 -11.274679) (xy 274.879689 -11.264499)
			(xy 274.868132 -11.263884) (xy 274.787868 -11.263884) (xy 274.776306 -11.264499) (xy 274.755535 -11.274663)
			(xy 274.74799 -11.283442) (xy 274.731237 -11.304225) (xy 274.692883 -11.341355) (xy 274.649729 -11.372777)
			(xy 274.602615 -11.397876) (xy 274.552463 -11.416162) (xy 274.500252 -11.427279) (xy 274.447 -11.431009)
			(xy 274.393748 -11.427279) (xy 274.341537 -11.416162) (xy 274.291385 -11.397876) (xy 274.244271 -11.372777)
			(xy 274.201117 -11.341355) (xy 274.162763 -11.304225) (xy 274.14601 -11.283442) (xy 274.138449 -11.274679)
			(xy 274.117689 -11.264499) (xy 274.106132 -11.263884) (xy 274.025868 -11.263884) (xy 274.014306 -11.264499)
			(xy 273.993535 -11.274663) (xy 273.98599 -11.283442) (xy 273.969237 -11.304225) (xy 273.930883 -11.341355)
			(xy 273.887729 -11.372777) (xy 273.840615 -11.397876) (xy 273.790463 -11.416162) (xy 273.738252 -11.427279)
			(xy 273.685 -11.431009) (xy 273.631748 -11.427279) (xy 273.579537 -11.416162) (xy 273.529385 -11.397876)
			(xy 273.482271 -11.372777) (xy 273.439117 -11.341355) (xy 273.400763 -11.304225) (xy 273.38401 -11.283442)
			(xy 273.376449 -11.274679) (xy 273.355689 -11.264499) (xy 273.344132 -11.263884) (xy 273.263868 -11.263884)
			(xy 273.252306 -11.264499) (xy 273.231535 -11.274663) (xy 273.22399 -11.283442) (xy 273.205815 -11.305939)
			(xy 273.163791 -11.345671) (xy 273.116252 -11.378608) (xy 273.064288 -11.403993) (xy 273.009088 -11.421247)
			(xy 272.951917 -11.429974) (xy 272.923 -11.430508) (xy 272.895749 -11.430022) (xy 272.841801 -11.422266)
			(xy 272.789506 -11.406911) (xy 272.739929 -11.384269) (xy 272.694079 -11.354803) (xy 272.652888 -11.319112)
			(xy 272.617197 -11.277921) (xy 272.587731 -11.232071) (xy 272.565089 -11.182494) (xy 272.549734 -11.130199)
			(xy 272.541978 -11.076251) (xy 272.541492 -11.049) (xy 213.052406 -11.049) (xy 213.052406 -90.34272)
			(xy 225.042728 -90.34272) (xy 225.046801 -90.287061) (xy 225.058936 -90.232588) (xy 225.078872 -90.180462)
			(xy 225.106186 -90.131794) (xy 225.140294 -90.087622) (xy 225.180471 -90.048887) (xy 225.225859 -90.016415)
			(xy 225.275491 -89.990897) (xy 225.328311 -89.972878) (xy 225.38319 -89.962741) (xy 225.438961 -89.960703)
			(xy 225.494435 -89.966806) (xy 225.548428 -89.980922) (xy 225.599791 -90.002749) (xy 225.647429 -90.031822)
			(xy 225.690325 -90.067521) (xy 225.727567 -90.109085) (xy 225.758361 -90.155629) (xy 225.782049 -90.20616)
			(xy 225.798127 -90.259602) (xy 225.806253 -90.314816) (xy 225.806762 -90.34272) (xy 225.806253 -90.370624)
			(xy 225.798127 -90.425838) (xy 225.782049 -90.47928) (xy 225.758361 -90.529811) (xy 225.727567 -90.576355)
			(xy 225.690325 -90.617919) (xy 225.647429 -90.653618) (xy 225.599791 -90.682691) (xy 225.548428 -90.704518)
			(xy 225.494435 -90.718634) (xy 225.438961 -90.724737) (xy 225.38319 -90.722699) (xy 225.328311 -90.712562)
			(xy 225.275491 -90.694543) (xy 225.225859 -90.669025) (xy 225.180471 -90.636553) (xy 225.140294 -90.597818)
			(xy 225.106186 -90.553646) (xy 225.078872 -90.504978) (xy 225.058936 -90.452852) (xy 225.046801 -90.398379)
			(xy 225.042728 -90.34272) (xy 213.052406 -90.34272) (xy 213.052406 -91.9988) (xy 219.099391 -91.9988)
			(xy 219.103394 -91.910938) (xy 219.11537 -91.823804) (xy 219.135221 -91.73812) (xy 219.16278 -91.654596)
			(xy 219.197821 -91.573924) (xy 219.240052 -91.496773) (xy 219.289124 -91.423782) (xy 219.344631 -91.355556)
			(xy 219.406111 -91.29266) (xy 219.473056 -91.235615) (xy 219.544911 -91.184894) (xy 219.621081 -91.140917)
			(xy 219.700934 -91.104049) (xy 219.783809 -91.074596) (xy 219.869019 -91.0528) (xy 219.955858 -91.038844)
			(xy 220.043606 -91.032841) (xy 220.131536 -91.034843) (xy 220.218921 -91.044833) (xy 220.305034 -91.062728)
			(xy 220.389164 -91.088379) (xy 220.470612 -91.121574) (xy 220.548705 -91.162038) (xy 220.622794 -91.209436)
			(xy 220.692266 -91.263375) (xy 220.756545 -91.323408) (xy 220.815099 -91.389037) (xy 220.867443 -91.459719)
			(xy 220.913142 -91.534868) (xy 220.951818 -91.613861) (xy 220.98315 -91.696044) (xy 221.00688 -91.780736)
			(xy 221.014295 -91.821) (xy 224.433128 -91.821) (xy 224.437201 -91.765341) (xy 224.449336 -91.710868)
			(xy 224.469272 -91.658742) (xy 224.496586 -91.610074) (xy 224.530694 -91.565902) (xy 224.570871 -91.527167)
			(xy 224.616259 -91.494695) (xy 224.665891 -91.469177) (xy 224.718711 -91.451158) (xy 224.77359 -91.441021)
			(xy 224.829361 -91.438983) (xy 224.884835 -91.445086) (xy 224.938828 -91.459202) (xy 224.990191 -91.481029)
			(xy 225.037829 -91.510102) (xy 225.080725 -91.545801) (xy 225.117967 -91.587365) (xy 225.148761 -91.633909)
			(xy 225.172449 -91.68444) (xy 225.188527 -91.737882) (xy 225.196653 -91.793096) (xy 225.197162 -91.821)
			(xy 225.196653 -91.848904) (xy 225.188527 -91.904118) (xy 225.172449 -91.95756) (xy 225.153116 -91.9988)
			(xy 229.386645 -91.9988) (xy 229.390648 -91.910938) (xy 229.402624 -91.823804) (xy 229.422475 -91.73812)
			(xy 229.450034 -91.654596) (xy 229.485075 -91.573924) (xy 229.527306 -91.496773) (xy 229.576378 -91.423782)
			(xy 229.631885 -91.355556) (xy 229.693365 -91.29266) (xy 229.76031 -91.235615) (xy 229.832165 -91.184894)
			(xy 229.908335 -91.140917) (xy 229.988188 -91.104049) (xy 230.071063 -91.074596) (xy 230.156273 -91.0528)
			(xy 230.243112 -91.038844) (xy 230.33086 -91.032841) (xy 230.41879 -91.034843) (xy 230.506175 -91.044833)
			(xy 230.592288 -91.062728) (xy 230.676418 -91.088379) (xy 230.757866 -91.121574) (xy 230.835959 -91.162038)
			(xy 230.910048 -91.209436) (xy 230.97952 -91.263375) (xy 231.043799 -91.323408) (xy 231.102353 -91.389037)
			(xy 231.154697 -91.459719) (xy 231.200396 -91.534868) (xy 231.239072 -91.613861) (xy 231.270404 -91.696044)
			(xy 231.294134 -91.780736) (xy 231.310064 -91.867235) (xy 231.318062 -91.954823) (xy 231.318562 -91.9988)
			(xy 231.318062 -92.042777) (xy 231.310064 -92.130365) (xy 231.294134 -92.216864) (xy 231.270404 -92.301556)
			(xy 231.239072 -92.383739) (xy 231.200396 -92.462732) (xy 231.177768 -92.499942) (xy 244.864636 -92.499942)
			(xy 244.864636 -87.499952) (xy 244.865131 -87.399111) (xy 244.873049 -87.197584) (xy 244.888873 -86.996524)
			(xy 244.912578 -86.79624) (xy 244.944128 -86.597041) (xy 244.983474 -86.399234) (xy 245.030556 -86.203125)
			(xy 245.085301 -86.009015) (xy 245.147624 -85.817204) (xy 245.217429 -85.627987) (xy 245.29461 -85.441658)
			(xy 245.379046 -85.258501) (xy 245.470608 -85.078801) (xy 245.569154 -84.902835) (xy 245.674532 -84.730872)
			(xy 245.786581 -84.56318) (xy 245.905127 -84.400016) (xy 246.029987 -84.241631) (xy 246.160969 -84.088271)
			(xy 246.297871 -83.940171) (xy 246.440481 -83.797561) (xy 246.588581 -83.660659) (xy 246.741941 -83.529677)
			(xy 246.900326 -83.404817) (xy 247.06349 -83.286271) (xy 247.231182 -83.174222) (xy 247.403145 -83.068844)
			(xy 247.579111 -82.970298) (xy 247.758811 -82.878736) (xy 247.941968 -82.7943) (xy 248.128297 -82.717119)
			(xy 248.317514 -82.647314) (xy 248.509325 -82.584991) (xy 248.703435 -82.530246) (xy 248.899544 -82.483164)
			(xy 249.097351 -82.443818) (xy 249.29655 -82.412268) (xy 249.496834 -82.388563) (xy 249.697894 -82.372739)
			(xy 249.899421 -82.364821) (xy 250.101103 -82.364821) (xy 250.30263 -82.372739) (xy 250.50369 -82.388563)
			(xy 250.703974 -82.412268) (xy 250.903173 -82.443818) (xy 251.10098 -82.483164) (xy 251.297089 -82.530246)
			(xy 251.491199 -82.584991) (xy 251.68301 -82.647314) (xy 251.872227 -82.717119) (xy 252.058556 -82.7943)
			(xy 252.241713 -82.878736) (xy 252.421413 -82.970298) (xy 252.597379 -83.068844) (xy 252.769342 -83.174222)
			(xy 252.937034 -83.286271) (xy 253.100198 -83.404817) (xy 253.258583 -83.529677) (xy 253.411943 -83.660659)
			(xy 253.560043 -83.797561) (xy 253.702653 -83.940171) (xy 253.839555 -84.088271) (xy 253.970537 -84.241631)
			(xy 254.095397 -84.400016) (xy 254.213943 -84.56318) (xy 254.325992 -84.730872) (xy 254.43137 -84.902835)
			(xy 254.529916 -85.078801) (xy 254.621478 -85.258501) (xy 254.705914 -85.441658) (xy 254.783095 -85.627987)
			(xy 254.8529 -85.817204) (xy 254.915223 -86.009015) (xy 254.969968 -86.203125) (xy 255.01705 -86.399234)
			(xy 255.056396 -86.597041) (xy 255.087946 -86.79624) (xy 255.111651 -86.996524) (xy 255.127475 -87.197584)
			(xy 255.135393 -87.399111) (xy 255.135888 -87.499952) (xy 255.135888 -92.499942) (xy 255.135393 -92.600783)
			(xy 255.127475 -92.80231) (xy 255.111651 -93.00337) (xy 255.087946 -93.203654) (xy 255.056396 -93.402853)
			(xy 255.01705 -93.60066) (xy 254.969968 -93.796769) (xy 254.915223 -93.990879) (xy 254.8529 -94.18269)
			(xy 254.783095 -94.371907) (xy 254.705914 -94.558236) (xy 254.621478 -94.741393) (xy 254.529916 -94.921093)
			(xy 254.43137 -95.097059) (xy 254.325992 -95.269022) (xy 254.213943 -95.436714) (xy 254.095397 -95.599878)
			(xy 253.970537 -95.758263) (xy 253.839555 -95.911623) (xy 253.702653 -96.059723) (xy 253.560043 -96.202333)
			(xy 253.411943 -96.339235) (xy 253.258583 -96.470217) (xy 253.100198 -96.595077) (xy 252.937034 -96.713623)
			(xy 252.769342 -96.825672) (xy 252.597379 -96.93105) (xy 252.421413 -97.029596) (xy 252.241713 -97.121158)
			(xy 252.058556 -97.205594) (xy 251.872227 -97.282775) (xy 251.68301 -97.35258) (xy 251.491199 -97.414903)
			(xy 251.297089 -97.469648) (xy 251.10098 -97.51673) (xy 250.903173 -97.556076) (xy 250.703974 -97.587626)
			(xy 250.50369 -97.611331) (xy 250.30263 -97.627155) (xy 250.101103 -97.635073) (xy 249.899421 -97.635073)
			(xy 249.697894 -97.627155) (xy 249.496834 -97.611331) (xy 249.29655 -97.587626) (xy 249.097351 -97.556076)
			(xy 248.899544 -97.51673) (xy 248.703435 -97.469648) (xy 248.509325 -97.414903) (xy 248.317514 -97.35258)
			(xy 248.128297 -97.282775) (xy 247.941968 -97.205594) (xy 247.758811 -97.121158) (xy 247.579111 -97.029596)
			(xy 247.403145 -96.93105) (xy 247.231182 -96.825672) (xy 247.06349 -96.713623) (xy 246.900326 -96.595077)
			(xy 246.741941 -96.470217) (xy 246.588581 -96.339235) (xy 246.440481 -96.202333) (xy 246.297871 -96.059723)
			(xy 246.160969 -95.911623) (xy 246.029987 -95.758263) (xy 245.905127 -95.599878) (xy 245.786581 -95.436714)
			(xy 245.674532 -95.269022) (xy 245.569154 -95.097059) (xy 245.470608 -94.921093) (xy 245.379046 -94.741393)
			(xy 245.29461 -94.558236) (xy 245.217429 -94.371907) (xy 245.147624 -94.18269) (xy 245.085301 -93.990879)
			(xy 245.030556 -93.796769) (xy 244.983474 -93.60066) (xy 244.944128 -93.402853) (xy 244.912578 -93.203654)
			(xy 244.888873 -93.00337) (xy 244.873049 -92.80231) (xy 244.865131 -92.600783) (xy 244.864636 -92.499942)
			(xy 231.177768 -92.499942) (xy 231.154697 -92.537881) (xy 231.102353 -92.608563) (xy 231.043799 -92.674192)
			(xy 230.97952 -92.734225) (xy 230.910048 -92.788164) (xy 230.835959 -92.835562) (xy 230.757866 -92.876026)
			(xy 230.676418 -92.909221) (xy 230.592288 -92.934872) (xy 230.506175 -92.952767) (xy 230.41879 -92.962757)
			(xy 230.33086 -92.964759) (xy 230.243112 -92.958756) (xy 230.156273 -92.9448) (xy 230.071063 -92.923004)
			(xy 229.988188 -92.893551) (xy 229.908335 -92.856683) (xy 229.832165 -92.812706) (xy 229.76031 -92.761985)
			(xy 229.693365 -92.70494) (xy 229.631885 -92.642044) (xy 229.576378 -92.573818) (xy 229.527306 -92.500827)
			(xy 229.485075 -92.423676) (xy 229.450034 -92.343004) (xy 229.422475 -92.25948) (xy 229.402624 -92.173796)
			(xy 229.390648 -92.086662) (xy 229.386645 -91.9988) (xy 225.153116 -91.9988) (xy 225.148761 -92.008091)
			(xy 225.117967 -92.054635) (xy 225.080725 -92.096199) (xy 225.037829 -92.131898) (xy 224.990191 -92.160971)
			(xy 224.938828 -92.182798) (xy 224.884835 -92.196914) (xy 224.829361 -92.203017) (xy 224.77359 -92.200979)
			(xy 224.718711 -92.190842) (xy 224.665891 -92.172823) (xy 224.616259 -92.147305) (xy 224.570871 -92.114833)
			(xy 224.530694 -92.076098) (xy 224.496586 -92.031926) (xy 224.469272 -91.983258) (xy 224.449336 -91.931132)
			(xy 224.437201 -91.876659) (xy 224.433128 -91.821) (xy 221.014295 -91.821) (xy 221.02281 -91.867235)
			(xy 221.030808 -91.954823) (xy 221.031308 -91.9988) (xy 221.030808 -92.042777) (xy 221.02281 -92.130365)
			(xy 221.00688 -92.216864) (xy 220.98315 -92.301556) (xy 220.951818 -92.383739) (xy 220.913142 -92.462732)
			(xy 220.867443 -92.537881) (xy 220.815099 -92.608563) (xy 220.790543 -92.636086) (xy 222.674432 -92.636086)
			(xy 222.678503 -92.580464) (xy 222.690629 -92.526027) (xy 222.710552 -92.473936) (xy 222.737848 -92.425301)
			(xy 222.771934 -92.381158) (xy 222.812083 -92.342449) (xy 222.857441 -92.309998) (xy 222.907041 -92.284497)
			(xy 222.959825 -92.26649) (xy 223.014668 -92.25636) (xy 223.070402 -92.254323) (xy 223.125839 -92.260423)
			(xy 223.179796 -92.274529) (xy 223.231125 -92.296341) (xy 223.278731 -92.325395) (xy 223.321599 -92.36107)
			(xy 223.358816 -92.402607) (xy 223.389589 -92.44912) (xy 223.413261 -92.499617) (xy 223.429329 -92.553024)
			(xy 223.437449 -92.6082) (xy 223.437958 -92.636086) (xy 223.437449 -92.663972) (xy 223.429329 -92.719148)
			(xy 223.413261 -92.772555) (xy 223.389589 -92.823052) (xy 223.358816 -92.869565) (xy 223.321599 -92.911102)
			(xy 223.278731 -92.946777) (xy 223.231125 -92.975831) (xy 223.179796 -92.997643) (xy 223.125839 -93.011749)
			(xy 223.070402 -93.017849) (xy 223.014668 -93.015812) (xy 222.959825 -93.005682) (xy 222.907041 -92.987675)
			(xy 222.857441 -92.962174) (xy 222.812083 -92.929723) (xy 222.771934 -92.891014) (xy 222.737848 -92.846871)
			(xy 222.710552 -92.798236) (xy 222.690629 -92.746145) (xy 222.678503 -92.691708) (xy 222.674432 -92.636086)
			(xy 220.790543 -92.636086) (xy 220.756545 -92.674192) (xy 220.692266 -92.734225) (xy 220.622794 -92.788164)
			(xy 220.548705 -92.835562) (xy 220.470612 -92.876026) (xy 220.389164 -92.909221) (xy 220.305034 -92.934872)
			(xy 220.218921 -92.952767) (xy 220.131536 -92.962757) (xy 220.043606 -92.964759) (xy 219.955858 -92.958756)
			(xy 219.869019 -92.9448) (xy 219.783809 -92.923004) (xy 219.700934 -92.893551) (xy 219.621081 -92.856683)
			(xy 219.544911 -92.812706) (xy 219.473056 -92.761985) (xy 219.406111 -92.70494) (xy 219.344631 -92.642044)
			(xy 219.289124 -92.573818) (xy 219.240052 -92.500827) (xy 219.197821 -92.423676) (xy 219.16278 -92.343004)
			(xy 219.135221 -92.25948) (xy 219.11537 -92.173796) (xy 219.103394 -92.086662) (xy 219.099391 -91.9988)
			(xy 213.052406 -91.9988) (xy 213.052406 -92.282264) (xy 213.051972 -92.292329) (xy 213.044242 -92.310917)
			(xy 213.03742 -92.318332) (xy 210.843622 -94.51213) (xy 210.836002 -94.530418) (xy 210.836002 -94.5388)
			(xy 219.099391 -94.5388) (xy 219.103394 -94.450938) (xy 219.11537 -94.363804) (xy 219.135221 -94.27812)
			(xy 219.16278 -94.194596) (xy 219.197821 -94.113924) (xy 219.240052 -94.036773) (xy 219.289124 -93.963782)
			(xy 219.344631 -93.895556) (xy 219.406111 -93.83266) (xy 219.473056 -93.775615) (xy 219.544911 -93.724894)
			(xy 219.621081 -93.680917) (xy 219.700934 -93.644049) (xy 219.783809 -93.614596) (xy 219.869019 -93.5928)
			(xy 219.955858 -93.578844) (xy 220.043606 -93.572841) (xy 220.131536 -93.574843) (xy 220.218921 -93.584833)
			(xy 220.305034 -93.602728) (xy 220.389164 -93.628379) (xy 220.470612 -93.661574) (xy 220.548705 -93.702038)
			(xy 220.622794 -93.749436) (xy 220.692266 -93.803375) (xy 220.745401 -93.853) (xy 223.264728 -93.853)
			(xy 223.268801 -93.797341) (xy 223.280936 -93.742868) (xy 223.300872 -93.690742) (xy 223.328186 -93.642074)
			(xy 223.362294 -93.597902) (xy 223.402471 -93.559167) (xy 223.447859 -93.526695) (xy 223.497491 -93.501177)
			(xy 223.550311 -93.483158) (xy 223.60519 -93.473021) (xy 223.660961 -93.470983) (xy 223.716435 -93.477086)
			(xy 223.770428 -93.491202) (xy 223.821791 -93.513029) (xy 223.869429 -93.542102) (xy 223.912325 -93.577801)
			(xy 223.949567 -93.619365) (xy 223.980361 -93.665909) (xy 224.004049 -93.71644) (xy 224.020127 -93.769882)
			(xy 224.028253 -93.825096) (xy 224.028762 -93.853) (xy 224.028253 -93.880904) (xy 224.020127 -93.936118)
			(xy 224.004049 -93.98956) (xy 223.980361 -94.040091) (xy 223.949567 -94.086635) (xy 223.912325 -94.128199)
			(xy 223.869429 -94.163898) (xy 223.821791 -94.192971) (xy 223.770428 -94.214798) (xy 223.716435 -94.228914)
			(xy 223.660961 -94.235017) (xy 223.60519 -94.232979) (xy 223.550311 -94.222842) (xy 223.497491 -94.204823)
			(xy 223.447859 -94.179305) (xy 223.402471 -94.146833) (xy 223.362294 -94.108098) (xy 223.328186 -94.063926)
			(xy 223.300872 -94.015258) (xy 223.280936 -93.963132) (xy 223.268801 -93.908659) (xy 223.264728 -93.853)
			(xy 220.745401 -93.853) (xy 220.756545 -93.863408) (xy 220.815099 -93.929037) (xy 220.867443 -93.999719)
			(xy 220.913142 -94.074868) (xy 220.951818 -94.153861) (xy 220.98315 -94.236044) (xy 221.00688 -94.320736)
			(xy 221.02281 -94.407235) (xy 221.030808 -94.494823) (xy 221.031308 -94.5388) (xy 229.386645 -94.5388)
			(xy 229.390648 -94.450938) (xy 229.402624 -94.363804) (xy 229.422475 -94.27812) (xy 229.450034 -94.194596)
			(xy 229.485075 -94.113924) (xy 229.527306 -94.036773) (xy 229.576378 -93.963782) (xy 229.631885 -93.895556)
			(xy 229.693365 -93.83266) (xy 229.76031 -93.775615) (xy 229.832165 -93.724894) (xy 229.908335 -93.680917)
			(xy 229.988188 -93.644049) (xy 230.071063 -93.614596) (xy 230.156273 -93.5928) (xy 230.243112 -93.578844)
			(xy 230.33086 -93.572841) (xy 230.41879 -93.574843) (xy 230.506175 -93.584833) (xy 230.592288 -93.602728)
			(xy 230.676418 -93.628379) (xy 230.757866 -93.661574) (xy 230.835959 -93.702038) (xy 230.910048 -93.749436)
			(xy 230.97952 -93.803375) (xy 231.043799 -93.863408) (xy 231.102353 -93.929037) (xy 231.154697 -93.999719)
			(xy 231.200396 -94.074868) (xy 231.239072 -94.153861) (xy 231.270404 -94.236044) (xy 231.294134 -94.320736)
			(xy 231.310064 -94.407235) (xy 231.318062 -94.494823) (xy 231.318562 -94.5388) (xy 231.318062 -94.582777)
			(xy 231.310064 -94.670365) (xy 231.294134 -94.756864) (xy 231.270404 -94.841556) (xy 231.239072 -94.923739)
			(xy 231.200396 -95.002732) (xy 231.154697 -95.077881) (xy 231.102353 -95.148563) (xy 231.043799 -95.214192)
			(xy 230.97952 -95.274225) (xy 230.910048 -95.328164) (xy 230.835959 -95.375562) (xy 230.757866 -95.416026)
			(xy 230.676418 -95.449221) (xy 230.592288 -95.474872) (xy 230.506175 -95.492767) (xy 230.41879 -95.502757)
			(xy 230.33086 -95.504759) (xy 230.243112 -95.498756) (xy 230.156273 -95.4848) (xy 230.071063 -95.463004)
			(xy 229.988188 -95.433551) (xy 229.908335 -95.396683) (xy 229.832165 -95.352706) (xy 229.76031 -95.301985)
			(xy 229.693365 -95.24494) (xy 229.631885 -95.182044) (xy 229.576378 -95.113818) (xy 229.527306 -95.040827)
			(xy 229.485075 -94.963676) (xy 229.450034 -94.883004) (xy 229.422475 -94.79948) (xy 229.402624 -94.713796)
			(xy 229.390648 -94.626662) (xy 229.386645 -94.5388) (xy 221.031308 -94.5388) (xy 221.030808 -94.582777)
			(xy 221.02281 -94.670365) (xy 221.00688 -94.756864) (xy 220.98315 -94.841556) (xy 220.951818 -94.923739)
			(xy 220.913142 -95.002732) (xy 220.90179 -95.0214) (xy 222.674432 -95.0214) (xy 222.678503 -94.965778)
			(xy 222.690629 -94.911341) (xy 222.710552 -94.85925) (xy 222.737848 -94.810615) (xy 222.771934 -94.766472)
			(xy 222.812083 -94.727763) (xy 222.857441 -94.695312) (xy 222.907041 -94.669811) (xy 222.959825 -94.651804)
			(xy 223.014668 -94.641674) (xy 223.070402 -94.639637) (xy 223.125839 -94.645737) (xy 223.179796 -94.659843)
			(xy 223.231125 -94.681655) (xy 223.278731 -94.710709) (xy 223.321599 -94.746384) (xy 223.358816 -94.787921)
			(xy 223.389589 -94.834434) (xy 223.413261 -94.884931) (xy 223.429329 -94.938338) (xy 223.437449 -94.993514)
			(xy 223.437958 -95.0214) (xy 223.437449 -95.049286) (xy 223.429329 -95.104462) (xy 223.413261 -95.157869)
			(xy 223.389589 -95.208366) (xy 223.358816 -95.254879) (xy 223.321599 -95.296416) (xy 223.278731 -95.332091)
			(xy 223.231125 -95.361145) (xy 223.179796 -95.382957) (xy 223.125839 -95.397063) (xy 223.070402 -95.403163)
			(xy 223.014668 -95.401126) (xy 222.959825 -95.390996) (xy 222.907041 -95.372989) (xy 222.857441 -95.347488)
			(xy 222.812083 -95.315037) (xy 222.771934 -95.276328) (xy 222.737848 -95.232185) (xy 222.710552 -95.18355)
			(xy 222.690629 -95.131459) (xy 222.678503 -95.077022) (xy 222.674432 -95.0214) (xy 220.90179 -95.0214)
			(xy 220.867443 -95.077881) (xy 220.815099 -95.148563) (xy 220.756545 -95.214192) (xy 220.692266 -95.274225)
			(xy 220.622794 -95.328164) (xy 220.548705 -95.375562) (xy 220.470612 -95.416026) (xy 220.389164 -95.449221)
			(xy 220.305034 -95.474872) (xy 220.218921 -95.492767) (xy 220.131536 -95.502757) (xy 220.043606 -95.504759)
			(xy 219.955858 -95.498756) (xy 219.869019 -95.4848) (xy 219.783809 -95.463004) (xy 219.700934 -95.433551)
			(xy 219.621081 -95.396683) (xy 219.544911 -95.352706) (xy 219.473056 -95.301985) (xy 219.406111 -95.24494)
			(xy 219.344631 -95.182044) (xy 219.289124 -95.113818) (xy 219.240052 -95.040827) (xy 219.197821 -94.963676)
			(xy 219.16278 -94.883004) (xy 219.135221 -94.79948) (xy 219.11537 -94.713796) (xy 219.103394 -94.626662)
			(xy 219.099391 -94.5388) (xy 210.836002 -94.5388) (xy 210.836002 -94.540578) (xy 210.835423 -94.586673)
			(xy 210.827242 -94.678501) (xy 210.811098 -94.769268) (xy 210.787112 -94.858285) (xy 210.755467 -94.944876)
			(xy 210.716404 -95.028382) (xy 210.670219 -95.108171) (xy 210.617262 -95.183636) (xy 210.557936 -95.254204)
			(xy 210.492692 -95.319338) (xy 210.422025 -95.378545) (xy 210.346471 -95.431375) (xy 210.266605 -95.477426)
			(xy 210.183033 -95.516349) (xy 210.096389 -95.547848) (xy 210.007332 -95.571684) (xy 209.916538 -95.587676)
			(xy 209.824696 -95.595702) (xy 209.7786 -95.596202) (xy 209.778346 -95.596202) (xy 209.730119 -95.595652)
			(xy 209.634067 -95.586841) (xy 209.539217 -95.569324) (xy 209.446354 -95.543248) (xy 209.35625 -95.508827)
			(xy 209.269652 -95.466349) (xy 209.187281 -95.416166) (xy 209.109818 -95.358693) (xy 209.073496 -95.326962)
			(xy 209.070194 -95.323914) (xy 209.058764 -95.316802) (xy 209.050636 -95.312738) (xy 209.03819 -95.307912)
			(xy 209.033737 -95.306248) (xy 209.024401 -95.304465) (xy 209.019648 -95.304356) (xy 194.34302 -95.304356)
			(xy 194.336791 -95.304571) (xy 194.324719 -95.307663) (xy 194.319144 -95.310452) (xy 194.299078 -95.32112)
			(xy 194.293621 -95.324223) (xy 194.28425 -95.332569) (xy 194.280536 -95.33763) (xy 194.280536 -95.337884)
			(xy 194.224229 -95.421905) (xy 194.105889 -95.58596) (xy 193.98118 -95.745228) (xy 193.850297 -95.899462)
			(xy 193.713442 -96.048423) (xy 193.570828 -96.191879) (xy 193.422676 -96.329609) (xy 193.269215 -96.461398)
			(xy 193.110684 -96.587043) (xy 192.947329 -96.706347) (xy 192.779403 -96.819127) (xy 192.607166 -96.925207)
			(xy 192.430885 -97.024423) (xy 192.324693 -97.0788) (xy 208.812391 -97.0788) (xy 208.816394 -96.990938)
			(xy 208.82837 -96.903804) (xy 208.848221 -96.81812) (xy 208.87578 -96.734596) (xy 208.910821 -96.653924)
			(xy 208.953052 -96.576773) (xy 209.002124 -96.503782) (xy 209.057631 -96.435556) (xy 209.119111 -96.37266)
			(xy 209.186056 -96.315615) (xy 209.257911 -96.264894) (xy 209.334081 -96.220917) (xy 209.413934 -96.184049)
			(xy 209.496809 -96.154596) (xy 209.582019 -96.1328) (xy 209.668858 -96.118844) (xy 209.756606 -96.112841)
			(xy 209.844536 -96.114843) (xy 209.931921 -96.124833) (xy 210.018034 -96.142728) (xy 210.102164 -96.168379)
			(xy 210.183612 -96.201574) (xy 210.261705 -96.242038) (xy 210.335794 -96.289436) (xy 210.405266 -96.343375)
			(xy 210.469545 -96.403408) (xy 210.528099 -96.469037) (xy 210.580443 -96.539719) (xy 210.626142 -96.614868)
			(xy 210.664818 -96.693861) (xy 210.69615 -96.776044) (xy 210.71988 -96.860736) (xy 210.73581 -96.947235)
			(xy 210.743808 -97.034823) (xy 210.744308 -97.0788) (xy 219.099391 -97.0788) (xy 219.103394 -96.990938)
			(xy 219.11537 -96.903804) (xy 219.135221 -96.81812) (xy 219.16278 -96.734596) (xy 219.197821 -96.653924)
			(xy 219.240052 -96.576773) (xy 219.289124 -96.503782) (xy 219.344631 -96.435556) (xy 219.406111 -96.37266)
			(xy 219.473056 -96.315615) (xy 219.544911 -96.264894) (xy 219.621081 -96.220917) (xy 219.700934 -96.184049)
			(xy 219.783809 -96.154596) (xy 219.869019 -96.1328) (xy 219.955858 -96.118844) (xy 220.043606 -96.112841)
			(xy 220.131536 -96.114843) (xy 220.218921 -96.124833) (xy 220.305034 -96.142728) (xy 220.389164 -96.168379)
			(xy 220.470612 -96.201574) (xy 220.548705 -96.242038) (xy 220.622794 -96.289436) (xy 220.692266 -96.343375)
			(xy 220.756545 -96.403408) (xy 220.815099 -96.469037) (xy 220.867443 -96.539719) (xy 220.913142 -96.614868)
			(xy 220.951818 -96.693861) (xy 220.982371 -96.774) (xy 224.475802 -96.774) (xy 224.476288 -96.746749)
			(xy 224.484044 -96.692801) (xy 224.499399 -96.640506) (xy 224.522041 -96.590929) (xy 224.551507 -96.545079)
			(xy 224.587198 -96.503888) (xy 224.628389 -96.468197) (xy 224.674239 -96.438731) (xy 224.723816 -96.416089)
			(xy 224.776111 -96.400734) (xy 224.830059 -96.392978) (xy 224.884561 -96.392978) (xy 224.938509 -96.400734)
			(xy 224.990804 -96.416089) (xy 225.040381 -96.438731) (xy 225.086231 -96.468197) (xy 225.127422 -96.503888)
			(xy 225.163113 -96.545079) (xy 225.192579 -96.590929) (xy 225.215221 -96.640506) (xy 225.230576 -96.692801)
			(xy 225.238332 -96.746749) (xy 225.238818 -96.774) (xy 225.238269 -96.802524) (xy 225.229761 -96.858935)
			(xy 225.21295 -96.913451) (xy 225.188211 -96.964857) (xy 225.156094 -97.012007) (xy 225.117316 -97.05385)
			(xy 225.08608 -97.0788) (xy 229.386892 -97.0788) (xy 229.387317 -97.035593) (xy 229.395047 -96.949527)
			(xy 229.410434 -96.864494) (xy 229.433357 -96.781177) (xy 229.463632 -96.700241) (xy 229.501017 -96.622333)
			(xy 229.545213 -96.548077) (xy 229.595867 -96.478067) (xy 229.652572 -96.412861) (xy 229.714877 -96.352983)
			(xy 229.782282 -96.298911) (xy 229.854248 -96.251077) (xy 229.9302 -96.209863) (xy 230.009531 -96.175601)
			(xy 230.091605 -96.148563) (xy 230.175767 -96.128965) (xy 230.218488 -96.12249) (xy 230.251842 -96.118094)
			(xy 230.318959 -96.113392) (xy 230.3526 -96.113092) (xy 230.396365 -96.113583) (xy 230.483537 -96.121504)
			(xy 230.569634 -96.137282) (xy 230.653949 -96.160787) (xy 230.735792 -96.191826) (xy 230.81449 -96.230144)
			(xy 230.889397 -96.275427) (xy 230.959899 -96.327303) (xy 231.025416 -96.385346) (xy 231.085412 -96.449081)
			(xy 231.139394 -96.517984) (xy 231.186919 -96.591489) (xy 231.227596 -96.668993) (xy 231.261093 -96.749861)
			(xy 231.287133 -96.833429) (xy 231.305504 -96.91901) (xy 231.316055 -97.005902) (xy 231.318699 -97.093393)
			(xy 231.313414 -97.180764) (xy 231.300244 -97.267298) (xy 231.279296 -97.352285) (xy 231.250743 -97.435028)
			(xy 231.21482 -97.514847) (xy 231.17182 -97.591088) (xy 231.122097 -97.663124) (xy 231.066058 -97.730365)
			(xy 231.004165 -97.792258) (xy 230.936924 -97.848297) (xy 230.864888 -97.89802) (xy 230.788647 -97.94102)
			(xy 230.785581 -97.9424) (xy 258.012182 -97.9424) (xy 258.016253 -97.886778) (xy 258.028379 -97.832341)
			(xy 258.048302 -97.78025) (xy 258.075598 -97.731615) (xy 258.109684 -97.687472) (xy 258.149833 -97.648763)
			(xy 258.195191 -97.616312) (xy 258.244791 -97.590811) (xy 258.297575 -97.572804) (xy 258.352418 -97.562674)
			(xy 258.408152 -97.560637) (xy 258.463589 -97.566737) (xy 258.517546 -97.580843) (xy 258.568875 -97.602655)
			(xy 258.616481 -97.631709) (xy 258.659349 -97.667384) (xy 258.696566 -97.708921) (xy 258.727339 -97.755434)
			(xy 258.751011 -97.805931) (xy 258.767079 -97.859338) (xy 258.775199 -97.914514) (xy 258.775708 -97.9424)
			(xy 258.775199 -97.970286) (xy 258.767079 -98.025462) (xy 258.751011 -98.078869) (xy 258.727339 -98.129366)
			(xy 258.696566 -98.175879) (xy 258.659349 -98.217416) (xy 258.616481 -98.253091) (xy 258.568875 -98.282145)
			(xy 258.517546 -98.303957) (xy 258.463589 -98.318063) (xy 258.408152 -98.324163) (xy 258.352418 -98.322126)
			(xy 258.297575 -98.311996) (xy 258.244791 -98.293989) (xy 258.195191 -98.268488) (xy 258.149833 -98.236037)
			(xy 258.109684 -98.197328) (xy 258.075598 -98.153185) (xy 258.048302 -98.10455) (xy 258.028379 -98.052459)
			(xy 258.016253 -97.998022) (xy 258.012182 -97.9424) (xy 230.785581 -97.9424) (xy 230.708828 -97.976943)
			(xy 230.626085 -98.005496) (xy 230.541098 -98.026444) (xy 230.454564 -98.039614) (xy 230.367193 -98.044899)
			(xy 230.279702 -98.042255) (xy 230.19281 -98.031704) (xy 230.107229 -98.013333) (xy 230.023661 -97.987293)
			(xy 229.942793 -97.953796) (xy 229.865289 -97.913119) (xy 229.791784 -97.865594) (xy 229.722881 -97.811612)
			(xy 229.659146 -97.751616) (xy 229.601103 -97.686099) (xy 229.549227 -97.615597) (xy 229.503944 -97.54069)
			(xy 229.465626 -97.461992) (xy 229.434587 -97.380149) (xy 229.411082 -97.295834) (xy 229.395304 -97.209737)
			(xy 229.387383 -97.122565) (xy 229.386892 -97.0788) (xy 225.08608 -97.0788) (xy 225.072741 -97.089455)
			(xy 225.048318 -97.1042) (xy 225.023314 -97.118084) (xy 224.970093 -97.139023) (xy 224.914341 -97.151778)
			(xy 224.85731 -97.156061) (xy 224.800279 -97.151778) (xy 224.744527 -97.139023) (xy 224.691306 -97.118084)
			(xy 224.666302 -97.1042) (xy 224.641879 -97.089451) (xy 224.597292 -97.053857) (xy 224.558504 -97.012019)
			(xy 224.526381 -96.96487) (xy 224.50164 -96.913462) (xy 224.484833 -96.858941) (xy 224.476334 -96.802526)
			(xy 224.475802 -96.774) (xy 220.982371 -96.774) (xy 220.98315 -96.776044) (xy 221.00688 -96.860736)
			(xy 221.02281 -96.947235) (xy 221.030808 -97.034823) (xy 221.031308 -97.0788) (xy 221.030808 -97.122777)
			(xy 221.02281 -97.210365) (xy 221.00688 -97.296864) (xy 220.98315 -97.381556) (xy 220.951818 -97.463739)
			(xy 220.913142 -97.542732) (xy 220.867443 -97.617881) (xy 220.815099 -97.688563) (xy 220.756545 -97.754192)
			(xy 220.692266 -97.814225) (xy 220.622794 -97.868164) (xy 220.548705 -97.915562) (xy 220.470612 -97.956026)
			(xy 220.389164 -97.989221) (xy 220.305034 -98.014872) (xy 220.218921 -98.032767) (xy 220.131536 -98.042757)
			(xy 220.043606 -98.044759) (xy 219.955858 -98.038756) (xy 219.869019 -98.0248) (xy 219.783809 -98.003004)
			(xy 219.700934 -97.973551) (xy 219.621081 -97.936683) (xy 219.544911 -97.892706) (xy 219.473056 -97.841985)
			(xy 219.406111 -97.78494) (xy 219.344631 -97.722044) (xy 219.289124 -97.653818) (xy 219.240052 -97.580827)
			(xy 219.197821 -97.503676) (xy 219.16278 -97.423004) (xy 219.135221 -97.33948) (xy 219.11537 -97.253796)
			(xy 219.103394 -97.166662) (xy 219.099391 -97.0788) (xy 210.744308 -97.0788) (xy 210.743808 -97.122777)
			(xy 210.73581 -97.210365) (xy 210.71988 -97.296864) (xy 210.69615 -97.381556) (xy 210.664818 -97.463739)
			(xy 210.626142 -97.542732) (xy 210.580443 -97.617881) (xy 210.528099 -97.688563) (xy 210.469545 -97.754192)
			(xy 210.405266 -97.814225) (xy 210.335794 -97.868164) (xy 210.261705 -97.915562) (xy 210.183612 -97.956026)
			(xy 210.102164 -97.989221) (xy 210.018034 -98.014872) (xy 209.931921 -98.032767) (xy 209.844536 -98.042757)
			(xy 209.756606 -98.044759) (xy 209.668858 -98.038756) (xy 209.582019 -98.0248) (xy 209.496809 -98.003004)
			(xy 209.413934 -97.973551) (xy 209.334081 -97.936683) (xy 209.257911 -97.892706) (xy 209.186056 -97.841985)
			(xy 209.119111 -97.78494) (xy 209.057631 -97.722044) (xy 209.002124 -97.653818) (xy 208.953052 -97.580827)
			(xy 208.910821 -97.503676) (xy 208.87578 -97.423004) (xy 208.848221 -97.33948) (xy 208.82837 -97.253796)
			(xy 208.816394 -97.166662) (xy 208.812391 -97.0788) (xy 192.324693 -97.0788) (xy 192.250835 -97.11662)
			(xy 192.067294 -97.201657) (xy 191.880546 -97.2794) (xy 191.690883 -97.34973) (xy 191.498597 -97.412537)
			(xy 191.303987 -97.467724) (xy 191.107355 -97.515205) (xy 190.909006 -97.554907) (xy 190.709248 -97.586767)
			(xy 190.50839 -97.610738) (xy 190.306743 -97.62678) (xy 190.104622 -97.634871) (xy 189.902338 -97.634996)
			(xy 189.700207 -97.627156) (xy 189.498541 -97.611363) (xy 189.297653 -97.587641) (xy 189.097856 -97.556028)
			(xy 188.899458 -97.516572) (xy 188.702767 -97.469335) (xy 188.508089 -97.414389) (xy 188.315726 -97.35182)
			(xy 188.125975 -97.281725) (xy 187.939132 -97.204213) (xy 187.755485 -97.119404) (xy 187.575321 -97.02743)
			(xy 187.398918 -96.928432) (xy 187.226549 -96.822566) (xy 187.058483 -96.709994) (xy 186.89498 -96.590892)
			(xy 186.736294 -96.465444) (xy 186.58267 -96.333845) (xy 186.434347 -96.196299) (xy 186.291556 -96.053019)
			(xy 186.154516 -95.904228) (xy 186.023442 -95.750156) (xy 185.898537 -95.591042) (xy 185.779993 -95.427134)
			(xy 185.72353 -95.343218) (xy 185.719974 -95.337884) (xy 185.706512 -95.325692) (xy 185.701686 -95.321374)
			(xy 185.681366 -95.310452) (xy 185.675739 -95.307621) (xy 185.663532 -95.304524) (xy 185.657236 -95.304356)
			(xy 182.774082 -95.304356) (xy 182.764014 -95.303928) (xy 182.745419 -95.296204) (xy 182.738014 -95.28937)
			(xy 182.132986 -94.684342) (xy 182.126139 -94.676944) (xy 182.118413 -94.658345) (xy 182.118 -94.648274)
			(xy 182.118 -85.492082) (xy 182.118427 -85.482013) (xy 182.126146 -85.463414) (xy 182.132986 -85.456014)
			(xy 187.056014 -80.532986) (xy 187.062868 -80.525591) (xy 187.07061 -80.506992) (xy 187.071 -80.496918)
			(xy 187.071 -77.872082) (xy 187.070573 -77.862013) (xy 187.062854 -77.843414) (xy 187.056014 -77.836014)
			(xy 184.926986 -75.706986) (xy 184.919874 -75.69962) (xy 184.901078 -75.692) (xy 184.171082 -75.692)
			(xy 184.161013 -75.692427) (xy 184.142414 -75.700146) (xy 184.135014 -75.706986) (xy 184.037986 -75.804014)
			(xy 184.03062 -75.811126) (xy 184.023 -75.829922) (xy 184.023 -76.305918) (xy 184.022573 -76.315987)
			(xy 184.014854 -76.334586) (xy 184.008014 -76.341986) (xy 183.783986 -76.566014) (xy 183.776591 -76.572868)
			(xy 183.757992 -76.58061) (xy 183.747918 -76.581) (xy 174.413164 -76.581) (xy 174.403097 -76.58057)
			(xy 174.384502 -76.572847) (xy 174.377096 -76.566014) (xy 174.02302 -76.211938) (xy 174.020442 -76.209432)
			(xy 174.014704 -76.2051) (xy 174.01159 -76.203302) (xy 174.006002 -76.200254) (xy 173.999144 -76.198476)
			(xy 173.99889 -76.198476) (xy 173.992202 -76.196578) (xy 173.980091 -76.189762) (xy 173.975014 -76.185014)
			(xy 172.252386 -74.462386) (xy 172.245532 -74.454991) (xy 172.23779 -74.436392) (xy 172.2374 -74.426318)
			(xy 172.2374 -72.076564) (xy 172.22978 -72.057768) (xy 172.222414 -72.050656) (xy 171.929298 -71.75754)
			(xy 171.922186 -71.750174) (xy 171.90339 -71.742554) (xy 171.88053 -71.742554) (xy 171.878244 -71.742808)
			(xy 171.877482 -71.742808) (xy 171.85214 -71.742345) (xy 171.801914 -71.735538) (xy 171.753032 -71.722137)
			(xy 171.706356 -71.702381) (xy 171.662707 -71.676616) (xy 171.642532 -71.661274) (xy 171.642024 -71.66102)
			(xy 171.638976 -71.658734) (xy 171.633388 -71.655432) (xy 171.627624 -71.652372) (xy 171.615018 -71.649019)
			(xy 171.608496 -71.648828) (xy 171.38523 -71.648828) (xy 171.37842 -71.649043) (xy 171.365286 -71.652646)
			(xy 171.359322 -71.65594) (xy 171.354496 -71.658734) (xy 171.351448 -71.66102) (xy 171.35094 -71.661274)
			(xy 171.330737 -71.676621) (xy 171.287043 -71.702407) (xy 171.240316 -71.722174) (xy 171.191382 -71.735573)
			(xy 171.141103 -71.742368) (xy 171.115736 -71.742808) (xy 171.090368 -71.742361) (xy 171.040088 -71.735573)
			(xy 170.991152 -71.722179) (xy 170.944424 -71.702415) (xy 170.900728 -71.67663) (xy 170.880532 -71.661274)
			(xy 170.880024 -71.66102) (xy 170.876976 -71.658734) (xy 170.871388 -71.655432) (xy 170.865624 -71.652372)
			(xy 170.853018 -71.649019) (xy 170.846496 -71.648828) (xy 168.056052 -71.648828) (xy 168.037256 -71.656448)
			(xy 168.030144 -71.663814) (xy 167.7416 -71.952358) (xy 167.735504 -71.981822) (xy 167.741092 -71.996046)
			(xy 167.749523 -72.018406) (xy 167.761389 -72.064696) (xy 167.767381 -72.112107) (xy 167.767762 -72.136)
			(xy 167.767276 -72.163269) (xy 167.759514 -72.217253) (xy 167.744149 -72.269583) (xy 167.721492 -72.319193)
			(xy 167.692006 -72.365074) (xy 167.656291 -72.406291) (xy 167.615074 -72.442006) (xy 167.569193 -72.471492)
			(xy 167.519583 -72.494149) (xy 167.467253 -72.509514) (xy 167.413269 -72.517276) (xy 167.386 -72.517762)
			(xy 167.362107 -72.517373) (xy 167.314699 -72.511375) (xy 167.26841 -72.499511) (xy 167.246046 -72.491092)
			(xy 167.231822 -72.485504) (xy 167.202358 -72.4916) (xy 166.765986 -72.927972) (xy 166.75862 -72.935084)
			(xy 166.751 -72.95388) (xy 166.751 -73.279) (xy 169.844718 -73.279) (xy 169.848789 -73.223378) (xy 169.860915 -73.168941)
			(xy 169.880838 -73.11685) (xy 169.908134 -73.068215) (xy 169.94222 -73.024072) (xy 169.982369 -72.985363)
			(xy 170.027727 -72.952912) (xy 170.077327 -72.927411) (xy 170.130111 -72.909404) (xy 170.184954 -72.899274)
			(xy 170.240688 -72.897237) (xy 170.296125 -72.903337) (xy 170.350082 -72.917443) (xy 170.401411 -72.939255)
			(xy 170.449017 -72.968309) (xy 170.491885 -73.003984) (xy 170.529102 -73.045521) (xy 170.559875 -73.092034)
			(xy 170.583547 -73.142531) (xy 170.599615 -73.195938) (xy 170.607735 -73.251114) (xy 170.608244 -73.279)
			(xy 170.607735 -73.306886) (xy 170.599615 -73.362062) (xy 170.583547 -73.415469) (xy 170.559875 -73.465966)
			(xy 170.529102 -73.512479) (xy 170.491885 -73.554016) (xy 170.449017 -73.589691) (xy 170.401411 -73.618745)
			(xy 170.350082 -73.640557) (xy 170.296125 -73.654663) (xy 170.240688 -73.660763) (xy 170.184954 -73.658726)
			(xy 170.130111 -73.648596) (xy 170.077327 -73.630589) (xy 170.027727 -73.605088) (xy 169.982369 -73.572637)
			(xy 169.94222 -73.533928) (xy 169.908134 -73.489785) (xy 169.880838 -73.44115) (xy 169.860915 -73.389059)
			(xy 169.848789 -73.334622) (xy 169.844718 -73.279) (xy 166.751 -73.279) (xy 166.751 -77.343) (xy 167.791128 -77.343)
			(xy 167.795201 -77.287341) (xy 167.807336 -77.232868) (xy 167.827272 -77.180742) (xy 167.854586 -77.132074)
			(xy 167.888694 -77.087902) (xy 167.928871 -77.049167) (xy 167.974259 -77.016695) (xy 168.023891 -76.991177)
			(xy 168.076711 -76.973158) (xy 168.13159 -76.963021) (xy 168.187361 -76.960983) (xy 168.242835 -76.967086)
			(xy 168.296828 -76.981202) (xy 168.348191 -77.003029) (xy 168.395829 -77.032102) (xy 168.438725 -77.067801)
			(xy 168.475967 -77.109365) (xy 168.506761 -77.155909) (xy 168.530449 -77.20644) (xy 168.546527 -77.259882)
			(xy 168.554653 -77.315096) (xy 168.555162 -77.343) (xy 168.554653 -77.370904) (xy 168.546527 -77.426118)
			(xy 168.530449 -77.47956) (xy 168.506761 -77.530091) (xy 168.475967 -77.576635) (xy 168.438725 -77.618199)
			(xy 168.395829 -77.653898) (xy 168.348191 -77.682971) (xy 168.296828 -77.704798) (xy 168.242835 -77.718914)
			(xy 168.187361 -77.725017) (xy 168.13159 -77.722979) (xy 168.076711 -77.712842) (xy 168.023891 -77.694823)
			(xy 167.974259 -77.669305) (xy 167.928871 -77.636833) (xy 167.888694 -77.598098) (xy 167.854586 -77.553926)
			(xy 167.827272 -77.505258) (xy 167.807336 -77.453132) (xy 167.795201 -77.398659) (xy 167.791128 -77.343)
			(xy 166.751 -77.343) (xy 166.751 -78.486) (xy 175.324514 -78.486) (xy 175.328587 -78.430341) (xy 175.340722 -78.375868)
			(xy 175.360658 -78.323742) (xy 175.387972 -78.275074) (xy 175.42208 -78.230902) (xy 175.462257 -78.192167)
			(xy 175.507645 -78.159695) (xy 175.557277 -78.134177) (xy 175.610097 -78.116158) (xy 175.664976 -78.106021)
			(xy 175.720747 -78.103983) (xy 175.776221 -78.110086) (xy 175.830214 -78.124202) (xy 175.881577 -78.146029)
			(xy 175.929215 -78.175102) (xy 175.972111 -78.210801) (xy 176.009353 -78.252365) (xy 176.040147 -78.298909)
			(xy 176.063835 -78.34944) (xy 176.079913 -78.402882) (xy 176.088039 -78.458096) (xy 176.088548 -78.486)
			(xy 176.088039 -78.513904) (xy 176.079913 -78.569118) (xy 176.063835 -78.62256) (xy 176.040147 -78.673091)
			(xy 176.009353 -78.719635) (xy 175.972111 -78.761199) (xy 175.929215 -78.796898) (xy 175.881577 -78.825971)
			(xy 175.830214 -78.847798) (xy 175.776221 -78.861914) (xy 175.720747 -78.868017) (xy 175.664976 -78.865979)
			(xy 175.610097 -78.855842) (xy 175.557277 -78.837823) (xy 175.507645 -78.812305) (xy 175.462257 -78.779833)
			(xy 175.42208 -78.741098) (xy 175.387972 -78.696926) (xy 175.360658 -78.648258) (xy 175.340722 -78.596132)
			(xy 175.328587 -78.541659) (xy 175.324514 -78.486) (xy 166.751 -78.486) (xy 166.751 -79.121) (xy 168.146728 -79.121)
			(xy 168.150801 -79.065341) (xy 168.162936 -79.010868) (xy 168.182872 -78.958742) (xy 168.210186 -78.910074)
			(xy 168.244294 -78.865902) (xy 168.284471 -78.827167) (xy 168.329859 -78.794695) (xy 168.379491 -78.769177)
			(xy 168.432311 -78.751158) (xy 168.48719 -78.741021) (xy 168.542961 -78.738983) (xy 168.598435 -78.745086)
			(xy 168.652428 -78.759202) (xy 168.703791 -78.781029) (xy 168.751429 -78.810102) (xy 168.794325 -78.845801)
			(xy 168.831567 -78.887365) (xy 168.862361 -78.933909) (xy 168.886049 -78.98444) (xy 168.902127 -79.037882)
			(xy 168.910253 -79.093096) (xy 168.910762 -79.121) (xy 169.289728 -79.121) (xy 169.293801 -79.065341)
			(xy 169.305936 -79.010868) (xy 169.325872 -78.958742) (xy 169.353186 -78.910074) (xy 169.387294 -78.865902)
			(xy 169.427471 -78.827167) (xy 169.472859 -78.794695) (xy 169.522491 -78.769177) (xy 169.575311 -78.751158)
			(xy 169.63019 -78.741021) (xy 169.685961 -78.738983) (xy 169.741435 -78.745086) (xy 169.795428 -78.759202)
			(xy 169.846791 -78.781029) (xy 169.894429 -78.810102) (xy 169.937325 -78.845801) (xy 169.973389 -78.88605)
			(xy 186.180728 -78.88605) (xy 186.184801 -78.830391) (xy 186.196936 -78.775918) (xy 186.216872 -78.723792)
			(xy 186.244186 -78.675124) (xy 186.278294 -78.630952) (xy 186.318471 -78.592217) (xy 186.363859 -78.559745)
			(xy 186.413491 -78.534227) (xy 186.466311 -78.516208) (xy 186.52119 -78.506071) (xy 186.576961 -78.504033)
			(xy 186.632435 -78.510136) (xy 186.686428 -78.524252) (xy 186.737791 -78.546079) (xy 186.785429 -78.575152)
			(xy 186.828325 -78.610851) (xy 186.865567 -78.652415) (xy 186.896361 -78.698959) (xy 186.920049 -78.74949)
			(xy 186.936127 -78.802932) (xy 186.944253 -78.858146) (xy 186.944762 -78.88605) (xy 186.944253 -78.913954)
			(xy 186.936127 -78.969168) (xy 186.920049 -79.02261) (xy 186.896361 -79.073141) (xy 186.865567 -79.119685)
			(xy 186.828325 -79.161249) (xy 186.785429 -79.196948) (xy 186.737791 -79.226021) (xy 186.686428 -79.247848)
			(xy 186.632435 -79.261964) (xy 186.576961 -79.268067) (xy 186.52119 -79.266029) (xy 186.466311 -79.255892)
			(xy 186.413491 -79.237873) (xy 186.363859 -79.212355) (xy 186.318471 -79.179883) (xy 186.278294 -79.141148)
			(xy 186.244186 -79.096976) (xy 186.216872 -79.048308) (xy 186.196936 -78.996182) (xy 186.184801 -78.941709)
			(xy 186.180728 -78.88605) (xy 169.973389 -78.88605) (xy 169.974567 -78.887365) (xy 170.005361 -78.933909)
			(xy 170.029049 -78.98444) (xy 170.045127 -79.037882) (xy 170.053253 -79.093096) (xy 170.053762 -79.121)
			(xy 170.053253 -79.148904) (xy 170.045127 -79.204118) (xy 170.029049 -79.25756) (xy 170.005361 -79.308091)
			(xy 169.974567 -79.354635) (xy 169.937325 -79.396199) (xy 169.894429 -79.431898) (xy 169.846791 -79.460971)
			(xy 169.795428 -79.482798) (xy 169.741435 -79.496914) (xy 169.685961 -79.503017) (xy 169.63019 -79.500979)
			(xy 169.575311 -79.490842) (xy 169.522491 -79.472823) (xy 169.472859 -79.447305) (xy 169.427471 -79.414833)
			(xy 169.387294 -79.376098) (xy 169.353186 -79.331926) (xy 169.325872 -79.283258) (xy 169.305936 -79.231132)
			(xy 169.293801 -79.176659) (xy 169.289728 -79.121) (xy 168.910762 -79.121) (xy 168.910253 -79.148904)
			(xy 168.902127 -79.204118) (xy 168.886049 -79.25756) (xy 168.862361 -79.308091) (xy 168.831567 -79.354635)
			(xy 168.794325 -79.396199) (xy 168.751429 -79.431898) (xy 168.703791 -79.460971) (xy 168.652428 -79.482798)
			(xy 168.598435 -79.496914) (xy 168.542961 -79.503017) (xy 168.48719 -79.500979) (xy 168.432311 -79.490842)
			(xy 168.379491 -79.472823) (xy 168.329859 -79.447305) (xy 168.284471 -79.414833) (xy 168.244294 -79.376098)
			(xy 168.210186 -79.331926) (xy 168.182872 -79.283258) (xy 168.162936 -79.231132) (xy 168.150801 -79.176659)
			(xy 168.146728 -79.121) (xy 166.751 -79.121) (xy 166.751 -80.20304) (xy 170.051728 -80.20304) (xy 170.055801 -80.147381)
			(xy 170.067936 -80.092908) (xy 170.087872 -80.040782) (xy 170.115186 -79.992114) (xy 170.149294 -79.947942)
			(xy 170.189471 -79.909207) (xy 170.234859 -79.876735) (xy 170.284491 -79.851217) (xy 170.337311 -79.833198)
			(xy 170.39219 -79.823061) (xy 170.447961 -79.821023) (xy 170.503435 -79.827126) (xy 170.557428 -79.841242)
			(xy 170.608791 -79.863069) (xy 170.656429 -79.892142) (xy 170.699325 -79.927841) (xy 170.736567 -79.969405)
			(xy 170.767361 -80.015949) (xy 170.791049 -80.06648) (xy 170.807127 -80.119922) (xy 170.80964 -80.137)
			(xy 182.370728 -80.137) (xy 182.374801 -80.081341) (xy 182.386936 -80.026868) (xy 182.406872 -79.974742)
			(xy 182.434186 -79.926074) (xy 182.468294 -79.881902) (xy 182.508471 -79.843167) (xy 182.553859 -79.810695)
			(xy 182.603491 -79.785177) (xy 182.656311 -79.767158) (xy 182.71119 -79.757021) (xy 182.766961 -79.754983)
			(xy 182.822435 -79.761086) (xy 182.876428 -79.775202) (xy 182.927791 -79.797029) (xy 182.975429 -79.826102)
			(xy 183.018325 -79.861801) (xy 183.055567 -79.903365) (xy 183.086361 -79.949909) (xy 183.110049 -80.00044)
			(xy 183.126127 -80.053882) (xy 183.134253 -80.109096) (xy 183.134762 -80.137) (xy 183.134253 -80.164904)
			(xy 183.126127 -80.220118) (xy 183.110049 -80.27356) (xy 183.086361 -80.324091) (xy 183.055567 -80.370635)
			(xy 183.018325 -80.412199) (xy 182.975429 -80.447898) (xy 182.927791 -80.476971) (xy 182.876428 -80.498798)
			(xy 182.822435 -80.512914) (xy 182.766961 -80.519017) (xy 182.71119 -80.516979) (xy 182.656311 -80.506842)
			(xy 182.603491 -80.488823) (xy 182.553859 -80.463305) (xy 182.508471 -80.430833) (xy 182.468294 -80.392098)
			(xy 182.434186 -80.347926) (xy 182.406872 -80.299258) (xy 182.386936 -80.247132) (xy 182.374801 -80.192659)
			(xy 182.370728 -80.137) (xy 170.80964 -80.137) (xy 170.815253 -80.175136) (xy 170.815762 -80.20304)
			(xy 170.815253 -80.230944) (xy 170.807127 -80.286158) (xy 170.791049 -80.3396) (xy 170.767361 -80.390131)
			(xy 170.736567 -80.436675) (xy 170.699325 -80.478239) (xy 170.656429 -80.513938) (xy 170.608791 -80.543011)
			(xy 170.557428 -80.564838) (xy 170.503435 -80.578954) (xy 170.447961 -80.585057) (xy 170.39219 -80.583019)
			(xy 170.337311 -80.572882) (xy 170.284491 -80.554863) (xy 170.234859 -80.529345) (xy 170.189471 -80.496873)
			(xy 170.149294 -80.458138) (xy 170.115186 -80.413966) (xy 170.087872 -80.365298) (xy 170.067936 -80.313172)
			(xy 170.055801 -80.258699) (xy 170.051728 -80.20304) (xy 166.751 -80.20304) (xy 166.751 -81.28) (xy 166.984678 -81.28)
			(xy 166.988751 -81.224341) (xy 167.000886 -81.169868) (xy 167.020822 -81.117742) (xy 167.048136 -81.069074)
			(xy 167.082244 -81.024902) (xy 167.122421 -80.986167) (xy 167.167809 -80.953695) (xy 167.217441 -80.928177)
			(xy 167.270261 -80.910158) (xy 167.32514 -80.900021) (xy 167.380911 -80.897983) (xy 167.436385 -80.904086)
			(xy 167.490378 -80.918202) (xy 167.541741 -80.940029) (xy 167.589379 -80.969102) (xy 167.632275 -81.004801)
			(xy 167.669517 -81.046365) (xy 167.700311 -81.092909) (xy 167.723999 -81.14344) (xy 167.740077 -81.196882)
			(xy 167.748203 -81.252096) (xy 167.748712 -81.28) (xy 167.748203 -81.307904) (xy 167.740077 -81.363118)
			(xy 167.723999 -81.41656) (xy 167.700311 -81.467091) (xy 167.669517 -81.513635) (xy 167.632275 -81.555199)
			(xy 167.589379 -81.590898) (xy 167.541741 -81.619971) (xy 167.490378 -81.641798) (xy 167.436385 -81.655914)
			(xy 167.380911 -81.662017) (xy 167.32514 -81.659979) (xy 167.270261 -81.649842) (xy 167.217441 -81.631823)
			(xy 167.167809 -81.606305) (xy 167.122421 -81.573833) (xy 167.082244 -81.535098) (xy 167.048136 -81.490926)
			(xy 167.020822 -81.442258) (xy 167.000886 -81.390132) (xy 166.988751 -81.335659) (xy 166.984678 -81.28)
			(xy 166.751 -81.28) (xy 166.751 -82.3041) (xy 175.361346 -82.3041) (xy 175.365377 -82.219475) (xy 175.377434 -82.135616)
			(xy 175.397408 -82.053284) (xy 175.425118 -81.973222) (xy 175.460313 -81.896158) (xy 175.502674 -81.822787)
			(xy 175.551817 -81.753776) (xy 175.607298 -81.689749) (xy 175.668614 -81.631285) (xy 175.73521 -81.578915)
			(xy 175.806482 -81.533112) (xy 175.881786 -81.494292) (xy 175.960438 -81.462805) (xy 176.041728 -81.438938)
			(xy 176.124918 -81.422905) (xy 176.209256 -81.414854) (xy 176.251616 -81.414366) (xy 176.293263 -81.414862)
			(xy 176.376192 -81.422668) (xy 176.458028 -81.438192) (xy 176.538054 -81.461297) (xy 176.57699 -81.476088)
			(xy 176.586068 -81.479207) (xy 176.60525 -81.479207) (xy 176.614328 -81.476088) (xy 176.653269 -81.461311)
			(xy 176.733294 -81.438204) (xy 176.815128 -81.422677) (xy 176.898055 -81.414865) (xy 176.939702 -81.414366)
			(xy 176.982064 -81.414814) (xy 177.066404 -81.422868) (xy 177.149597 -81.438902) (xy 177.230888 -81.462771)
			(xy 177.309543 -81.49426) (xy 177.384848 -81.533083) (xy 177.456122 -81.578888) (xy 177.52272 -81.631261)
			(xy 177.584037 -81.689727) (xy 177.639519 -81.753757) (xy 177.688664 -81.822771) (xy 177.731026 -81.896144)
			(xy 177.766221 -81.973211) (xy 177.793931 -82.053275) (xy 177.813906 -82.135611) (xy 177.825963 -82.219472)
			(xy 177.829995 -82.3041) (xy 177.829171 -82.3214) (xy 180.186328 -82.3214) (xy 180.190401 -82.265741)
			(xy 180.202536 -82.211268) (xy 180.222472 -82.159142) (xy 180.249786 -82.110474) (xy 180.283894 -82.066302)
			(xy 180.324071 -82.027567) (xy 180.369459 -81.995095) (xy 180.419091 -81.969577) (xy 180.471911 -81.951558)
			(xy 180.52679 -81.941421) (xy 180.582561 -81.939383) (xy 180.638035 -81.945486) (xy 180.692028 -81.959602)
			(xy 180.743391 -81.981429) (xy 180.791029 -82.010502) (xy 180.833925 -82.046201) (xy 180.871167 -82.087765)
			(xy 180.901961 -82.134309) (xy 180.925649 -82.18484) (xy 180.941727 -82.238282) (xy 180.949853 -82.293496)
			(xy 180.950362 -82.3214) (xy 180.949853 -82.349304) (xy 180.941727 -82.404518) (xy 180.925649 -82.45796)
			(xy 180.901961 -82.508491) (xy 180.871167 -82.555035) (xy 180.833925 -82.596599) (xy 180.791029 -82.632298)
			(xy 180.743391 -82.661371) (xy 180.692028 -82.683198) (xy 180.638035 -82.697314) (xy 180.582561 -82.703417)
			(xy 180.52679 -82.701379) (xy 180.471911 -82.691242) (xy 180.419091 -82.673223) (xy 180.369459 -82.647705)
			(xy 180.324071 -82.615233) (xy 180.283894 -82.576498) (xy 180.249786 -82.532326) (xy 180.222472 -82.483658)
			(xy 180.202536 -82.431532) (xy 180.190401 -82.377059) (xy 180.186328 -82.3214) (xy 177.829171 -82.3214)
			(xy 177.825963 -82.388728) (xy 177.813906 -82.472589) (xy 177.793931 -82.554925) (xy 177.766221 -82.634989)
			(xy 177.731026 -82.712056) (xy 177.688664 -82.785429) (xy 177.639519 -82.854443) (xy 177.584037 -82.918473)
			(xy 177.52272 -82.976939) (xy 177.456122 -83.029312) (xy 177.384848 -83.075117) (xy 177.309543 -83.11394)
			(xy 177.230888 -83.145429) (xy 177.149597 -83.169298) (xy 177.066404 -83.185332) (xy 176.982064 -83.193386)
			(xy 176.939702 -83.19389) (xy 176.898055 -83.193391) (xy 176.815126 -83.185586) (xy 176.73329 -83.170063)
			(xy 176.653264 -83.146959) (xy 176.614328 -83.132168) (xy 176.605259 -83.128992) (xy 176.586059 -83.128992)
			(xy 176.57699 -83.132168) (xy 176.538059 -83.146972) (xy 176.45803 -83.170071) (xy 176.376193 -83.185591)
			(xy 176.293264 -83.193395) (xy 176.251616 -83.19389) (xy 176.209256 -83.193346) (xy 176.124918 -83.185295)
			(xy 176.041728 -83.169262) (xy 175.960438 -83.145395) (xy 175.881786 -83.113908) (xy 175.806482 -83.075088)
			(xy 175.73521 -83.029285) (xy 175.668614 -82.976915) (xy 175.607298 -82.918451) (xy 175.551817 -82.854424)
			(xy 175.502674 -82.785413) (xy 175.460313 -82.712042) (xy 175.425118 -82.634978) (xy 175.397408 -82.554916)
			(xy 175.377434 -82.472584) (xy 175.365377 -82.388725) (xy 175.361346 -82.3041) (xy 166.751 -82.3041)
			(xy 166.751 -82.58048) (xy 166.751487 -82.594211) (xy 166.758875 -82.620662) (xy 166.773041 -82.644191)
			(xy 166.792962 -82.663096) (xy 166.817199 -82.676013) (xy 166.844001 -82.682007) (xy 166.871431 -82.680647)
			(xy 166.884604 -82.676746) (xy 166.913868 -82.667639) (xy 166.974358 -82.657811) (xy 167.005 -82.657188)
			(xy 167.032266 -82.657674) (xy 167.086242 -82.665435) (xy 167.138565 -82.680798) (xy 167.188169 -82.703452)
			(xy 167.234044 -82.732934) (xy 167.275256 -82.768644) (xy 167.310966 -82.809856) (xy 167.340448 -82.855731)
			(xy 167.363102 -82.905335) (xy 167.378465 -82.957658) (xy 167.386226 -83.011634) (xy 167.386226 -83.066166)
			(xy 167.378465 -83.120142) (xy 167.363102 -83.172465) (xy 167.340448 -83.222069) (xy 167.310966 -83.267944)
			(xy 167.275256 -83.309156) (xy 167.234044 -83.344866) (xy 167.188169 -83.374348) (xy 167.138565 -83.397002)
			(xy 167.086242 -83.412365) (xy 167.032266 -83.420126) (xy 167.005 -83.420712) (xy 166.974359 -83.420081)
			(xy 166.913871 -83.41025) (xy 166.884604 -83.401154) (xy 166.871424 -83.397256) (xy 166.843986 -83.395869)
			(xy 166.817171 -83.40185) (xy 166.792922 -83.414764) (xy 166.772994 -83.433676) (xy 166.758831 -83.457218)
			(xy 166.751458 -83.483684) (xy 166.751 -83.49742) (xy 166.751 -83.791766) (xy 181.838606 -83.791766)
			(xy 181.846363 -83.73778) (xy 181.861723 -83.685448) (xy 181.884375 -83.635834) (xy 181.913857 -83.589949)
			(xy 181.949568 -83.548727) (xy 181.990783 -83.513006) (xy 182.036662 -83.483514) (xy 182.086271 -83.460852)
			(xy 182.1386 -83.44548) (xy 182.192584 -83.437712) (xy 182.219854 -83.437222) (xy 182.245762 -83.437984)
			(xy 182.259702 -83.438503) (xy 182.287 -83.432806) (xy 182.311737 -83.419932) (xy 182.332064 -83.400842)
			(xy 182.346465 -83.376962) (xy 182.353863 -83.350075) (xy 182.35422 -83.33613) (xy 182.35422 -83.334098)
			(xy 182.354704 -83.306827) (xy 182.362466 -83.25284) (xy 182.377833 -83.200507) (xy 182.400491 -83.150894)
			(xy 182.429979 -83.10501) (xy 182.465697 -83.063791) (xy 182.506918 -83.028074) (xy 182.552802 -82.998587)
			(xy 182.602416 -82.97593) (xy 182.654749 -82.960564) (xy 182.708736 -82.952803) (xy 182.763278 -82.952804)
			(xy 182.817265 -82.960567) (xy 182.869598 -82.975935) (xy 182.919211 -82.998594) (xy 182.965094 -83.028082)
			(xy 183.006313 -83.063801) (xy 183.04203 -83.105022) (xy 183.071516 -83.150907) (xy 183.094172 -83.200521)
			(xy 183.109537 -83.252854) (xy 183.117297 -83.306842) (xy 183.117296 -83.361384) (xy 183.109532 -83.415371)
			(xy 183.094163 -83.467703) (xy 183.071504 -83.517315) (xy 183.042014 -83.563198) (xy 183.006295 -83.604417)
			(xy 182.965073 -83.640133) (xy 182.919188 -83.669619) (xy 182.869574 -83.692274) (xy 182.817241 -83.707638)
			(xy 182.763253 -83.715398) (xy 182.735982 -83.71586) (xy 182.710074 -83.715098) (xy 182.696135 -83.714537)
			(xy 182.668836 -83.720248) (xy 182.644101 -83.733133) (xy 182.623775 -83.75223) (xy 182.609375 -83.776115)
			(xy 182.601974 -83.803005) (xy 182.601616 -83.816952) (xy 182.601616 -83.818984) (xy 182.601193 -83.846254)
			(xy 182.593433 -83.900239) (xy 182.57807 -83.952571) (xy 182.555416 -84.002183) (xy 182.525931 -84.048067)
			(xy 182.490217 -84.089288) (xy 182.449001 -84.125006) (xy 182.40312 -84.154495) (xy 182.35351 -84.177155)
			(xy 182.30118 -84.192524) (xy 182.247196 -84.20029) (xy 182.192656 -84.200293) (xy 182.13867 -84.192535)
			(xy 182.086338 -84.177173) (xy 182.036725 -84.15452) (xy 181.990841 -84.125037) (xy 181.949619 -84.089324)
			(xy 181.9139 -84.048109) (xy 181.884409 -84.002229) (xy 181.861748 -83.95262) (xy 181.846378 -83.90029)
			(xy 181.838611 -83.846306) (xy 181.838606 -83.791766) (xy 166.751 -83.791766) (xy 166.751 -89.488518)
			(xy 166.750573 -89.498587) (xy 166.742854 -89.517186) (xy 166.736014 -89.524586) (xy 165.114986 -91.145614)
			(xy 165.107591 -91.152468) (xy 165.088992 -91.16021) (xy 165.078918 -91.1606) (xy 116.6114 -91.1606)
			(xy 116.026692 -91.745308) (xy 116.026692 -96.308361) (xy 157.479742 -96.308361) (xy 157.479742 -96.223639)
			(xy 157.487795 -96.139302) (xy 157.503829 -96.056112) (xy 157.527697 -95.974822) (xy 157.559185 -95.89617)
			(xy 157.598007 -95.820867) (xy 157.64381 -95.749595) (xy 157.696181 -95.682999) (xy 157.754646 -95.621684)
			(xy 157.818674 -95.566203) (xy 157.887686 -95.51706) (xy 157.961056 -95.4747) (xy 158.038121 -95.439505)
			(xy 158.118183 -95.411796) (xy 158.200516 -95.391822) (xy 158.284375 -95.379765) (xy 158.369 -95.375734)
			(xy 158.453625 -95.379765) (xy 158.537484 -95.391822) (xy 158.619817 -95.411796) (xy 158.699879 -95.439505)
			(xy 158.776944 -95.4747) (xy 158.850314 -95.51706) (xy 158.919326 -95.566203) (xy 158.983354 -95.621684)
			(xy 159.041819 -95.682999) (xy 159.09419 -95.749595) (xy 159.139993 -95.820867) (xy 159.178815 -95.89617)
			(xy 159.210303 -95.974822) (xy 159.234171 -96.056112) (xy 159.250205 -96.139302) (xy 159.258258 -96.223639)
			(xy 159.258762 -96.266) (xy 159.258258 -96.308361) (xy 159.250205 -96.392698) (xy 159.234171 -96.475888)
			(xy 159.210303 -96.557178) (xy 159.178815 -96.63583) (xy 159.139993 -96.711133) (xy 159.09419 -96.782405)
			(xy 159.041819 -96.849001) (xy 158.983354 -96.910316) (xy 158.919326 -96.965797) (xy 158.850314 -97.01494)
			(xy 158.776944 -97.0573) (xy 158.699879 -97.092495) (xy 158.619817 -97.120204) (xy 158.537484 -97.140178)
			(xy 158.453625 -97.152235) (xy 158.369 -97.156267) (xy 158.284375 -97.152235) (xy 158.200516 -97.140178)
			(xy 158.118183 -97.120204) (xy 158.038121 -97.092495) (xy 157.961056 -97.0573) (xy 157.887686 -97.01494)
			(xy 157.818674 -96.965797) (xy 157.754646 -96.910316) (xy 157.696181 -96.849001) (xy 157.64381 -96.782405)
			(xy 157.598007 -96.711133) (xy 157.559185 -96.63583) (xy 157.527697 -96.557178) (xy 157.503829 -96.475888)
			(xy 157.487795 -96.392698) (xy 157.479742 -96.308361) (xy 116.026692 -96.308361) (xy 116.026692 -100.70719)
			(xy 116.026851 -100.711) (xy 226.820982 -100.711) (xy 226.825053 -100.655378) (xy 226.837179 -100.600941)
			(xy 226.857102 -100.54885) (xy 226.884398 -100.500215) (xy 226.918484 -100.456072) (xy 226.958633 -100.417363)
			(xy 227.003991 -100.384912) (xy 227.053591 -100.359411) (xy 227.106375 -100.341404) (xy 227.161218 -100.331274)
			(xy 227.216952 -100.329237) (xy 227.272389 -100.335337) (xy 227.326346 -100.349443) (xy 227.377675 -100.371255)
			(xy 227.425281 -100.400309) (xy 227.468149 -100.435984) (xy 227.505366 -100.477521) (xy 227.536139 -100.524034)
			(xy 227.559811 -100.574531) (xy 227.575879 -100.627938) (xy 227.583999 -100.683114) (xy 227.584508 -100.711)
			(xy 227.583999 -100.738886) (xy 227.575879 -100.794062) (xy 227.559811 -100.847469) (xy 227.536139 -100.897966)
			(xy 227.505366 -100.944479) (xy 227.468149 -100.986016) (xy 227.425281 -101.021691) (xy 227.377675 -101.050745)
			(xy 227.326346 -101.072557) (xy 227.272389 -101.086663) (xy 227.216952 -101.092763) (xy 227.161218 -101.090726)
			(xy 227.106375 -101.080596) (xy 227.053591 -101.062589) (xy 227.003991 -101.037088) (xy 226.958633 -101.004637)
			(xy 226.918484 -100.965928) (xy 226.884398 -100.921785) (xy 226.857102 -100.87315) (xy 226.837179 -100.821059)
			(xy 226.825053 -100.766622) (xy 226.820982 -100.711) (xy 116.026851 -100.711) (xy 116.027113 -100.717261)
			(xy 116.034824 -100.735869) (xy 116.041678 -100.743258) (xy 116.998496 -101.700076) (xy 117.005893 -101.706926)
			(xy 117.024491 -101.714665) (xy 117.034564 -101.715062) (xy 292.025578 -101.715062)
		)
		(stroke
			(width 0)
			(type solid)
		)
		(fill yes)
		(layer "In7.Cu")
		(net "P3V3_AUX")
	)
	(gr_poly
		(pts
			(arc
				(start 192.800224 -51.05908)
				(mid 192.819747 -51.055179)
				(end 192.836292 -51.044094)
			)
			(arc
				(start 193.053462 -50.826924)
				(mid 193.064573 -50.81039)
				(end 193.068448 -50.790856)
			)
			(arc
				(start 193.068448 -46.88586)
				(mid 193.064547 -46.866337)
				(end 193.053462 -46.849792)
			)
			(arc
				(start 189.652656 -43.448986)
				(mid 189.636122 -43.437875)
				(end 189.616588 -43.434)
			)
			(arc
				(start 186.057794 -43.434)
				(mid 186.038271 -43.437901)
				(end 186.021726 -43.448986)
			)
			(arc
				(start 182.666386 -46.804326)
				(mid 182.655275 -46.82086)
				(end 182.6514 -46.840394)
			)
			(arc
				(start 182.6514 -50.663602)
				(mid 182.655301 -50.683125)
				(end 182.666386 -50.69967)
			)
			(arc
				(start 183.01081 -51.044094)
				(mid 183.027344 -51.055205)
				(end 183.046878 -51.05908)
			)
		)
		(stroke
			(width 0)
			(type solid)
		)
		(fill yes)
		(layer "In8.Cu")
		(net "P52V_2_FUSE_1")
	)
	(gr_poly
		(pts
			(arc
				(start 257.287522 -51.05908)
				(mid 257.307045 -51.055179)
				(end 257.32359 -51.044094)
			)
			(arc
				(start 257.668014 -50.69967)
				(mid 257.679125 -50.683136)
				(end 257.683 -50.663602)
			)
			(arc
				(start 257.683 -46.840394)
				(mid 257.679099 -46.820871)
				(end 257.668014 -46.804326)
			)
			(arc
				(start 254.312674 -43.448986)
				(mid 254.29614 -43.437875)
				(end 254.276606 -43.434)
			)
			(arc
				(start 250.717812 -43.434)
				(mid 250.698289 -43.437901)
				(end 250.681744 -43.448986)
			)
			(arc
				(start 247.280938 -46.849792)
				(mid 247.269827 -46.866326)
				(end 247.265952 -46.88586)
			)
			(arc
				(start 247.265952 -50.790856)
				(mid 247.269853 -50.810379)
				(end 247.280938 -50.826924)
			)
			(arc
				(start 247.498108 -51.044094)
				(mid 247.514642 -51.055205)
				(end 247.534176 -51.05908)
			)
		)
		(stroke
			(width 0)
			(type solid)
		)
		(fill yes)
		(layer "In8.Cu")
		(net "P52V_1_FUSE_1")
	)
	(gr_poly
		(pts
			(arc
				(start 136.007856 -80.01)
				(mid 136.027379 -80.006099)
				(end 136.043924 -79.995014)
			)
			(arc
				(start 136.343644 -79.695294)
				(mid 136.354755 -79.67876)
				(end 136.35863 -79.659226)
			)
			(arc
				(start 136.35863 -68.303902)
				(mid 136.397314 -68.109513)
				(end 136.507474 -67.944746)
			)
			(arc
				(start 137.49655 -66.95567)
				(mid 137.661318 -66.845512)
				(end 137.855706 -66.806826)
			)
			(arc
				(start 139.442444 -66.806826)
				(mid 139.460379 -66.803555)
				(end 139.475972 -66.794126)
			)
			(arc
				(start 139.475972 -66.794126)
				(mid 139.749442 -66.630021)
				(end 140.06322 -66.572892)
			)
			(arc
				(start 140.06322 -66.572892)
				(mid 140.377013 -66.629983)
				(end 140.650468 -66.794126)
			)
			(arc
				(start 140.650468 -66.794126)
				(mid 140.666078 -66.80351)
				(end 140.683996 -66.806826)
			)
			(arc
				(start 142.0876 -66.806826)
				(mid 142.123521 -66.791947)
				(end 142.1384 -66.756026)
			)
			(xy 142.1384 -64.131698)
			(arc
				(start 142.13713 -64.12611)
				(mid 142.120011 -64.026684)
				(end 142.11427 -63.925958)
			)
			(arc
				(start 142.11427 -63.925958)
				(mid 142.12002 -63.825234)
				(end 142.13713 -63.725806)
			)
			(xy 142.1384 -63.720218) (xy 142.1384 -63.025782)
			(arc
				(start 142.13713 -63.020194)
				(mid 142.120011 -62.920768)
				(end 142.11427 -62.820042)
			)
			(arc
				(start 142.11427 -62.820042)
				(mid 142.12002 -62.719318)
				(end 142.13713 -62.61989)
			)
			(xy 142.1384 -62.614302)
			(arc
				(start 142.1384 -47.729394)
				(mid 142.134499 -47.709871)
				(end 142.123414 -47.693326)
			)
			(arc
				(start 141.308074 -46.877986)
				(mid 141.29154 -46.866875)
				(end 141.272006 -46.863)
			)
			(arc
				(start 123.573794 -46.863)
				(mid 123.554271 -46.866901)
				(end 123.537726 -46.877986)
			)
			(arc
				(start 123.357386 -47.058326)
				(mid 123.346275 -47.07486)
				(end 123.3424 -47.094394)
			)
			(arc
				(start 123.3424 -79.651606)
				(mid 123.346301 -79.671129)
				(end 123.357386 -79.687674)
			)
			(arc
				(start 123.664726 -79.995014)
				(mid 123.68126 -80.006125)
				(end 123.700794 -80.01)
			)
		)
		(stroke
			(width 0)
			(type solid)
		)
		(fill yes)
		(layer "In8.Cu")
		(net "P52V_HS2_DRAIN_1")
	)
	(gr_poly
		(pts
			(arc
				(start 323.745606 -80.01)
				(mid 323.765129 -80.006099)
				(end 323.781674 -79.995014)
			)
			(arc
				(start 324.089014 -79.687674)
				(mid 324.100125 -79.67114)
				(end 324.104 -79.651606)
			)
			(arc
				(start 324.104 -47.094394)
				(mid 324.100099 -47.074871)
				(end 324.089014 -47.058326)
			)
			(arc
				(start 323.908674 -46.877986)
				(mid 323.89214 -46.866875)
				(end 323.872606 -46.863)
			)
			(arc
				(start 305.3588 -46.863)
				(mid 305.322879 -46.877879)
				(end 305.308 -46.9138)
			)
			(arc
				(start 305.308 -62.242954)
				(mid 305.310753 -62.259451)
				(end 305.318668 -62.274196)
			)
			(arc
				(start 305.318668 -62.274196)
				(mid 305.457751 -62.531519)
				(end 305.505866 -62.820042)
			)
			(arc
				(start 305.505866 -62.820042)
				(mid 305.462214 -63.095019)
				(end 305.335686 -63.343028)
			)
			(arc
				(start 305.335686 -63.343028)
				(mid 305.325927 -63.373)
				(end 305.335686 -63.402972)
			)
			(arc
				(start 305.335686 -63.402972)
				(mid 305.462208 -63.650983)
				(end 305.505866 -63.925958)
			)
			(arc
				(start 305.505866 -63.925958)
				(mid 305.45777 -64.214488)
				(end 305.318668 -64.471804)
			)
			(arc
				(start 305.318668 -64.471804)
				(mid 305.310697 -64.48653)
				(end 305.308 -64.503046)
			)
			(arc
				(start 305.308 -66.78549)
				(mid 305.322879 -66.821411)
				(end 305.3588 -66.83629)
			)
			(arc
				(start 306.81422 -66.83629)
				(mid 306.833245 -66.832593)
				(end 306.849526 -66.822066)
			)
			(arc
				(start 306.849526 -66.822066)
				(mid 307.467 -66.57292)
				(end 308.084474 -66.822066)
			)
			(arc
				(start 308.084474 -66.822066)
				(mid 308.100741 -66.832627)
				(end 308.11978 -66.83629)
			)
			(arc
				(start 309.808372 -66.83629)
				(mid 310.002761 -66.874974)
				(end 310.167528 -66.985134)
			)
			(arc
				(start 311.081166 -67.898772)
				(mid 311.191324 -68.06354)
				(end 311.23001 -68.257928)
			)
			(arc
				(start 311.23001 -79.613252)
				(mid 311.233911 -79.632775)
				(end 311.244996 -79.64932)
			)
			(arc
				(start 311.59069 -79.995014)
				(mid 311.607224 -80.006125)
				(end 311.626758 -80.01)
			)
		)
		(stroke
			(width 0)
			(type solid)
		)
		(fill yes)
		(layer "In8.Cu")
		(net "P52V_HS1_DRAIN_1")
	)
	(gr_poly
		(pts
			(arc
				(start 141.221206 -45.847)
				(mid 141.240729 -45.843099)
				(end 141.257274 -45.832014)
			)
			(arc
				(start 142.123414 -44.965874)
				(mid 142.134525 -44.94934)
				(end 142.1384 -44.929806)
			)
			(arc
				(start 142.1384 -41.667176)
				(mid 142.131291 -41.641003)
				(end 142.11173 -41.622218)
			)
			(arc
				(start 142.11173 -41.622218)
				(mid 141.769734 -41.29524)
				(end 141.643862 -40.839136)
			)
			(arc
				(start 141.643862 -40.839136)
				(mid 141.647416 -40.759442)
				(end 141.658086 -40.680386)
			)
			(xy 141.660372 -40.66794) (xy 141.653006 -40.644318)
			(arc
				(start 141.511274 -40.502586)
				(mid 141.49474 -40.491475)
				(end 141.475206 -40.4876)
			)
			(arc
				(start 139.1666 -40.4876)
				(mid 138.972211 -40.448916)
				(end 138.807444 -40.338756)
			)
			(arc
				(start 137.689844 -39.221156)
				(mid 137.579686 -39.056388)
				(end 137.541 -38.862)
			)
			(arc
				(start 137.541 -33.8328)
				(mid 137.579684 -33.638411)
				(end 137.689844 -33.473644)
			)
			(arc
				(start 137.989564 -33.173924)
				(mid 138.154332 -33.063766)
				(end 138.34872 -33.02508)
			)
			(arc
				(start 139.38885 -33.02508)
				(mid 139.408704 -33.02104)
				(end 139.425426 -33.009586)
			)
			(arc
				(start 139.425426 -33.009586)
				(mid 140.06322 -32.740107)
				(end 140.701014 -33.009586)
			)
			(arc
				(start 140.701014 -33.009586)
				(mid 140.717722 -33.021073)
				(end 140.73759 -33.02508)
			)
			(arc
				(start 141.520926 -33.02508)
				(mid 141.540449 -33.021179)
				(end 141.556994 -33.010094)
			)
			(arc
				(start 142.123414 -32.443674)
				(mid 142.134525 -32.42714)
				(end 142.1384 -32.407606)
			)
			(xy 142.1384 -30.298898)
			(arc
				(start 142.13713 -30.29331)
				(mid 142.120011 -30.193884)
				(end 142.11427 -30.093158)
			)
			(arc
				(start 142.11427 -30.093158)
				(mid 142.12002 -29.992434)
				(end 142.13713 -29.893006)
			)
			(xy 142.1384 -29.887418) (xy 142.1384 -29.192982)
			(arc
				(start 142.13713 -29.187394)
				(mid 142.120011 -29.087968)
				(end 142.11427 -28.987242)
			)
			(arc
				(start 142.11427 -28.987242)
				(mid 142.12002 -28.886518)
				(end 142.13713 -28.78709)
			)
			(xy 142.1384 -28.781502)
			(arc
				(start 142.1384 -13.439394)
				(mid 142.134499 -13.419871)
				(end 142.123414 -13.403326)
			)
			(arc
				(start 141.689074 -12.968986)
				(mid 141.67254 -12.957875)
				(end 141.653006 -12.954)
			)
			(arc
				(start 123.700794 -12.954)
				(mid 123.681271 -12.957901)
				(end 123.664726 -12.968986)
			)
			(arc
				(start 123.357386 -13.276326)
				(mid 123.346275 -13.29286)
				(end 123.3424 -13.312394)
			)
			(arc
				(start 123.3424 -45.615606)
				(mid 123.346301 -45.635129)
				(end 123.357386 -45.651674)
			)
			(arc
				(start 123.537726 -45.832014)
				(mid 123.55426 -45.843125)
				(end 123.573794 -45.847)
			)
		)
		(stroke
			(width 0)
			(type solid)
		)
		(fill yes)
		(layer "In8.Cu")
		(net "P52V_HS2_DRAIN_2")
	)
	(gr_poly
		(pts
			(arc
				(start 323.872606 -45.847)
				(mid 323.892129 -45.843099)
				(end 323.908674 -45.832014)
			)
			(arc
				(start 324.089014 -45.651674)
				(mid 324.100125 -45.63514)
				(end 324.104 -45.615606)
			)
			(arc
				(start 324.104 -13.312394)
				(mid 324.100099 -13.292871)
				(end 324.089014 -13.276326)
			)
			(arc
				(start 323.781674 -12.968986)
				(mid 323.76514 -12.957875)
				(end 323.745606 -12.954)
			)
			(arc
				(start 305.793394 -12.954)
				(mid 305.773871 -12.957901)
				(end 305.757326 -12.968986)
			)
			(arc
				(start 305.322986 -13.403326)
				(mid 305.311875 -13.41986)
				(end 305.308 -13.439394)
			)
			(arc
				(start 305.308 -28.410154)
				(mid 305.310753 -28.426651)
				(end 305.318668 -28.441396)
			)
			(arc
				(start 305.318668 -28.441396)
				(mid 305.457751 -28.698719)
				(end 305.505866 -28.987242)
			)
			(arc
				(start 305.505866 -28.987242)
				(mid 305.462214 -29.262219)
				(end 305.335686 -29.510228)
			)
			(arc
				(start 305.335686 -29.510228)
				(mid 305.325927 -29.5402)
				(end 305.335686 -29.570172)
			)
			(arc
				(start 305.335686 -29.570172)
				(mid 305.462208 -29.818183)
				(end 305.505866 -30.093158)
			)
			(arc
				(start 305.505866 -30.093158)
				(mid 305.45777 -30.381688)
				(end 305.318668 -30.639004)
			)
			(arc
				(start 305.318668 -30.639004)
				(mid 305.310697 -30.65373)
				(end 305.308 -30.670246)
			)
			(arc
				(start 305.308 -32.712406)
				(mid 305.311901 -32.731929)
				(end 305.322986 -32.748474)
			)
			(arc
				(start 305.53152 -32.957008)
				(mid 305.548054 -32.968119)
				(end 305.567588 -32.971994)
			)
			(arc
				(start 306.848764 -32.971994)
				(mid 306.866531 -32.968786)
				(end 306.882038 -32.959548)
			)
			(arc
				(start 306.882038 -32.959548)
				(mid 307.467 -32.740071)
				(end 308.051962 -32.959548)
			)
			(arc
				(start 308.051962 -32.959548)
				(mid 308.067477 -32.968763)
				(end 308.085236 -32.971994)
			)
			(arc
				(start 309.723028 -32.971994)
				(mid 309.917417 -33.010678)
				(end 310.082184 -33.120838)
			)
			(arc
				(start 311.103518 -34.142172)
				(mid 311.213676 -34.30694)
				(end 311.252362 -34.501328)
			)
			(arc
				(start 311.252362 -39.039038)
				(mid 311.213678 -39.233427)
				(end 311.103518 -39.398194)
			)
			(arc
				(start 309.629556 -40.872156)
				(mid 309.464788 -40.982314)
				(end 309.2704 -41.021)
			)
			(arc
				(start 305.844194 -41.021)
				(mid 305.824671 -41.024901)
				(end 305.808126 -41.035986)
			)
			(xy 305.748944 -41.095168)
			(arc
				(start 305.745134 -41.102788)
				(mid 305.574995 -41.341081)
				(end 305.336702 -41.51122)
			)
			(xy 305.329082 -41.51503)
			(arc
				(start 305.322986 -41.521126)
				(mid 305.311875 -41.53766)
				(end 305.308 -41.557194)
			)
			(arc
				(start 305.308 -45.158406)
				(mid 305.311901 -45.177929)
				(end 305.322986 -45.194474)
			)
			(arc
				(start 305.960526 -45.832014)
				(mid 305.97706 -45.843125)
				(end 305.996594 -45.847)
			)
		)
		(stroke
			(width 0)
			(type solid)
		)
		(fill yes)
		(layer "In8.Cu")
		(net "P52V_HS1_DRAIN_2")
	)
	(gr_poly
		(pts
			(arc
				(start 301.02302 -66.83629)
				(mid 301.042045 -66.832593)
				(end 301.058326 -66.822066)
			)
			(arc
				(start 301.058326 -66.822066)
				(mid 301.6758 -66.57292)
				(end 302.293274 -66.822066)
			)
			(arc
				(start 302.293274 -66.822066)
				(mid 302.309541 -66.832627)
				(end 302.32858 -66.83629)
			)
			(arc
				(start 304.2412 -66.83629)
				(mid 304.277121 -66.821411)
				(end 304.292 -66.78549)
			)
			(arc
				(start 304.292 -64.788288)
				(mid 304.283781 -64.760329)
				(end 304.26152 -64.741552)
			)
			(arc
				(start 304.26152 -64.741552)
				(mid 303.872479 -64.413552)
				(end 303.72685 -63.925958)
			)
			(arc
				(start 303.72685 -63.925958)
				(mid 303.770502 -63.650981)
				(end 303.89703 -63.402972)
			)
			(arc
				(start 303.89703 -63.402972)
				(mid 303.906789 -63.373)
				(end 303.89703 -63.343028)
			)
			(arc
				(start 303.89703 -63.343028)
				(mid 303.770508 -63.095017)
				(end 303.72685 -62.820042)
			)
			(arc
				(start 303.72685 -62.820042)
				(mid 303.872423 -62.33241)
				(end 304.26152 -62.004448)
			)
			(arc
				(start 304.26152 -62.004448)
				(mid 304.283721 -61.985633)
				(end 304.292 -61.957712)
			)
			(arc
				(start 304.292 -42.065194)
				(mid 304.288099 -42.045671)
				(end 304.277014 -42.029126)
			)
			(xy 303.762918 -41.51503)
			(arc
				(start 303.755298 -41.51122)
				(mid 303.517005 -41.341081)
				(end 303.346866 -41.102788)
			)
			(arc
				(start 303.346866 -41.102788)
				(mid 303.342572 -41.095678)
				(end 303.337214 -41.089326)
			)
			(arc
				(start 303.283874 -41.035986)
				(mid 303.26734 -41.024875)
				(end 303.247806 -41.021)
			)
			(arc
				(start 300.6852 -41.021)
				(mid 300.490811 -40.982316)
				(end 300.326044 -40.872156)
			)
			(arc
				(start 298.809156 -39.355268)
				(mid 298.698998 -39.1905)
				(end 298.660312 -38.996112)
			)
			(arc
				(start 298.660312 -33.576768)
				(mid 298.698996 -33.382379)
				(end 298.809156 -33.217612)
			)
			(arc
				(start 298.90593 -33.120838)
				(mid 299.070698 -33.01068)
				(end 299.265086 -32.971994)
			)
			(arc
				(start 301.057564 -32.971994)
				(mid 301.075331 -32.968786)
				(end 301.090838 -32.959548)
			)
			(arc
				(start 301.090838 -32.959548)
				(mid 301.6758 -32.740071)
				(end 302.260762 -32.959548)
			)
			(arc
				(start 302.260762 -32.959548)
				(mid 302.276277 -32.968763)
				(end 302.294036 -32.971994)
			)
			(arc
				(start 304.007012 -32.971994)
				(mid 304.026535 -32.968093)
				(end 304.04308 -32.957008)
			)
			(arc
				(start 304.277014 -32.723074)
				(mid 304.288125 -32.70654)
				(end 304.292 -32.687006)
			)
			(arc
				(start 304.292 -30.955488)
				(mid 304.283781 -30.927529)
				(end 304.26152 -30.908752)
			)
			(arc
				(start 304.26152 -30.908752)
				(mid 303.872479 -30.580752)
				(end 303.72685 -30.093158)
			)
			(arc
				(start 303.72685 -30.093158)
				(mid 303.770502 -29.818181)
				(end 303.89703 -29.570172)
			)
			(arc
				(start 303.89703 -29.570172)
				(mid 303.906789 -29.5402)
				(end 303.89703 -29.510228)
			)
			(arc
				(start 303.89703 -29.510228)
				(mid 303.770508 -29.262217)
				(end 303.72685 -28.987242)
			)
			(arc
				(start 303.72685 -28.987242)
				(mid 303.872423 -28.49961)
				(end 304.26152 -28.171648)
			)
			(arc
				(start 304.26152 -28.171648)
				(mid 304.283721 -28.152833)
				(end 304.292 -28.124912)
			)
			(arc
				(start 304.292 -13.439394)
				(mid 304.288099 -13.419871)
				(end 304.277014 -13.403326)
			)
			(arc
				(start 303.842674 -12.968986)
				(mid 303.82614 -12.957875)
				(end 303.806606 -12.954)
			)
			(arc
				(start 283.585412 -12.954)
				(mid 283.565889 -12.957901)
				(end 283.549344 -12.968986)
			)
			(arc
				(start 280.176986 -16.341344)
				(mid 280.165875 -16.357878)
				(end 280.162 -16.377412)
			)
			(arc
				(start 280.162 -27.182318)
				(mid 280.123316 -27.376707)
				(end 280.013156 -27.541474)
			)
			(arc
				(start 278.747474 -28.807156)
				(mid 278.582706 -28.917314)
				(end 278.388318 -28.956)
			)
			(arc
				(start 231.371394 -28.956)
				(mid 231.351871 -28.959901)
				(end 231.335326 -28.970986)
			)
			(arc
				(start 229.884986 -30.421326)
				(mid 229.873875 -30.43786)
				(end 229.87 -30.457394)
			)
			(arc
				(start 229.87 -46.758606)
				(mid 229.873901 -46.778129)
				(end 229.884986 -46.794674)
			)
			(arc
				(start 230.446326 -47.356014)
				(mid 230.46286 -47.367125)
				(end 230.482394 -47.371)
			)
			(arc
				(start 242.73256 -47.371)
				(mid 242.752083 -47.367099)
				(end 242.768628 -47.356014)
			)
			(arc
				(start 248.63425 -41.490392)
				(mid 248.799018 -41.380234)
				(end 248.993406 -41.341548)
			)
			(arc
				(start 273.700748 -41.341548)
				(mid 273.895137 -41.380232)
				(end 274.059904 -41.490392)
			)
			(arc
				(start 275.771356 -43.201844)
				(mid 275.881514 -43.366612)
				(end 275.9202 -43.561)
			)
			(arc
				(start 275.9202 -49.908206)
				(mid 275.924101 -49.927729)
				(end 275.935186 -49.944274)
			)
			(arc
				(start 276.725126 -50.734214)
				(mid 276.74166 -50.745325)
				(end 276.761194 -50.7492)
			)
			(arc
				(start 294.8432 -50.7492)
				(mid 295.037589 -50.787884)
				(end 295.202356 -50.898044)
			)
			(arc
				(start 296.904156 -52.599844)
				(mid 297.014314 -52.764612)
				(end 297.053 -52.959)
			)
			(arc
				(start 297.053 -65.300606)
				(mid 297.056901 -65.320129)
				(end 297.067986 -65.336674)
			)
			(arc
				(start 298.552616 -66.821304)
				(mid 298.56915 -66.832415)
				(end 298.588684 -66.83629)
			)
		)
		(stroke
			(width 0)
			(type solid)
		)
		(fill yes)
		(layer "In8.Cu")
		(net "P52V_1")
	)
	(gr_poly
		(pts
			(arc
				(start 145.801842 -66.806826)
				(mid 145.819777 -66.803555)
				(end 145.83537 -66.794126)
			)
			(arc
				(start 145.83537 -66.794126)
				(mid 146.10884 -66.630021)
				(end 146.422618 -66.572892)
			)
			(arc
				(start 146.422618 -66.572892)
				(mid 146.736411 -66.629983)
				(end 147.009866 -66.794126)
			)
			(arc
				(start 147.009866 -66.794126)
				(mid 147.025476 -66.80351)
				(end 147.043394 -66.806826)
			)
			(arc
				(start 148.436838 -66.806826)
				(mid 148.456361 -66.802925)
				(end 148.472906 -66.79184)
			)
			(arc
				(start 148.854414 -66.410332)
				(mid 148.865525 -66.393798)
				(end 148.8694 -66.374264)
			)
			(arc
				(start 148.8694 -60.2234)
				(mid 148.908084 -60.029011)
				(end 149.018244 -59.864244)
			)
			(arc
				(start 152.548844 -56.333644)
				(mid 152.713612 -56.223486)
				(end 152.908 -56.1848)
			)
			(arc
				(start 159.102806 -56.1848)
				(mid 159.122329 -56.180899)
				(end 159.138874 -56.169814)
			)
			(arc
				(start 160.118044 -55.190644)
				(mid 160.282812 -55.080486)
				(end 160.4772 -55.0418)
			)
			(arc
				(start 175.333406 -55.0418)
				(mid 175.352929 -55.037899)
				(end 175.369474 -55.026814)
			)
			(arc
				(start 175.779176 -54.617112)
				(mid 175.790287 -54.600578)
				(end 175.794162 -54.581044)
			)
			(arc
				(start 175.794162 -53.658516)
				(mid 175.790261 -53.638993)
				(end 175.779176 -53.622448)
			)
			(arc
				(start 173.785022 -51.628294)
				(mid 173.768488 -51.617183)
				(end 173.748954 -51.613308)
			)
			(arc
				(start 172.583348 -51.613308)
				(mid 172.388959 -51.574624)
				(end 172.224192 -51.464464)
			)
			(arc
				(start 171.815506 -51.055778)
				(mid 171.705348 -50.89101)
				(end 171.666662 -50.696622)
			)
			(arc
				(start 171.666662 -43.570398)
				(mid 171.705346 -43.376009)
				(end 171.815506 -43.211242)
			)
			(arc
				(start 173.556676 -41.470072)
				(mid 173.721444 -41.359914)
				(end 173.915832 -41.321228)
			)
			(arc
				(start 191.747394 -41.321228)
				(mid 191.941783 -41.359912)
				(end 192.10655 -41.470072)
			)
			(arc
				(start 197.992492 -47.356014)
				(mid 198.009026 -47.367125)
				(end 198.02856 -47.371)
			)
			(arc
				(start 209.852006 -47.371)
				(mid 209.871529 -47.367099)
				(end 209.888074 -47.356014)
			)
			(arc
				(start 210.449414 -46.794674)
				(mid 210.460525 -46.77814)
				(end 210.4644 -46.758606)
			)
			(arc
				(start 210.4644 -30.457394)
				(mid 210.460499 -30.437871)
				(end 210.449414 -30.421326)
			)
			(arc
				(start 208.999074 -28.970986)
				(mid 208.98254 -28.959875)
				(end 208.963006 -28.956)
			)
			(arc
				(start 161.946082 -28.956)
				(mid 161.751693 -28.917316)
				(end 161.586926 -28.807156)
			)
			(arc
				(start 160.321244 -27.541474)
				(mid 160.211086 -27.376706)
				(end 160.1724 -27.182318)
			)
			(arc
				(start 160.1724 -16.377412)
				(mid 160.168499 -16.357889)
				(end 160.157414 -16.341344)
			)
			(arc
				(start 156.785056 -12.968986)
				(mid 156.768522 -12.957875)
				(end 156.748988 -12.954)
			)
			(arc
				(start 143.639794 -12.954)
				(mid 143.620271 -12.957901)
				(end 143.603726 -12.968986)
			)
			(arc
				(start 143.169386 -13.403326)
				(mid 143.158275 -13.41986)
				(end 143.1544 -13.439394)
			)
			(xy 143.1544 -28.086812) (xy 143.176752 -28.114498)
			(arc
				(start 143.194278 -28.118308)
				(mid 143.696887 -28.429625)
				(end 143.893286 -28.987242)
			)
			(arc
				(start 143.893286 -28.987242)
				(mid 143.849634 -29.262219)
				(end 143.723106 -29.510228)
			)
			(arc
				(start 143.723106 -29.510228)
				(mid 143.713347 -29.5402)
				(end 143.723106 -29.570172)
			)
			(arc
				(start 143.723106 -29.570172)
				(mid 143.849628 -29.818183)
				(end 143.893286 -30.093158)
			)
			(arc
				(start 143.893286 -30.093158)
				(mid 143.696838 -30.650735)
				(end 143.194278 -30.962092)
			)
			(xy 143.176752 -30.965902) (xy 143.1544 -30.993588)
			(arc
				(start 143.1544 -32.458406)
				(mid 143.158301 -32.477929)
				(end 143.169386 -32.494474)
			)
			(arc
				(start 143.685006 -33.010094)
				(mid 143.70154 -33.021205)
				(end 143.721074 -33.02508)
			)
			(arc
				(start 145.18005 -33.02508)
				(mid 145.199904 -33.02104)
				(end 145.216626 -33.009586)
			)
			(arc
				(start 145.216626 -33.009586)
				(mid 145.85442 -32.740107)
				(end 146.492214 -33.009586)
			)
			(arc
				(start 146.492214 -33.009586)
				(mid 146.508922 -33.021073)
				(end 146.52879 -33.02508)
			)
			(arc
				(start 147.35048 -33.02508)
				(mid 147.544869 -33.063764)
				(end 147.709636 -33.173924)
			)
			(arc
				(start 148.212556 -33.676844)
				(mid 148.322714 -33.841612)
				(end 148.3614 -34.036)
			)
			(arc
				(start 148.3614 -38.3794)
				(mid 148.322716 -38.573789)
				(end 148.212556 -38.738556)
			)
			(arc
				(start 146.612356 -40.338756)
				(mid 146.447588 -40.448914)
				(end 146.2532 -40.4876)
			)
			(arc
				(start 144.292574 -40.4876)
				(mid 144.270175 -40.492805)
				(end 144.252442 -40.507412)
			)
			(xy 144.1958 -40.58031) (xy 144.191228 -40.60317)
			(arc
				(start 144.194276 -40.614854)
				(mid 144.215769 -40.72608)
				(end 144.222978 -40.839136)
			)
			(arc
				(start 144.222978 -40.839136)
				(mid 143.962447 -41.468113)
				(end 143.33347 -41.728644)
			)
			(arc
				(start 143.33347 -41.728644)
				(mid 143.298644 -41.727932)
				(end 143.263874 -41.72585)
			)
			(xy 143.253206 -41.725088) (xy 143.233394 -41.731946)
			(arc
				(start 143.170656 -41.789858)
				(mid 143.158592 -41.806821)
				(end 143.1544 -41.827196)
			)
			(xy 143.1544 -61.919612) (xy 143.176752 -61.947298)
			(arc
				(start 143.194278 -61.951108)
				(mid 143.696887 -62.262425)
				(end 143.893286 -62.820042)
			)
			(arc
				(start 143.893286 -62.820042)
				(mid 143.849634 -63.095019)
				(end 143.723106 -63.343028)
			)
			(arc
				(start 143.723106 -63.343028)
				(mid 143.713347 -63.373)
				(end 143.723106 -63.402972)
			)
			(arc
				(start 143.723106 -63.402972)
				(mid 143.849628 -63.650983)
				(end 143.893286 -63.925958)
			)
			(arc
				(start 143.893286 -63.925958)
				(mid 143.696838 -64.483535)
				(end 143.194278 -64.794892)
			)
			(xy 143.176752 -64.798702) (xy 143.1544 -64.826388)
			(arc
				(start 143.1544 -66.756026)
				(mid 143.169279 -66.791947)
				(end 143.2052 -66.806826)
			)
		)
		(stroke
			(width 0)
			(type solid)
		)
		(fill yes)
		(layer "In8.Cu")
		(net "P52V_2")
	)
	(gr_poly
		(pts
			(xy 474.000068 -199.098154) (xy 474.055876 -199.097646) (xy 474.167179 -199.089307) (xy 474.277548 -199.072673)
			(xy 474.386365 -199.047838) (xy 474.493022 -199.01494) (xy 474.596923 -198.974164) (xy 474.697485 -198.925736)
			(xy 474.794147 -198.869929) (xy 474.886368 -198.807054) (xy 474.973633 -198.737463) (xy 475.055452 -198.661545)
			(xy 475.13137 -198.579725) (xy 475.20096 -198.49246) (xy 475.263834 -198.400239) (xy 475.319641 -198.303576)
			(xy 475.368068 -198.203014) (xy 475.408844 -198.099113) (xy 475.441741 -197.992456) (xy 475.466575 -197.883638)
			(xy 475.483208 -197.773269) (xy 475.491546 -197.661966) (xy 475.492064 -197.606158) (xy 475.492064 -135.770112)
			(xy 475.491555 -135.714305) (xy 475.483215 -135.603002) (xy 475.46658 -135.492634) (xy 475.441744 -135.383817)
			(xy 475.408845 -135.277161) (xy 475.368068 -135.173262) (xy 475.31964 -135.072701) (xy 475.263833 -134.97604)
			(xy 475.200958 -134.88382) (xy 475.131367 -134.796556) (xy 475.055449 -134.714737) (xy 474.973629 -134.63882)
			(xy 474.886364 -134.569231) (xy 474.794143 -134.506357) (xy 474.697481 -134.450551) (xy 474.596919 -134.402124)
			(xy 474.49302 -134.361348) (xy 474.386363 -134.328451) (xy 474.277546 -134.303616) (xy 474.167178 -134.286983)
			(xy 474.055875 -134.278644) (xy 474.000068 -134.278116) (xy 444.999872 -134.278116) (xy 444.929968 -134.278612)
			(xy 444.790381 -134.286463) (xy 444.651454 -134.302127) (xy 444.513624 -134.325555) (xy 444.377323 -134.356674)
			(xy 444.242982 -134.395385) (xy 444.111022 -134.441566) (xy 443.981859 -134.495074) (xy 443.855899 -134.555738)
			(xy 443.733538 -134.623368) (xy 443.615161 -134.697752) (xy 443.50114 -134.778656) (xy 443.391834 -134.865825)
			(xy 443.287587 -134.958985) (xy 443.188727 -135.057842) (xy 443.095565 -135.162087) (xy 443.008393 -135.27139)
			(xy 442.927487 -135.385409) (xy 442.8531 -135.503784) (xy 442.785466 -135.626144) (xy 442.724799 -135.752102)
			(xy 442.671289 -135.881264) (xy 442.625104 -136.013223) (xy 442.586389 -136.147563) (xy 442.555267 -136.283863)
			(xy 442.531836 -136.421693) (xy 442.516168 -136.56062) (xy 442.508314 -136.700206) (xy 442.507878 -136.77011)
			(xy 442.507878 -153.299922) (xy 442.507375 -153.422774) (xy 442.499335 -153.668345) (xy 442.483265 -153.913522)
			(xy 442.459181 -154.158042) (xy 442.42711 -154.401643) (xy 442.387085 -154.644065) (xy 442.33915 -154.885047)
			(xy 442.283356 -155.124331) (xy 442.219763 -155.361662) (xy 442.148438 -155.596785) (xy 442.069459 -155.829449)
			(xy 441.982909 -156.059404) (xy 441.888882 -156.286404) (xy 441.787478 -156.510205) (xy 441.678806 -156.73057)
			(xy 441.562982 -156.94726) (xy 441.44013 -157.160045) (xy 441.310381 -157.368697) (xy 441.173875 -157.572991)
			(xy 441.030758 -157.77271) (xy 440.881183 -157.967639) (xy 440.72531 -158.15757) (xy 440.563307 -158.342299)
			(xy 440.395346 -158.521628) (xy 440.221607 -158.695366) (xy 440.042277 -158.863327) (xy 439.857547 -159.02533)
			(xy 439.667615 -159.181202) (xy 439.472686 -159.330776) (xy 439.272966 -159.473893) (xy 439.068671 -159.610398)
			(xy 438.860019 -159.740145) (xy 438.647234 -159.862996) (xy 438.430543 -159.97882) (xy 438.210178 -160.087491)
			(xy 437.986376 -160.188894) (xy 437.759376 -160.28292) (xy 437.52942 -160.369469) (xy 437.296757 -160.448447)
			(xy 437.061633 -160.519771) (xy 436.824302 -160.583363) (xy 436.585017 -160.639156) (xy 436.344035 -160.68709)
			(xy 436.101614 -160.727114) (xy 435.858012 -160.759184) (xy 435.613492 -160.783267) (xy 435.368315 -160.799337)
			(xy 435.122744 -160.807376) (xy 434.999892 -160.807908) (xy 416.576256 -160.807908) (xy 416.506352 -160.808399)
			(xy 416.366764 -160.816241) (xy 416.227835 -160.831897) (xy 416.090003 -160.855317) (xy 415.9537 -160.88643)
			(xy 415.819357 -160.925136) (xy 415.687395 -160.971313) (xy 415.55823 -161.024817) (xy 415.432268 -161.085479)
			(xy 415.309905 -161.153108) (xy 415.191527 -161.227492) (xy 415.077506 -161.308396) (xy 414.968201 -161.395567)
			(xy 414.863955 -161.488728) (xy 414.765097 -161.587588) (xy 414.671937 -161.691836) (xy 414.584769 -161.801143)
			(xy 414.503867 -161.915166) (xy 414.429485 -162.033545) (xy 414.361858 -162.155909) (xy 414.301198 -162.281872)
			(xy 414.247697 -162.411038) (xy 414.201522 -162.543001) (xy 414.162818 -162.677345) (xy 414.131708 -162.813648)
			(xy 414.10829 -162.951481) (xy 414.092637 -163.09041) (xy 414.084798 -163.229998) (xy 414.084262 -163.299902)
			(xy 414.084262 -187.606178) (xy 414.083778 -187.676532) (xy 414.07589 -187.817019) (xy 414.060137 -187.956842)
			(xy 414.036568 -188.095562) (xy 414.005258 -188.232743) (xy 413.966306 -188.367952) (xy 413.919834 -188.500764)
			(xy 413.865987 -188.630762) (xy 413.804937 -188.757535) (xy 413.736874 -188.880686) (xy 413.662013 -188.999827)
			(xy 413.580589 -189.114583) (xy 413.492859 -189.224593) (xy 413.399098 -189.329511) (xy 413.299602 -189.429006)
			(xy 413.194684 -189.522766) (xy 413.084674 -189.610496) (xy 412.969917 -189.691919) (xy 412.850776 -189.76678)
			(xy 412.727625 -189.834842) (xy 412.600851 -189.895892) (xy 412.470853 -189.949738) (xy 412.33804 -189.99621)
			(xy 412.202831 -190.035161) (xy 412.065651 -190.06647) (xy 411.92693 -190.090038) (xy 411.787107 -190.105791)
			(xy 411.64662 -190.113679) (xy 411.576266 -190.114174) (xy 351.499932 -190.114174) (xy 351.429578 -190.113691)
			(xy 351.28909 -190.105803) (xy 351.149266 -190.09005) (xy 351.010545 -190.066482) (xy 350.873364 -190.035172)
			(xy 350.738154 -189.996221) (xy 350.605341 -189.949748) (xy 350.475343 -189.895903) (xy 350.348569 -189.834852)
			(xy 350.225417 -189.766789) (xy 350.106275 -189.691929) (xy 349.991518 -189.610505) (xy 349.881507 -189.522775)
			(xy 349.776589 -189.429014) (xy 349.677092 -189.329519) (xy 349.583332 -189.2246) (xy 349.495601 -189.11459)
			(xy 349.414177 -188.999833) (xy 349.339316 -188.880692) (xy 349.271252 -188.75754) (xy 349.210202 -188.630766)
			(xy 349.156355 -188.500768) (xy 349.109883 -188.367955) (xy 349.07093 -188.232746) (xy 349.03962 -188.095565)
			(xy 349.016052 -187.956844) (xy 349.000298 -187.81702) (xy 348.99241 -187.676532) (xy 348.991936 -187.606178)
			(xy 348.991936 -110.499906) (xy 348.991437 -110.399374) (xy 348.983341 -110.198474) (xy 348.967162 -109.998063)
			(xy 348.942927 -109.798466) (xy 348.910674 -109.600006) (xy 348.870457 -109.403006) (xy 348.822339 -109.207786)
			(xy 348.7664 -109.014661) (xy 348.702729 -108.823945) (xy 348.631431 -108.635948) (xy 348.552621 -108.450974)
			(xy 348.466427 -108.269323) (xy 348.372988 -108.09129) (xy 348.272456 -107.917165) (xy 348.164995 -107.747228)
			(xy 348.050777 -107.581757) (xy 347.92999 -107.421018) (xy 347.802828 -107.265274) (xy 347.669498 -107.114776)
			(xy 347.530217 -106.969769) (xy 347.385209 -106.830488) (xy 347.234711 -106.697159) (xy 347.078966 -106.569998)
			(xy 346.918227 -106.449211) (xy 346.752755 -106.334994) (xy 346.582818 -106.227533) (xy 346.408692 -106.127002)
			(xy 346.230659 -106.033564) (xy 346.049008 -105.947371) (xy 345.864034 -105.868561) (xy 345.676036 -105.797264)
			(xy 345.48532 -105.733594) (xy 345.292195 -105.677656) (xy 345.096974 -105.629539) (xy 344.899974 -105.589322)
			(xy 344.701514 -105.55707) (xy 344.501917 -105.532836) (xy 344.301506 -105.516658) (xy 344.100606 -105.508563)
			(xy 344.000074 -105.508044) (xy 293.310056 -105.508044) (xy 293.254251 -105.508567) (xy 293.142952 -105.516911)
			(xy 293.032588 -105.533549) (xy 292.923776 -105.558388) (xy 292.817125 -105.591289) (xy 292.713231 -105.632068)
			(xy 292.612674 -105.680497) (xy 292.516018 -105.736305) (xy 292.423802 -105.799181) (xy 292.336543 -105.868771)
			(xy 292.254729 -105.944688) (xy 292.178817 -106.026507) (xy 292.109231 -106.11377) (xy 292.046361 -106.205989)
			(xy 291.990558 -106.302648) (xy 291.942135 -106.403208) (xy 291.901361 -106.507104) (xy 291.868466 -106.613758)
			(xy 291.843634 -106.722571) (xy 291.827002 -106.832936) (xy 291.818664 -106.944235) (xy 291.81806 -107.00004)
			(xy 291.81806 -121.780046) (xy 291.817562 -121.863539) (xy 291.809615 -122.030336) (xy 291.793739 -122.196566)
			(xy 291.769973 -122.361852) (xy 291.738368 -122.52582) (xy 291.698998 -122.688098) (xy 291.65195 -122.848319)
			(xy 291.597333 -123.006121) (xy 291.535268 -123.161144) (xy 291.465898 -123.313039) (xy 291.389379 -123.461461)
			(xy 291.305884 -123.606075) (xy 291.215603 -123.746551) (xy 291.11874 -123.882573) (xy 291.015514 -124.013832)
			(xy 290.90616 -124.14003) (xy 290.790925 -124.260882) (xy 290.670071 -124.376114) (xy 290.54387 -124.485465)
			(xy 290.412609 -124.588688) (xy 290.276585 -124.685548) (xy 290.136106 -124.775826) (xy 289.991491 -124.859317)
			(xy 289.843067 -124.935833) (xy 289.691171 -125.0052) (xy 289.536146 -125.067261) (xy 289.378343 -125.121875)
			(xy 289.218121 -125.168919) (xy 289.055841 -125.208285) (xy 288.891873 -125.239886) (xy 288.726586 -125.263649)
			(xy 288.560356 -125.27952) (xy 288.393559 -125.287464) (xy 288.310066 -125.28804) (xy 139.910058 -125.28804)
			(xy 139.826564 -125.287542) (xy 139.659766 -125.279595) (xy 139.493535 -125.26372) (xy 139.328247 -125.239954)
			(xy 139.164277 -125.20835) (xy 139.001997 -125.168979) (xy 138.841774 -125.121932) (xy 138.683971 -125.067315)
			(xy 138.528946 -125.005251) (xy 138.377049 -124.935881) (xy 138.228625 -124.859362) (xy 138.08401 -124.775868)
			(xy 137.943531 -124.685588) (xy 137.807507 -124.588725) (xy 137.676246 -124.4855) (xy 137.550046 -124.376146)
			(xy 137.429191 -124.260912) (xy 137.313956 -124.140057) (xy 137.204603 -124.013857) (xy 137.101377 -123.882596)
			(xy 137.004515 -123.746572) (xy 136.914234 -123.606094) (xy 136.830739 -123.461479) (xy 136.75422 -123.313055)
			(xy 136.68485 -123.161158) (xy 136.622786 -123.006132) (xy 136.568169 -122.848329) (xy 136.521122 -122.688106)
			(xy 136.481751 -122.525826) (xy 136.450147 -122.361857) (xy 136.42638 -122.196569) (xy 136.410505 -122.030338)
			(xy 136.402558 -121.86354) (xy 136.402064 -121.780046) (xy 136.402064 -107.00004) (xy 136.401556 -106.944232)
			(xy 136.393218 -106.832928) (xy 136.376585 -106.722558) (xy 136.35175 -106.61374) (xy 136.318853 -106.507082)
			(xy 136.278076 -106.403181) (xy 136.229649 -106.302618) (xy 136.173842 -106.205955) (xy 136.110967 -106.113733)
			(xy 136.041377 -106.026468) (xy 135.965459 -105.944647) (xy 135.883638 -105.868729) (xy 135.796373 -105.799137)
			(xy 135.704152 -105.736262) (xy 135.607489 -105.680455) (xy 135.506926 -105.632027) (xy 135.403025 -105.59125)
			(xy 135.296368 -105.558352) (xy 135.18755 -105.533517) (xy 135.07718 -105.516883) (xy 134.965876 -105.508544)
			(xy 134.910068 -105.508044) (xy 95.999808 -105.508044) (xy 95.899276 -105.508543) (xy 95.698376 -105.516639)
			(xy 95.497964 -105.532817) (xy 95.298366 -105.557053) (xy 95.099907 -105.589305) (xy 94.902906 -105.629523)
			(xy 94.707685 -105.67764) (xy 94.51456 -105.73358) (xy 94.323844 -105.79725) (xy 94.135846 -105.868548)
			(xy 93.950872 -105.947358) (xy 93.769221 -106.033552) (xy 93.591188 -106.126991) (xy 93.417061 -106.227522)
			(xy 93.247124 -106.334984) (xy 93.081652 -106.449201) (xy 92.920913 -106.569988) (xy 92.765169 -106.69715)
			(xy 92.61467 -106.83048) (xy 92.469663 -106.969761) (xy 92.330381 -107.114769) (xy 92.197051 -107.265267)
			(xy 92.06989 -107.421012) (xy 91.949102 -107.581751) (xy 91.834885 -107.747223) (xy 91.727424 -107.91716)
			(xy 91.626892 -108.091286) (xy 91.533453 -108.269319) (xy 91.447259 -108.45097) (xy 91.368448 -108.635944)
			(xy 91.29715 -108.823942) (xy 91.23348 -109.014658) (xy 91.177541 -109.207783) (xy 91.129423 -109.403004)
			(xy 91.089206 -109.600005) (xy 91.056953 -109.798465) (xy 91.032718 -109.998062) (xy 91.016539 -110.198474)
			(xy 91.008443 -110.399374) (xy 91.007946 -110.499906) (xy 91.007946 -187.606178) (xy 91.007462 -187.676532)
			(xy 90.999574 -187.817018) (xy 90.983821 -187.956841) (xy 90.960252 -188.095561) (xy 90.928942 -188.232741)
			(xy 90.88999 -188.36795) (xy 90.843517 -188.500762) (xy 90.789671 -188.630759) (xy 90.72862 -188.757532)
			(xy 90.660557 -188.880683) (xy 90.585696 -188.999823) (xy 90.504272 -189.114579) (xy 90.416542 -189.224588)
			(xy 90.322781 -189.329506) (xy 90.223285 -189.429) (xy 90.118367 -189.52276) (xy 90.008357 -189.610489)
			(xy 89.8936 -189.691911) (xy 89.774459 -189.766771) (xy 89.651307 -189.834833) (xy 89.524533 -189.895882)
			(xy 89.394536 -189.949727) (xy 89.261723 -189.996198) (xy 89.126514 -190.035149) (xy 88.989334 -190.066457)
			(xy 88.850614 -190.090024) (xy 88.71079 -190.105776) (xy 88.570304 -190.113663) (xy 88.49995 -190.114174)
			(xy 28.42387 -190.114174) (xy 28.353517 -190.11368) (xy 28.213033 -190.105789) (xy 28.073211 -190.090033)
			(xy 27.934494 -190.066462) (xy 27.797316 -190.035151) (xy 27.66211 -189.996197) (xy 27.5293 -189.949723)
			(xy 27.399305 -189.895876) (xy 27.272534 -189.834824) (xy 27.149386 -189.766761) (xy 27.030248 -189.691899)
			(xy 26.915494 -189.610476) (xy 26.805487 -189.522746) (xy 26.700572 -189.428986) (xy 26.601078 -189.329491)
			(xy 26.507321 -189.224573) (xy 26.419593 -189.114564) (xy 26.338172 -188.999809) (xy 26.263313 -188.880669)
			(xy 26.195252 -188.757519) (xy 26.134203 -188.630747) (xy 26.080358 -188.500751) (xy 26.033887 -188.367941)
			(xy 25.994936 -188.232734) (xy 25.963628 -188.095555) (xy 25.94006 -187.956837) (xy 25.924307 -187.817016)
			(xy 25.916419 -187.676531) (xy 25.915874 -187.606178) (xy 25.915874 -163.299902) (xy 25.915393 -163.229997)
			(xy 25.907553 -163.090407) (xy 25.8919 -162.951476) (xy 25.868481 -162.813642) (xy 25.83737 -162.677337)
			(xy 25.798666 -162.542992) (xy 25.752489 -162.411028) (xy 25.698986 -162.28186) (xy 25.638325 -162.155896)
			(xy 25.570696 -162.033531) (xy 25.496312 -161.915151) (xy 25.415408 -161.801128) (xy 25.328237 -161.69182)
			(xy 25.235075 -161.587572) (xy 25.136214 -161.488712) (xy 25.031966 -161.395551) (xy 24.922658 -161.308381)
			(xy 24.808634 -161.227478) (xy 24.690253 -161.153095) (xy 24.567888 -161.085467) (xy 24.441923 -161.024807)
			(xy 24.312756 -160.971304) (xy 24.180791 -160.925129) (xy 24.046445 -160.886426) (xy 23.91014 -160.855316)
			(xy 23.772306 -160.831898) (xy 23.633375 -160.816245) (xy 23.493785 -160.808407) (xy 23.42388 -160.807908)
			(xy 1.999996 -160.807908) (xy 1.944189 -160.80843) (xy 1.832887 -160.816771) (xy 1.72252 -160.833407)
			(xy 1.613705 -160.858243) (xy 1.50705 -160.891142) (xy 1.403152 -160.93192) (xy 1.302591 -160.980347)
			(xy 1.205931 -161.036154) (xy 1.113712 -161.099029) (xy 1.026449 -161.168619) (xy 0.94463 -161.244536)
			(xy 0.868714 -161.326355) (xy 0.799124 -161.413618) (xy 0.73625 -161.505838) (xy 0.680444 -161.602499)
			(xy 0.632016 -161.703059) (xy 0.59124 -161.806958) (xy 0.558341 -161.913613) (xy 0.533505 -162.022428)
			(xy 0.51687 -162.132795) (xy 0.50853 -162.244097) (xy 0.508 -162.299904) (xy 0.508 -194.670734) (xy 2.904225 -194.670734)
			(xy 2.904225 -194.541594) (xy 2.912175 -194.412699) (xy 2.928045 -194.284539) (xy 2.951774 -194.157598)
			(xy 2.983273 -194.032359) (xy 3.022422 -193.909296) (xy 3.069073 -193.788877) (xy 3.123048 -193.671558)
			(xy 3.184143 -193.557784) (xy 3.252126 -193.447987) (xy 3.32674 -193.342584) (xy 3.407701 -193.241974)
			(xy 3.494701 -193.146539) (xy 3.587412 -193.05664) (xy 3.685482 -192.972619) (xy 3.788537 -192.894795)
			(xy 3.896188 -192.823463) (xy 4.008027 -192.758893) (xy 4.123628 -192.701331) (xy 4.242553 -192.650994)
			(xy 4.364352 -192.608074) (xy 4.488562 -192.572733) (xy 4.614711 -192.545106) (xy 4.742323 -192.525297)
			(xy 4.870912 -192.513381) (xy 4.99999 -192.509405) (xy 5.129068 -192.513381) (xy 5.257657 -192.525297)
			(xy 5.385269 -192.545106) (xy 5.511418 -192.572733) (xy 5.635628 -192.608074) (xy 5.757427 -192.650994)
			(xy 5.876352 -192.701331) (xy 5.991953 -192.758893) (xy 6.103792 -192.823463) (xy 6.211443 -192.894795)
			(xy 6.314498 -192.972619) (xy 6.412568 -193.05664) (xy 6.505279 -193.146539) (xy 6.592279 -193.241974)
			(xy 6.67324 -193.342584) (xy 6.747854 -193.447987) (xy 6.815837 -193.557784) (xy 6.876932 -193.671558)
			(xy 6.930907 -193.788877) (xy 6.977558 -193.909296) (xy 7.016707 -194.032359) (xy 7.048206 -194.157598)
			(xy 7.071935 -194.284539) (xy 7.087805 -194.412699) (xy 7.095755 -194.541594) (xy 7.096252 -194.606164)
			(xy 7.095755 -194.670734) (xy 468.904309 -194.670734) (xy 468.904309 -194.541594) (xy 468.912259 -194.412699)
			(xy 468.928129 -194.284539) (xy 468.951858 -194.157598) (xy 468.983357 -194.032359) (xy 469.022506 -193.909296)
			(xy 469.069157 -193.788877) (xy 469.123132 -193.671558) (xy 469.184227 -193.557784) (xy 469.25221 -193.447987)
			(xy 469.326824 -193.342584) (xy 469.407785 -193.241974) (xy 469.494785 -193.146539) (xy 469.587496 -193.05664)
			(xy 469.685566 -192.972619) (xy 469.788621 -192.894795) (xy 469.896272 -192.823463) (xy 470.008111 -192.758893)
			(xy 470.123712 -192.701331) (xy 470.242637 -192.650994) (xy 470.364436 -192.608074) (xy 470.488646 -192.572733)
			(xy 470.614795 -192.545106) (xy 470.742407 -192.525297) (xy 470.870996 -192.513381) (xy 471.000074 -192.509405)
			(xy 471.129152 -192.513381) (xy 471.257741 -192.525297) (xy 471.385353 -192.545106) (xy 471.511502 -192.572733)
			(xy 471.635712 -192.608074) (xy 471.757511 -192.650994) (xy 471.876436 -192.701331) (xy 471.992037 -192.758893)
			(xy 472.103876 -192.823463) (xy 472.211527 -192.894795) (xy 472.314582 -192.972619) (xy 472.412652 -193.05664)
			(xy 472.505363 -193.146539) (xy 472.592363 -193.241974) (xy 472.673324 -193.342584) (xy 472.747938 -193.447987)
			(xy 472.815921 -193.557784) (xy 472.877016 -193.671558) (xy 472.930991 -193.788877) (xy 472.977642 -193.909296)
			(xy 473.016791 -194.032359) (xy 473.04829 -194.157598) (xy 473.072019 -194.284539) (xy 473.087889 -194.412699)
			(xy 473.095839 -194.541594) (xy 473.096336 -194.606164) (xy 473.095839 -194.670734) (xy 473.087889 -194.799629)
			(xy 473.072019 -194.927789) (xy 473.04829 -195.05473) (xy 473.016791 -195.179969) (xy 472.977642 -195.303032)
			(xy 472.930991 -195.423451) (xy 472.877016 -195.54077) (xy 472.815921 -195.654544) (xy 472.747938 -195.764341)
			(xy 472.673324 -195.869744) (xy 472.592363 -195.970354) (xy 472.505363 -196.065789) (xy 472.412652 -196.155688)
			(xy 472.314582 -196.239709) (xy 472.211527 -196.317533) (xy 472.103876 -196.388865) (xy 471.992037 -196.453435)
			(xy 471.876436 -196.510997) (xy 471.757511 -196.561334) (xy 471.635712 -196.604254) (xy 471.511502 -196.639595)
			(xy 471.385353 -196.667222) (xy 471.257741 -196.687031) (xy 471.129152 -196.698947) (xy 471.000074 -196.702924)
			(xy 470.870996 -196.698947) (xy 470.742407 -196.687031) (xy 470.614795 -196.667222) (xy 470.488646 -196.639595)
			(xy 470.364436 -196.604254) (xy 470.242637 -196.561334) (xy 470.123712 -196.510997) (xy 470.008111 -196.453435)
			(xy 469.896272 -196.388865) (xy 469.788621 -196.317533) (xy 469.685566 -196.239709) (xy 469.587496 -196.155688)
			(xy 469.494785 -196.065789) (xy 469.407785 -195.970354) (xy 469.326824 -195.869744) (xy 469.25221 -195.764341)
			(xy 469.184227 -195.654544) (xy 469.123132 -195.54077) (xy 469.069157 -195.423451) (xy 469.022506 -195.303032)
			(xy 468.983357 -195.179969) (xy 468.951858 -195.05473) (xy 468.928129 -194.927789) (xy 468.912259 -194.799629)
			(xy 468.904309 -194.670734) (xy 7.095755 -194.670734) (xy 7.087805 -194.799629) (xy 7.071935 -194.927789)
			(xy 7.048206 -195.05473) (xy 7.016707 -195.179969) (xy 6.977558 -195.303032) (xy 6.930907 -195.423451)
			(xy 6.876932 -195.54077) (xy 6.815837 -195.654544) (xy 6.747854 -195.764341) (xy 6.67324 -195.869744)
			(xy 6.592279 -195.970354) (xy 6.505279 -196.065789) (xy 6.412568 -196.155688) (xy 6.314498 -196.239709)
			(xy 6.211443 -196.317533) (xy 6.103792 -196.388865) (xy 5.991953 -196.453435) (xy 5.876352 -196.510997)
			(xy 5.757427 -196.561334) (xy 5.635628 -196.604254) (xy 5.511418 -196.639595) (xy 5.385269 -196.667222)
			(xy 5.257657 -196.687031) (xy 5.129068 -196.698947) (xy 4.99999 -196.702924) (xy 4.870912 -196.698947)
			(xy 4.742323 -196.687031) (xy 4.614711 -196.667222) (xy 4.488562 -196.639595) (xy 4.364352 -196.604254)
			(xy 4.242553 -196.561334) (xy 4.123628 -196.510997) (xy 4.008027 -196.453435) (xy 3.896188 -196.388865)
			(xy 3.788537 -196.317533) (xy 3.685482 -196.239709) (xy 3.587412 -196.155688) (xy 3.494701 -196.065789)
			(xy 3.407701 -195.970354) (xy 3.32674 -195.869744) (xy 3.252126 -195.764341) (xy 3.184143 -195.654544)
			(xy 3.123048 -195.54077) (xy 3.069073 -195.423451) (xy 3.022422 -195.303032) (xy 2.983273 -195.179969)
			(xy 2.951774 -195.05473) (xy 2.928045 -194.927789) (xy 2.912175 -194.799629) (xy 2.904225 -194.670734)
			(xy 0.508 -194.670734) (xy 0.508 -197.606158) (xy 0.508522 -197.661965) (xy 0.516863 -197.773267)
			(xy 0.533498 -197.883634) (xy 0.558335 -197.99245) (xy 0.591234 -198.099105) (xy 0.632011 -198.203004)
			(xy 0.680438 -198.303564) (xy 0.736246 -198.400225) (xy 0.79912 -198.492445) (xy 0.86871 -198.579708)
			(xy 0.944627 -198.661527) (xy 1.026446 -198.737444) (xy 1.113709 -198.807034) (xy 1.205929 -198.869908)
			(xy 1.30259 -198.925716) (xy 1.40315 -198.974143) (xy 1.507049 -199.01492) (xy 1.613704 -199.047819)
			(xy 1.72252 -199.072656) (xy 1.832887 -199.089291) (xy 1.944189 -199.097632) (xy 1.999996 -199.098154)
		)
		(stroke
			(width 0)
			(type solid)
		)
		(fill yes)
		(layer "In8.Cu")
		(net "GND3")
	)
	(gr_poly
		(pts
			(xy 75.000104 -171.140882) (xy 75.095437 -171.140376) (xy 75.285932 -171.132284) (xy 75.475912 -171.116114)
			(xy 75.665035 -171.091896) (xy 75.852959 -171.059673) (xy 76.039346 -171.019503) (xy 76.223861 -170.971459)
			(xy 76.40617 -170.915628) (xy 76.585945 -170.852109) (xy 76.762863 -170.781017) (xy 76.936604 -170.702482)
			(xy 77.106855 -170.616643) (xy 77.27331 -170.523655) (xy 77.435668 -170.423687) (xy 77.593638 -170.316919)
			(xy 77.746933 -170.203542) (xy 77.895279 -170.083761) (xy 78.038407 -169.957793) (xy 78.17606 -169.825863)
			(xy 78.30799 -169.68821) (xy 78.433959 -169.545082) (xy 78.55374 -169.396736) (xy 78.667117 -169.243441)
			(xy 78.773885 -169.085472) (xy 78.873853 -168.923113) (xy 78.966841 -168.756659) (xy 79.05268 -168.586408)
			(xy 79.131216 -168.412667) (xy 79.202307 -168.235749) (xy 79.265826 -168.055974) (xy 79.321658 -167.873665)
			(xy 79.369702 -167.68915) (xy 79.409872 -167.502763) (xy 79.442095 -167.314839) (xy 79.466314 -167.125716)
			(xy 79.482484 -166.935736) (xy 79.490576 -166.745241) (xy 79.491078 -166.649908) (xy 79.491078 -161.28111)
			(xy 79.497763 -161.194561) (xy 79.518105 -161.022146) (xy 79.546364 -160.850851) (xy 79.582482 -160.681039)
			(xy 79.626381 -160.51307) (xy 79.677968 -160.347301) (xy 79.737135 -160.184083) (xy 79.803755 -160.023764)
			(xy 79.877687 -159.866682) (xy 79.958774 -159.713171) (xy 80.046845 -159.563557) (xy 80.141711 -159.418158)
			(xy 80.243173 -159.277281) (xy 80.351014 -159.141227) (xy 80.465007 -159.010282) (xy 80.584908 -158.884726)
			(xy 80.710464 -158.764825) (xy 80.841408 -158.650833) (xy 80.977463 -158.542992) (xy 81.11834 -158.44153)
			(xy 81.263739 -158.346663) (xy 81.413353 -158.258593) (xy 81.566864 -158.177506) (xy 81.723946 -158.103574)
			(xy 81.884265 -158.036954) (xy 82.047483 -157.977788) (xy 82.213252 -157.9262) (xy 82.381221 -157.882301)
			(xy 82.551033 -157.846184) (xy 82.722328 -157.817924) (xy 82.894743 -157.797583) (xy 82.981292 -157.790896)
			(xy 83.49996 -157.790896) (xy 83.595294 -157.790398) (xy 83.785791 -157.782307) (xy 83.975773 -157.766139)
			(xy 84.164897 -157.741923) (xy 84.352823 -157.709701) (xy 84.539213 -157.669533) (xy 84.723729 -157.62149)
			(xy 84.90604 -157.565659) (xy 85.085818 -157.502142) (xy 85.262738 -157.431051) (xy 85.436481 -157.352516)
			(xy 85.606734 -157.266677) (xy 85.773191 -157.173691) (xy 85.935552 -157.073723) (xy 86.093523 -156.966955)
			(xy 86.246821 -156.853578) (xy 86.395169 -156.733797) (xy 86.538299 -156.607828) (xy 86.675955 -156.475898)
			(xy 86.807886 -156.338245) (xy 86.933857 -156.195116) (xy 87.05364 -156.04677) (xy 87.167019 -155.893474)
			(xy 87.273789 -155.735504) (xy 87.373759 -155.573145) (xy 87.466748 -155.406689) (xy 87.552589 -155.236437)
			(xy 87.631127 -155.062695) (xy 87.70222 -154.885776) (xy 87.76574 -154.705999) (xy 87.821573 -154.523689)
			(xy 87.869618 -154.339173) (xy 87.909789 -154.152784) (xy 87.942013 -153.964858) (xy 87.966233 -153.775734)
			(xy 87.982404 -153.585753) (xy 87.990497 -153.395256) (xy 87.990934 -153.299922) (xy 87.990934 -110.499906)
			(xy 87.991432 -110.374101) (xy 87.999343 -110.122617) (xy 88.015149 -109.871504) (xy 88.038834 -109.621013)
			(xy 88.070376 -109.371388) (xy 88.109743 -109.122878) (xy 88.156896 -108.875727) (xy 88.211788 -108.630178)
			(xy 88.274366 -108.386475) (xy 88.344568 -108.144858) (xy 88.422324 -107.905565) (xy 88.507557 -107.668832)
			(xy 88.600185 -107.434893) (xy 88.700114 -107.203979) (xy 88.807248 -106.976318) (xy 88.921479 -106.752134)
			(xy 89.042695 -106.531649) (xy 89.170776 -106.315079) (xy 89.305597 -106.10264) (xy 89.447024 -105.89454)
			(xy 89.594918 -105.690985) (xy 89.749132 -105.492175) (xy 89.909514 -105.298308) (xy 90.075907 -105.109574)
			(xy 90.248145 -104.926159) (xy 90.42606 -104.748244) (xy 90.609475 -104.576006) (xy 90.798209 -104.409613)
			(xy 90.992077 -104.249231) (xy 91.190887 -104.095017) (xy 91.394442 -103.947123) (xy 91.602542 -103.805696)
			(xy 91.814981 -103.670875) (xy 92.03155 -103.542794) (xy 92.252036 -103.421578) (xy 92.47622 -103.307347)
			(xy 92.703881 -103.200214) (xy 92.934795 -103.100284) (xy 93.168734 -103.007657) (xy 93.405467 -102.922423)
			(xy 93.64476 -102.844667) (xy 93.886377 -102.774465) (xy 94.13008 -102.711888) (xy 94.375628 -102.656995)
			(xy 94.62278 -102.609842) (xy 94.87129 -102.570476) (xy 95.120915 -102.538934) (xy 95.371406 -102.515249)
			(xy 95.622519 -102.499443) (xy 95.874003 -102.491532) (xy 95.999808 -102.491032) (xy 318.10579 -102.491032)
			(xy 318.106806 -102.492048) (xy 319.051686 -102.492048) (xy 319.052702 -102.491032) (xy 344.000074 -102.491032)
			(xy 344.12588 -102.491521) (xy 344.377368 -102.499423) (xy 344.628483 -102.515221) (xy 344.878979 -102.538899)
			(xy 345.128607 -102.570434) (xy 345.377121 -102.609794) (xy 345.624276 -102.656941) (xy 345.869829 -102.711827)
			(xy 346.113536 -102.7744) (xy 346.355158 -102.844597) (xy 346.594455 -102.922349) (xy 346.831192 -103.007579)
			(xy 347.065135 -103.100203) (xy 347.296054 -103.20013) (xy 347.523719 -103.30726) (xy 347.747907 -103.421489)
			(xy 347.968397 -103.542704) (xy 348.18497 -103.670784) (xy 348.397413 -103.805604) (xy 348.605517 -103.947031)
			(xy 348.809076 -104.094924) (xy 349.007888 -104.249139) (xy 349.201759 -104.409522) (xy 349.36105 -104.549956)
			(xy 422.484046 -104.549956) (xy 422.488076 -104.407621) (xy 422.500151 -104.265741) (xy 422.520234 -104.124773)
			(xy 422.548261 -103.985166) (xy 422.584141 -103.847368) (xy 422.627759 -103.711821) (xy 422.678976 -103.578959)
			(xy 422.737627 -103.449207) (xy 422.803525 -103.322981) (xy 422.876459 -103.200685) (xy 422.956196 -103.082712)
			(xy 423.042478 -102.969439) (xy 423.135031 -102.861228) (xy 423.233558 -102.758427) (xy 423.337743 -102.661365)
			(xy 423.447252 -102.570353) (xy 423.561735 -102.485681) (xy 423.680825 -102.407623) (xy 423.80414 -102.336427)
			(xy 423.931286 -102.272321) (xy 424.061855 -102.215512) (xy 424.195429 -102.16618) (xy 424.33158 -102.124484)
			(xy 424.469871 -102.090558) (xy 424.609861 -102.06451) (xy 424.7511 -102.046424) (xy 424.893136 -102.036357)
			(xy 425.035514 -102.034342) (xy 425.177778 -102.040385) (xy 425.319472 -102.054467) (xy 425.460142 -102.076543)
			(xy 425.599339 -102.106543) (xy 425.736615 -102.144369) (xy 425.871531 -102.189901) (xy 426.003655 -102.242992)
			(xy 426.132564 -102.303474) (xy 426.257845 -102.371152) (xy 426.379096 -102.445809) (xy 426.495929 -102.527207)
			(xy 426.60797 -102.615084) (xy 426.71486 -102.709159) (xy 426.816257 -102.809131) (xy 426.911835 -102.914679)
			(xy 427.001289 -103.025465) (xy 427.084331 -103.141134) (xy 427.160697 -103.261317) (xy 427.230141 -103.385627)
			(xy 427.292441 -103.513668) (xy 427.347397 -103.645027) (xy 427.394834 -103.779286) (xy 427.434598 -103.916013)
			(xy 427.466564 -104.054771) (xy 427.490629 -104.195115) (xy 427.506715 -104.336596) (xy 427.51477 -104.47876)
			(xy 427.515274 -104.549956) (xy 427.51477 -104.621152) (xy 427.506715 -104.763316) (xy 427.490629 -104.904797)
			(xy 427.466564 -105.045141) (xy 427.434598 -105.183899) (xy 427.394834 -105.320626) (xy 427.347397 -105.454885)
			(xy 427.292441 -105.586244) (xy 427.230141 -105.714285) (xy 427.160697 -105.838595) (xy 427.084331 -105.958778)
			(xy 427.001289 -106.074447) (xy 426.911835 -106.185233) (xy 426.816257 -106.290781) (xy 426.71486 -106.390753)
			(xy 426.60797 -106.484828) (xy 426.495929 -106.572705) (xy 426.379096 -106.654103) (xy 426.257845 -106.72876)
			(xy 426.132564 -106.796438) (xy 426.003655 -106.85692) (xy 425.871531 -106.910011) (xy 425.736615 -106.955543)
			(xy 425.599339 -106.993369) (xy 425.460142 -107.023369) (xy 425.319472 -107.045445) (xy 425.177778 -107.059527)
			(xy 425.035514 -107.06557) (xy 424.893136 -107.063555) (xy 424.7511 -107.053488) (xy 424.609861 -107.035402)
			(xy 424.469871 -107.009354) (xy 424.33158 -106.975428) (xy 424.195429 -106.933732) (xy 424.061855 -106.8844)
			(xy 423.931286 -106.827591) (xy 423.80414 -106.763485) (xy 423.680825 -106.692289) (xy 423.561735 -106.614231)
			(xy 423.447252 -106.529559) (xy 423.337743 -106.438547) (xy 423.233558 -106.341485) (xy 423.135031 -106.238684)
			(xy 423.042478 -106.130473) (xy 422.956196 -106.0172) (xy 422.876459 -105.899227) (xy 422.803525 -105.776931)
			(xy 422.737627 -105.650705) (xy 422.678976 -105.520953) (xy 422.627759 -105.388091) (xy 422.584141 -105.252544)
			(xy 422.548261 -105.114746) (xy 422.520234 -104.975139) (xy 422.500151 -104.834171) (xy 422.488076 -104.692291)
			(xy 422.484046 -104.549956) (xy 349.36105 -104.549956) (xy 349.390496 -104.575916) (xy 349.573914 -104.748156)
			(xy 349.75183 -104.926072) (xy 349.924071 -105.109489) (xy 350.090465 -105.298226) (xy 350.250849 -105.492096)
			(xy 350.405064 -105.690908) (xy 350.552958 -105.894467) (xy 350.694385 -106.10257) (xy 350.829205 -106.315013)
			(xy 350.957286 -106.531586) (xy 351.078501 -106.752075) (xy 351.192731 -106.976263) (xy 351.299862 -107.203928)
			(xy 351.399789 -107.434846) (xy 351.492414 -107.668789) (xy 351.577645 -107.905526) (xy 351.655397 -108.144823)
			(xy 351.725595 -108.386444) (xy 351.788168 -108.630152) (xy 351.843055 -108.875704) (xy 351.890203 -109.122859)
			(xy 351.929563 -109.371373) (xy 351.961098 -109.621001) (xy 351.984777 -109.871497) (xy 352.000576 -110.122612)
			(xy 352.008479 -110.3741) (xy 352.008948 -110.499906) (xy 352.008948 -111.879888) (xy 377.061232 -111.879888)
			(xy 377.065214 -111.789938) (xy 377.077131 -111.700691) (xy 377.096889 -111.612847) (xy 377.124333 -111.527093)
			(xy 377.159249 -111.4441) (xy 377.201363 -111.364518) (xy 377.250346 -111.288969) (xy 377.305814 -111.218045)
			(xy 377.367334 -111.1523) (xy 377.434423 -111.09225) (xy 377.506557 -111.038365) (xy 377.583171 -110.991065)
			(xy 377.663665 -110.950722) (xy 377.74741 -110.91765) (xy 377.833751 -110.89211) (xy 377.92201 -110.8743)
			(xy 378.011499 -110.86436) (xy 378.101515 -110.862369) (xy 378.191356 -110.86834) (xy 378.280317 -110.882229)
			(xy 378.367702 -110.903925) (xy 378.452828 -110.93326) (xy 378.535028 -110.970003) (xy 378.613659 -111.013867)
			(xy 378.688106 -111.064509) (xy 378.757786 -111.121533) (xy 378.822153 -111.184492) (xy 378.880704 -111.252893)
			(xy 378.932981 -111.326201) (xy 378.978574 -111.403843) (xy 379.017127 -111.48521) (xy 379.048338 -111.569666)
			(xy 379.071962 -111.65655) (xy 379.087815 -111.745182) (xy 379.095772 -111.834869) (xy 379.09627 -111.879888)
			(xy 396.619232 -111.879888) (xy 396.623214 -111.789938) (xy 396.635131 -111.700691) (xy 396.654889 -111.612847)
			(xy 396.682333 -111.527093) (xy 396.717249 -111.4441) (xy 396.759363 -111.364518) (xy 396.808346 -111.288969)
			(xy 396.863814 -111.218045) (xy 396.925334 -111.1523) (xy 396.992423 -111.09225) (xy 397.064557 -111.038365)
			(xy 397.141171 -110.991065) (xy 397.221665 -110.950722) (xy 397.30541 -110.91765) (xy 397.391751 -110.89211)
			(xy 397.48001 -110.8743) (xy 397.569499 -110.86436) (xy 397.659515 -110.862369) (xy 397.749356 -110.86834)
			(xy 397.838317 -110.882229) (xy 397.925702 -110.903925) (xy 398.010828 -110.93326) (xy 398.093028 -110.970003)
			(xy 398.171659 -111.013867) (xy 398.246106 -111.064509) (xy 398.315786 -111.121533) (xy 398.380153 -111.184492)
			(xy 398.438704 -111.252893) (xy 398.490981 -111.326201) (xy 398.536574 -111.403843) (xy 398.575127 -111.48521)
			(xy 398.606338 -111.569666) (xy 398.629962 -111.65655) (xy 398.645815 -111.745182) (xy 398.653772 -111.834869)
			(xy 398.65427 -111.879888) (xy 398.653772 -111.924907) (xy 398.645815 -112.014594) (xy 398.629962 -112.103226)
			(xy 398.606338 -112.19011) (xy 398.575127 -112.274566) (xy 398.536574 -112.355933) (xy 398.490981 -112.433575)
			(xy 398.438704 -112.506883) (xy 398.380153 -112.575284) (xy 398.315786 -112.638243) (xy 398.246106 -112.695267)
			(xy 398.171659 -112.745909) (xy 398.093028 -112.789773) (xy 398.010828 -112.826516) (xy 397.925702 -112.855851)
			(xy 397.838317 -112.877547) (xy 397.749356 -112.891436) (xy 397.659515 -112.897407) (xy 397.569499 -112.895416)
			(xy 397.48001 -112.885476) (xy 397.391751 -112.867666) (xy 397.30541 -112.842126) (xy 397.221665 -112.809054)
			(xy 397.141171 -112.768711) (xy 397.064557 -112.721411) (xy 396.992423 -112.667526) (xy 396.925334 -112.607476)
			(xy 396.863814 -112.541731) (xy 396.808346 -112.470807) (xy 396.759363 -112.395258) (xy 396.717249 -112.315676)
			(xy 396.682333 -112.232683) (xy 396.654889 -112.146929) (xy 396.635131 -112.059085) (xy 396.623214 -111.969838)
			(xy 396.619232 -111.879888) (xy 379.09627 -111.879888) (xy 379.095772 -111.924907) (xy 379.087815 -112.014594)
			(xy 379.071962 -112.103226) (xy 379.048338 -112.19011) (xy 379.017127 -112.274566) (xy 378.978574 -112.355933)
			(xy 378.932981 -112.433575) (xy 378.880704 -112.506883) (xy 378.822153 -112.575284) (xy 378.757786 -112.638243)
			(xy 378.688106 -112.695267) (xy 378.613659 -112.745909) (xy 378.535028 -112.789773) (xy 378.452828 -112.826516)
			(xy 378.367702 -112.855851) (xy 378.280317 -112.877547) (xy 378.191356 -112.891436) (xy 378.101515 -112.897407)
			(xy 378.011499 -112.895416) (xy 377.92201 -112.885476) (xy 377.833751 -112.867666) (xy 377.74741 -112.842126)
			(xy 377.663665 -112.809054) (xy 377.583171 -112.768711) (xy 377.506557 -112.721411) (xy 377.434423 -112.667526)
			(xy 377.367334 -112.607476) (xy 377.305814 -112.541731) (xy 377.250346 -112.470807) (xy 377.201363 -112.395258)
			(xy 377.159249 -112.315676) (xy 377.124333 -112.232683) (xy 377.096889 -112.146929) (xy 377.077131 -112.059085)
			(xy 377.065214 -111.969838) (xy 377.061232 -111.879888) (xy 352.008948 -111.879888) (xy 352.008948 -119.38)
			(xy 376.553741 -119.38) (xy 376.557716 -119.269941) (xy 376.569624 -119.160455) (xy 376.5894 -119.052114)
			(xy 376.616943 -118.945483) (xy 376.652108 -118.841117) (xy 376.694712 -118.73956) (xy 376.744533 -118.641343)
			(xy 376.801312 -118.546976) (xy 376.864751 -118.456952) (xy 376.934522 -118.371741) (xy 377.010259 -118.291786)
			(xy 377.091568 -118.217505) (xy 377.178025 -118.149285) (xy 377.269179 -118.08748) (xy 377.364556 -118.032415)
			(xy 377.463657 -117.984375) (xy 377.565966 -117.943611) (xy 377.67095 -117.910336) (xy 377.778061 -117.884723)
			(xy 377.886741 -117.866906) (xy 377.996424 -117.856977) (xy 378.106537 -117.854989) (xy 378.216507 -117.860951)
			(xy 378.32576 -117.874833) (xy 378.433726 -117.896563) (xy 378.539843 -117.926026) (xy 378.643557 -117.963069)
			(xy 378.744328 -118.0075) (xy 378.84163 -118.059087) (xy 378.934956 -118.117559) (xy 379.023819 -118.182614)
			(xy 379.107757 -118.253912) (xy 379.186332 -118.33108) (xy 379.259133 -118.413717) (xy 379.325781 -118.501391)
			(xy 379.38593 -118.593647) (xy 379.439264 -118.690002) (xy 379.485507 -118.789954) (xy 379.524417 -118.892982)
			(xy 379.555791 -118.99855) (xy 379.579466 -119.106106) (xy 379.595318 -119.21509) (xy 379.603265 -119.324934)
			(xy 379.603762 -119.38) (xy 396.111741 -119.38) (xy 396.115716 -119.269941) (xy 396.127624 -119.160455)
			(xy 396.1474 -119.052114) (xy 396.174943 -118.945483) (xy 396.210108 -118.841117) (xy 396.252712 -118.73956)
			(xy 396.302533 -118.641343) (xy 396.359312 -118.546976) (xy 396.422751 -118.456952) (xy 396.492522 -118.371741)
			(xy 396.568259 -118.291786) (xy 396.649568 -118.217505) (xy 396.736025 -118.149285) (xy 396.827179 -118.08748)
			(xy 396.922556 -118.032415) (xy 397.021657 -117.984375) (xy 397.123966 -117.943611) (xy 397.22895 -117.910336)
			(xy 397.336061 -117.884723) (xy 397.444741 -117.866906) (xy 397.554424 -117.856977) (xy 397.664537 -117.854989)
			(xy 397.774507 -117.860951) (xy 397.88376 -117.874833) (xy 397.991726 -117.896563) (xy 398.097843 -117.926026)
			(xy 398.201557 -117.963069) (xy 398.302328 -118.0075) (xy 398.39963 -118.059087) (xy 398.492956 -118.117559)
			(xy 398.581819 -118.182614) (xy 398.665757 -118.253912) (xy 398.744332 -118.33108) (xy 398.817133 -118.413717)
			(xy 398.883781 -118.501391) (xy 398.94393 -118.593647) (xy 398.997264 -118.690002) (xy 399.043507 -118.789954)
			(xy 399.082417 -118.892982) (xy 399.113791 -118.99855) (xy 399.137466 -119.106106) (xy 399.153318 -119.21509)
			(xy 399.161265 -119.324934) (xy 399.161762 -119.38) (xy 399.161265 -119.435066) (xy 399.153318 -119.54491)
			(xy 399.137466 -119.653894) (xy 399.113791 -119.76145) (xy 399.082417 -119.867018) (xy 399.043507 -119.970046)
			(xy 398.997264 -120.069998) (xy 398.94393 -120.166353) (xy 398.883781 -120.258609) (xy 398.817133 -120.346283)
			(xy 398.744332 -120.42892) (xy 398.665757 -120.506088) (xy 398.581819 -120.577386) (xy 398.492956 -120.642441)
			(xy 398.39963 -120.700913) (xy 398.302328 -120.7525) (xy 398.201557 -120.796931) (xy 398.097843 -120.833974)
			(xy 397.991726 -120.863437) (xy 397.88376 -120.885167) (xy 397.774507 -120.899049) (xy 397.664537 -120.905011)
			(xy 397.554424 -120.903023) (xy 397.444741 -120.893094) (xy 397.336061 -120.875277) (xy 397.22895 -120.849664)
			(xy 397.123966 -120.816389) (xy 397.021657 -120.775625) (xy 396.922556 -120.727585) (xy 396.827179 -120.67252)
			(xy 396.736025 -120.610715) (xy 396.649568 -120.542495) (xy 396.568259 -120.468214) (xy 396.492522 -120.388259)
			(xy 396.422751 -120.303048) (xy 396.359312 -120.213024) (xy 396.302533 -120.118657) (xy 396.252712 -120.02044)
			(xy 396.210108 -119.918883) (xy 396.174943 -119.814517) (xy 396.1474 -119.707886) (xy 396.127624 -119.599545)
			(xy 396.115716 -119.490059) (xy 396.111741 -119.38) (xy 379.603762 -119.38) (xy 379.603265 -119.435066)
			(xy 379.595318 -119.54491) (xy 379.579466 -119.653894) (xy 379.555791 -119.76145) (xy 379.524417 -119.867018)
			(xy 379.485507 -119.970046) (xy 379.439264 -120.069998) (xy 379.38593 -120.166353) (xy 379.325781 -120.258609)
			(xy 379.259133 -120.346283) (xy 379.186332 -120.42892) (xy 379.107757 -120.506088) (xy 379.023819 -120.577386)
			(xy 378.934956 -120.642441) (xy 378.84163 -120.700913) (xy 378.744328 -120.7525) (xy 378.643557 -120.796931)
			(xy 378.539843 -120.833974) (xy 378.433726 -120.863437) (xy 378.32576 -120.885167) (xy 378.216507 -120.899049)
			(xy 378.106537 -120.905011) (xy 377.996424 -120.903023) (xy 377.886741 -120.893094) (xy 377.778061 -120.875277)
			(xy 377.67095 -120.849664) (xy 377.565966 -120.816389) (xy 377.463657 -120.775625) (xy 377.364556 -120.727585)
			(xy 377.269179 -120.67252) (xy 377.178025 -120.610715) (xy 377.091568 -120.542495) (xy 377.010259 -120.468214)
			(xy 376.934522 -120.388259) (xy 376.864751 -120.303048) (xy 376.801312 -120.213024) (xy 376.744533 -120.118657)
			(xy 376.694712 -120.02044) (xy 376.652108 -119.918883) (xy 376.616943 -119.814517) (xy 376.5894 -119.707886)
			(xy 376.569624 -119.599545) (xy 376.557716 -119.490059) (xy 376.553741 -119.38) (xy 352.008948 -119.38)
			(xy 352.008948 -132.199888) (xy 377.061232 -132.199888) (xy 377.065214 -132.109938) (xy 377.077131 -132.020691)
			(xy 377.096889 -131.932847) (xy 377.124333 -131.847093) (xy 377.159249 -131.7641) (xy 377.201363 -131.684518)
			(xy 377.250346 -131.608969) (xy 377.305814 -131.538045) (xy 377.367334 -131.4723) (xy 377.434423 -131.41225)
			(xy 377.506557 -131.358365) (xy 377.583171 -131.311065) (xy 377.663665 -131.270722) (xy 377.74741 -131.23765)
			(xy 377.833751 -131.21211) (xy 377.92201 -131.1943) (xy 378.011499 -131.18436) (xy 378.101515 -131.182369)
			(xy 378.191356 -131.18834) (xy 378.280317 -131.202229) (xy 378.367702 -131.223925) (xy 378.452828 -131.25326)
			(xy 378.535028 -131.290003) (xy 378.613659 -131.333867) (xy 378.688106 -131.384509) (xy 378.757786 -131.441533)
			(xy 378.822153 -131.504492) (xy 378.880704 -131.572893) (xy 378.932981 -131.646201) (xy 378.978574 -131.723843)
			(xy 379.017127 -131.80521) (xy 379.048338 -131.889666) (xy 379.071962 -131.97655) (xy 379.087815 -132.065182)
			(xy 379.095772 -132.154869) (xy 379.09627 -132.199888) (xy 396.619232 -132.199888) (xy 396.623214 -132.109938)
			(xy 396.635131 -132.020691) (xy 396.654889 -131.932847) (xy 396.682333 -131.847093) (xy 396.717249 -131.7641)
			(xy 396.759363 -131.684518) (xy 396.808346 -131.608969) (xy 396.863814 -131.538045) (xy 396.925334 -131.4723)
			(xy 396.992423 -131.41225) (xy 397.064557 -131.358365) (xy 397.141171 -131.311065) (xy 397.221665 -131.270722)
			(xy 397.30541 -131.23765) (xy 397.391751 -131.21211) (xy 397.48001 -131.1943) (xy 397.569499 -131.18436)
			(xy 397.659515 -131.182369) (xy 397.749356 -131.18834) (xy 397.838317 -131.202229) (xy 397.925702 -131.223925)
			(xy 398.010828 -131.25326) (xy 398.093028 -131.290003) (xy 398.171659 -131.333867) (xy 398.246106 -131.384509)
			(xy 398.315786 -131.441533) (xy 398.380153 -131.504492) (xy 398.438704 -131.572893) (xy 398.490981 -131.646201)
			(xy 398.536574 -131.723843) (xy 398.575127 -131.80521) (xy 398.606338 -131.889666) (xy 398.629962 -131.97655)
			(xy 398.645815 -132.065182) (xy 398.653772 -132.154869) (xy 398.65427 -132.199888) (xy 398.653772 -132.244907)
			(xy 398.645815 -132.334594) (xy 398.629962 -132.423226) (xy 398.606338 -132.51011) (xy 398.575127 -132.594566)
			(xy 398.536574 -132.675933) (xy 398.490981 -132.753575) (xy 398.438704 -132.826883) (xy 398.380153 -132.895284)
			(xy 398.315786 -132.958243) (xy 398.246106 -133.015267) (xy 398.171659 -133.065909) (xy 398.093028 -133.109773)
			(xy 398.010828 -133.146516) (xy 397.925702 -133.175851) (xy 397.838317 -133.197547) (xy 397.749356 -133.211436)
			(xy 397.659515 -133.217407) (xy 397.569499 -133.215416) (xy 397.48001 -133.205476) (xy 397.391751 -133.187666)
			(xy 397.30541 -133.162126) (xy 397.221665 -133.129054) (xy 397.141171 -133.088711) (xy 397.064557 -133.041411)
			(xy 396.992423 -132.987526) (xy 396.925334 -132.927476) (xy 396.863814 -132.861731) (xy 396.808346 -132.790807)
			(xy 396.759363 -132.715258) (xy 396.717249 -132.635676) (xy 396.682333 -132.552683) (xy 396.654889 -132.466929)
			(xy 396.635131 -132.379085) (xy 396.623214 -132.289838) (xy 396.619232 -132.199888) (xy 379.09627 -132.199888)
			(xy 379.095772 -132.244907) (xy 379.087815 -132.334594) (xy 379.071962 -132.423226) (xy 379.048338 -132.51011)
			(xy 379.017127 -132.594566) (xy 378.978574 -132.675933) (xy 378.932981 -132.753575) (xy 378.880704 -132.826883)
			(xy 378.822153 -132.895284) (xy 378.757786 -132.958243) (xy 378.688106 -133.015267) (xy 378.613659 -133.065909)
			(xy 378.535028 -133.109773) (xy 378.452828 -133.146516) (xy 378.367702 -133.175851) (xy 378.280317 -133.197547)
			(xy 378.191356 -133.211436) (xy 378.101515 -133.217407) (xy 378.011499 -133.215416) (xy 377.92201 -133.205476)
			(xy 377.833751 -133.187666) (xy 377.74741 -133.162126) (xy 377.663665 -133.129054) (xy 377.583171 -133.088711)
			(xy 377.506557 -133.041411) (xy 377.434423 -132.987526) (xy 377.367334 -132.927476) (xy 377.305814 -132.861731)
			(xy 377.250346 -132.790807) (xy 377.201363 -132.715258) (xy 377.159249 -132.635676) (xy 377.124333 -132.552683)
			(xy 377.096889 -132.466929) (xy 377.077131 -132.379085) (xy 377.065214 -132.289838) (xy 377.061232 -132.199888)
			(xy 352.008948 -132.199888) (xy 352.008948 -139.7) (xy 376.553741 -139.7) (xy 376.557716 -139.589941)
			(xy 376.569624 -139.480455) (xy 376.5894 -139.372114) (xy 376.616943 -139.265483) (xy 376.652108 -139.161117)
			(xy 376.694712 -139.05956) (xy 376.744533 -138.961343) (xy 376.801312 -138.866976) (xy 376.864751 -138.776952)
			(xy 376.934522 -138.691741) (xy 377.010259 -138.611786) (xy 377.091568 -138.537505) (xy 377.178025 -138.469285)
			(xy 377.269179 -138.40748) (xy 377.364556 -138.352415) (xy 377.463657 -138.304375) (xy 377.565966 -138.263611)
			(xy 377.67095 -138.230336) (xy 377.778061 -138.204723) (xy 377.886741 -138.186906) (xy 377.996424 -138.176977)
			(xy 378.106537 -138.174989) (xy 378.216507 -138.180951) (xy 378.32576 -138.194833) (xy 378.433726 -138.216563)
			(xy 378.539843 -138.246026) (xy 378.643557 -138.283069) (xy 378.744328 -138.3275) (xy 378.84163 -138.379087)
			(xy 378.934956 -138.437559) (xy 379.023819 -138.502614) (xy 379.107757 -138.573912) (xy 379.186332 -138.65108)
			(xy 379.259133 -138.733717) (xy 379.325781 -138.821391) (xy 379.38593 -138.913647) (xy 379.439264 -139.010002)
			(xy 379.485507 -139.109954) (xy 379.524417 -139.212982) (xy 379.555791 -139.31855) (xy 379.579466 -139.426106)
			(xy 379.595318 -139.53509) (xy 379.603265 -139.644934) (xy 379.603762 -139.7) (xy 396.111741 -139.7)
			(xy 396.115716 -139.589941) (xy 396.127624 -139.480455) (xy 396.1474 -139.372114) (xy 396.174943 -139.265483)
			(xy 396.210108 -139.161117) (xy 396.252712 -139.05956) (xy 396.302533 -138.961343) (xy 396.359312 -138.866976)
			(xy 396.422751 -138.776952) (xy 396.492522 -138.691741) (xy 396.568259 -138.611786) (xy 396.649568 -138.537505)
			(xy 396.736025 -138.469285) (xy 396.827179 -138.40748) (xy 396.922556 -138.352415) (xy 397.021657 -138.304375)
			(xy 397.123966 -138.263611) (xy 397.22895 -138.230336) (xy 397.336061 -138.204723) (xy 397.444741 -138.186906)
			(xy 397.554424 -138.176977) (xy 397.664537 -138.174989) (xy 397.774507 -138.180951) (xy 397.88376 -138.194833)
			(xy 397.991726 -138.216563) (xy 398.097843 -138.246026) (xy 398.201557 -138.283069) (xy 398.302328 -138.3275)
			(xy 398.39963 -138.379087) (xy 398.492956 -138.437559) (xy 398.581819 -138.502614) (xy 398.665757 -138.573912)
			(xy 398.744332 -138.65108) (xy 398.817133 -138.733717) (xy 398.883781 -138.821391) (xy 398.94393 -138.913647)
			(xy 398.997264 -139.010002) (xy 399.043507 -139.109954) (xy 399.082417 -139.212982) (xy 399.113791 -139.31855)
			(xy 399.137466 -139.426106) (xy 399.153318 -139.53509) (xy 399.161265 -139.644934) (xy 399.161762 -139.7)
			(xy 399.161265 -139.755066) (xy 399.153318 -139.86491) (xy 399.137466 -139.973894) (xy 399.113791 -140.08145)
			(xy 399.082417 -140.187018) (xy 399.043507 -140.290046) (xy 398.997264 -140.389998) (xy 398.94393 -140.486353)
			(xy 398.883781 -140.578609) (xy 398.817133 -140.666283) (xy 398.744332 -140.74892) (xy 398.665757 -140.826088)
			(xy 398.581819 -140.897386) (xy 398.492956 -140.962441) (xy 398.39963 -141.020913) (xy 398.302328 -141.0725)
			(xy 398.201557 -141.116931) (xy 398.097843 -141.153974) (xy 397.991726 -141.183437) (xy 397.88376 -141.205167)
			(xy 397.774507 -141.219049) (xy 397.664537 -141.225011) (xy 397.554424 -141.223023) (xy 397.444741 -141.213094)
			(xy 397.336061 -141.195277) (xy 397.22895 -141.169664) (xy 397.123966 -141.136389) (xy 397.021657 -141.095625)
			(xy 396.922556 -141.047585) (xy 396.827179 -140.99252) (xy 396.736025 -140.930715) (xy 396.649568 -140.862495)
			(xy 396.568259 -140.788214) (xy 396.492522 -140.708259) (xy 396.422751 -140.623048) (xy 396.359312 -140.533024)
			(xy 396.302533 -140.438657) (xy 396.252712 -140.34044) (xy 396.210108 -140.238883) (xy 396.174943 -140.134517)
			(xy 396.1474 -140.027886) (xy 396.127624 -139.919545) (xy 396.115716 -139.810059) (xy 396.111741 -139.7)
			(xy 379.603762 -139.7) (xy 379.603265 -139.755066) (xy 379.595318 -139.86491) (xy 379.579466 -139.973894)
			(xy 379.555791 -140.08145) (xy 379.524417 -140.187018) (xy 379.485507 -140.290046) (xy 379.439264 -140.389998)
			(xy 379.38593 -140.486353) (xy 379.325781 -140.578609) (xy 379.259133 -140.666283) (xy 379.186332 -140.74892)
			(xy 379.107757 -140.826088) (xy 379.023819 -140.897386) (xy 378.934956 -140.962441) (xy 378.84163 -141.020913)
			(xy 378.744328 -141.0725) (xy 378.643557 -141.116931) (xy 378.539843 -141.153974) (xy 378.433726 -141.183437)
			(xy 378.32576 -141.205167) (xy 378.216507 -141.219049) (xy 378.106537 -141.225011) (xy 377.996424 -141.223023)
			(xy 377.886741 -141.213094) (xy 377.778061 -141.195277) (xy 377.67095 -141.169664) (xy 377.565966 -141.136389)
			(xy 377.463657 -141.095625) (xy 377.364556 -141.047585) (xy 377.269179 -140.99252) (xy 377.178025 -140.930715)
			(xy 377.091568 -140.862495) (xy 377.010259 -140.788214) (xy 376.934522 -140.708259) (xy 376.864751 -140.623048)
			(xy 376.801312 -140.533024) (xy 376.744533 -140.438657) (xy 376.694712 -140.34044) (xy 376.652108 -140.238883)
			(xy 376.616943 -140.134517) (xy 376.5894 -140.027886) (xy 376.569624 -139.919545) (xy 376.557716 -139.810059)
			(xy 376.553741 -139.7) (xy 352.008948 -139.7) (xy 352.008948 -153.299922) (xy 352.009454 -153.395255)
			(xy 352.017547 -153.585749) (xy 352.033718 -153.775728) (xy 352.057937 -153.964849) (xy 352.09016 -154.152772)
			(xy 352.130331 -154.339159) (xy 352.178375 -154.523672) (xy 352.234207 -154.70598) (xy 352.297727 -154.885754)
			(xy 352.368818 -155.062671) (xy 352.447355 -155.23641) (xy 352.533194 -155.40666) (xy 352.626182 -155.573114)
			(xy 352.72615 -155.735471) (xy 352.832919 -155.893439) (xy 352.946296 -156.046733) (xy 353.066077 -156.195077)
			(xy 353.192045 -156.338204) (xy 353.323975 -156.475856) (xy 353.461628 -156.607784) (xy 353.604756 -156.733752)
			(xy 353.753102 -156.853531) (xy 353.906397 -156.966907) (xy 354.064366 -157.073674) (xy 354.226724 -157.173641)
			(xy 354.393179 -157.266627) (xy 354.563429 -157.352464) (xy 354.73717 -157.430999) (xy 354.914087 -157.502089)
			(xy 355.093862 -157.565606) (xy 355.27617 -157.621437) (xy 355.460684 -157.66948) (xy 355.647071 -157.709648)
			(xy 355.834994 -157.74187) (xy 356.024116 -157.766087) (xy 356.214095 -157.782255) (xy 356.404589 -157.790347)
			(xy 356.499922 -157.790896) (xy 357.000048 -157.790896) (xy 357.083565 -157.791394) (xy 357.250411 -157.799344)
			(xy 357.416689 -157.815224) (xy 357.582024 -157.838998) (xy 357.746039 -157.870611) (xy 357.908365 -157.909993)
			(xy 358.068633 -157.957054) (xy 358.226481 -158.011687) (xy 358.38155 -158.07377) (xy 358.53349 -158.14316)
			(xy 358.681955 -158.219701) (xy 358.826611 -158.30322) (xy 358.967129 -158.393527) (xy 359.10319 -158.490418)
			(xy 359.234488 -158.593673) (xy 359.360723 -158.703059) (xy 359.481611 -158.818327) (xy 359.492747 -158.830006)
			(xy 361.785893 -158.830006) (xy 361.789998 -158.730238) (xy 361.802285 -158.631143) (xy 361.822671 -158.533393)
			(xy 361.85102 -158.437649) (xy 361.887138 -158.344557) (xy 361.930782 -158.254747) (xy 361.981657 -158.168826)
			(xy 362.039419 -158.087375) (xy 362.103677 -158.010945) (xy 362.173997 -157.940052) (xy 362.21162 -157.907228)
			(xy 362.219631 -157.899646) (xy 362.228855 -157.879636) (xy 362.2294 -157.86862) (xy 362.2294 -157.791404)
			(xy 362.22886 -157.780385) (xy 362.219642 -157.760369) (xy 362.21162 -157.752796) (xy 362.175695 -157.72148)
			(xy 362.108323 -157.65406) (xy 362.046446 -157.581563) (xy 361.990445 -157.504438) (xy 361.940665 -157.423158)
			(xy 361.897412 -157.338225) (xy 361.860953 -157.250162) (xy 361.831512 -157.15951) (xy 361.809271 -157.066829)
			(xy 361.794367 -156.972689) (xy 361.786891 -156.87767) (xy 361.786424 -156.830014) (xy 361.786965 -156.779837)
			(xy 361.79525 -156.679825) (xy 361.811765 -156.580838) (xy 361.836396 -156.483554) (xy 361.868976 -156.388635)
			(xy 361.909282 -156.29673) (xy 361.957039 -156.208467) (xy 362.01192 -156.124449) (xy 362.073551 -156.045249)
			(xy 362.141512 -155.971408) (xy 362.215337 -155.903431) (xy 362.294523 -155.841782) (xy 362.378528 -155.786881)
			(xy 362.46678 -155.739104) (xy 362.558676 -155.698777) (xy 362.653587 -155.666176) (xy 362.750866 -155.641522)
			(xy 362.849849 -155.624985) (xy 362.949859 -155.616677) (xy 363.000036 -155.616148) (xy 363.047698 -155.616657)
			(xy 363.142727 -155.624138) (xy 363.236876 -155.639052) (xy 363.329565 -155.661306) (xy 363.420222 -155.690763)
			(xy 363.508289 -155.727242) (xy 363.593222 -155.770518) (xy 363.674499 -155.820323) (xy 363.751617 -155.876352)
			(xy 363.824103 -155.938258) (xy 363.891508 -156.005661) (xy 363.922818 -156.041598) (xy 363.930385 -156.049627)
			(xy 363.950406 -156.058842) (xy 363.961426 -156.059378) (xy 364.038642 -156.059378) (xy 364.049665 -156.05887)
			(xy 364.069681 -156.04963) (xy 364.07725 -156.041598) (xy 364.108538 -156.005641) (xy 364.175953 -155.938249)
			(xy 364.248446 -155.876351) (xy 364.32557 -155.820329) (xy 364.406849 -155.770527) (xy 364.491784 -155.727252)
			(xy 364.579851 -155.690771) (xy 364.670507 -155.661309) (xy 364.763194 -155.639047) (xy 364.857342 -155.624122)
			(xy 364.95237 -155.616626) (xy 365.000032 -155.616148) (xy 365.050199 -155.616675) (xy 365.150189 -155.624962)
			(xy 365.249154 -155.641476) (xy 365.346418 -155.666105) (xy 365.441316 -155.69868) (xy 365.5332 -155.738979)
			(xy 365.621444 -155.786728) (xy 365.705443 -155.841599) (xy 365.784626 -155.903218) (xy 365.85845 -155.971164)
			(xy 365.926413 -156.044974) (xy 365.988049 -156.124143) (xy 366.042938 -156.208131) (xy 366.090705 -156.296364)
			(xy 366.131025 -156.38824) (xy 366.16362 -156.483131) (xy 366.18827 -156.580389) (xy 366.204806 -156.679351)
			(xy 366.213114 -156.779339) (xy 366.213644 -156.829506) (xy 366.213644 -156.830014) (xy 366.21318 -156.877671)
			(xy 366.205711 -156.972691) (xy 366.190811 -157.066833) (xy 366.168573 -157.159516) (xy 366.139134 -157.250169)
			(xy 366.102675 -157.338233) (xy 366.059421 -157.423167) (xy 366.009638 -157.504446) (xy 365.953632 -157.58157)
			(xy 365.891751 -157.654063) (xy 365.824373 -157.721479) (xy 365.788448 -157.752796) (xy 365.780421 -157.760364)
			(xy 365.771207 -157.780384) (xy 365.770668 -157.791404) (xy 365.770668 -157.86862) (xy 365.771205 -157.879639)
			(xy 365.780426 -157.899654) (xy 365.788448 -157.907228) (xy 365.826082 -157.94004) (xy 365.896405 -158.010933)
			(xy 365.960665 -158.087364) (xy 366.018429 -158.168815) (xy 366.069306 -158.254737) (xy 366.112952 -158.344548)
			(xy 366.149072 -158.437642) (xy 366.177421 -158.533388) (xy 366.197809 -158.63114) (xy 366.210097 -158.730236)
			(xy 366.214202 -158.830006) (xy 367.785885 -158.830006) (xy 367.78999 -158.730238) (xy 367.802277 -158.631144)
			(xy 367.822663 -158.533394) (xy 367.851011 -158.43765) (xy 367.887129 -158.344558) (xy 367.930773 -158.254748)
			(xy 367.981647 -158.168827) (xy 368.039408 -158.087376) (xy 368.103666 -158.010945) (xy 368.173985 -157.940052)
			(xy 368.211608 -157.907228) (xy 368.219618 -157.899644) (xy 368.228843 -157.879636) (xy 368.229388 -157.86862)
			(xy 368.229388 -157.791404) (xy 368.228852 -157.780385) (xy 368.219631 -157.760368) (xy 368.211608 -157.752796)
			(xy 368.17568 -157.721483) (xy 368.108309 -157.654062) (xy 368.046432 -157.581565) (xy 367.990432 -157.504439)
			(xy 367.940652 -157.423159) (xy 367.897399 -157.338226) (xy 367.86094 -157.250162) (xy 367.8315 -157.15951)
			(xy 367.809259 -157.066829) (xy 367.794355 -156.972689) (xy 367.786879 -156.87767) (xy 367.786412 -156.830014)
			(xy 367.786965 -156.779837) (xy 367.79525 -156.679826) (xy 367.811765 -156.58084) (xy 367.836396 -156.483556)
			(xy 367.868975 -156.388637) (xy 367.909281 -156.296733) (xy 367.957037 -156.208471) (xy 368.011917 -156.124453)
			(xy 368.073548 -156.045253) (xy 368.141507 -155.971413) (xy 368.215332 -155.903435) (xy 368.294517 -155.841786)
			(xy 368.378521 -155.786885) (xy 368.466772 -155.739108) (xy 368.558667 -155.698781) (xy 368.653578 -155.666178)
			(xy 368.750856 -155.641524) (xy 368.849838 -155.624986) (xy 368.949847 -155.616677) (xy 369.000024 -155.616148)
			(xy 369.047687 -155.616593) (xy 369.142718 -155.624081) (xy 369.236868 -155.639002) (xy 369.329558 -155.661263)
			(xy 369.420216 -155.690726) (xy 369.508283 -155.727212) (xy 369.593216 -155.770493) (xy 369.674492 -155.820305)
			(xy 369.751609 -155.876339) (xy 369.824093 -155.938251) (xy 369.891497 -156.005658) (xy 369.922806 -156.041598)
			(xy 369.930378 -156.049622) (xy 369.950395 -156.05884) (xy 369.961414 -156.059378) (xy 370.03863 -156.059378)
			(xy 370.049652 -156.058864) (xy 370.069669 -156.049628) (xy 370.077238 -156.041598) (xy 370.108532 -156.005647)
			(xy 370.175947 -155.938254) (xy 370.248439 -155.876356) (xy 370.325562 -155.820334) (xy 370.406841 -155.770531)
			(xy 370.491775 -155.727256) (xy 370.579841 -155.690775) (xy 370.670497 -155.661312) (xy 370.763183 -155.639049)
			(xy 370.857331 -155.624123) (xy 370.952359 -155.616626) (xy 371.00002 -155.616148) (xy 371.050186 -155.616687)
			(xy 371.150177 -155.624972) (xy 371.249142 -155.641486) (xy 371.346405 -155.666113) (xy 371.441303 -155.698688)
			(xy 371.533187 -155.738987) (xy 371.621431 -155.786734) (xy 371.70543 -155.841604) (xy 371.784613 -155.903223)
			(xy 371.858438 -155.971169) (xy 371.9264 -156.044978) (xy 371.988036 -156.124147) (xy 372.042926 -156.208134)
			(xy 372.090693 -156.296366) (xy 372.131012 -156.388242) (xy 372.163608 -156.483132) (xy 372.188258 -156.58039)
			(xy 372.204794 -156.679351) (xy 372.213102 -156.77934) (xy 372.213632 -156.829506) (xy 372.213632 -156.830014)
			(xy 372.213173 -156.877671) (xy 372.205703 -156.972691) (xy 372.190803 -157.066833) (xy 372.168565 -157.159516)
			(xy 372.139126 -157.250169) (xy 372.102666 -157.338234) (xy 372.059411 -157.423168) (xy 372.009628 -157.504447)
			(xy 371.953622 -157.58157) (xy 371.89174 -157.654063) (xy 371.824361 -157.721479) (xy 371.788436 -157.752796)
			(xy 371.780407 -157.760362) (xy 371.771194 -157.780384) (xy 371.770656 -157.791404) (xy 371.770656 -157.86862)
			(xy 371.771165 -157.879643) (xy 371.780403 -157.89966) (xy 371.788436 -157.907228) (xy 371.82687 -157.940727)
			(xy 371.898577 -158.013215) (xy 371.963952 -158.091462) (xy 372.022533 -158.174916) (xy 372.073908 -158.26299)
			(xy 372.096284 -158.308802) (xy 372.100856 -158.318454) (xy 372.116858 -158.332424) (xy 372.199154 -158.357316)
			(xy 372.209416 -158.359985) (xy 372.230452 -158.357503) (xy 372.239794 -158.35249) (xy 372.285756 -158.325685)
			(xy 372.380859 -158.27795) (xy 372.479133 -158.237137) (xy 372.580073 -158.203457) (xy 372.683163 -158.17708)
			(xy 372.787875 -158.158142) (xy 372.893673 -158.146741) (xy 373.000016 -158.142934) (xy 373.106359 -158.146741)
			(xy 373.212157 -158.158142) (xy 373.316869 -158.17708) (xy 373.419959 -158.203457) (xy 373.520899 -158.237137)
			(xy 373.619173 -158.27795) (xy 373.714276 -158.325685) (xy 373.760238 -158.35249) (xy 373.769622 -158.357377)
			(xy 373.79061 -158.359868) (xy 373.800878 -158.357316) (xy 373.883174 -158.332424) (xy 373.899176 -158.318454)
			(xy 373.903748 -158.308802) (xy 373.926127 -158.262992) (xy 373.977496 -158.174915) (xy 374.036076 -158.091459)
			(xy 374.101453 -158.013214) (xy 374.173165 -157.940731) (xy 374.211596 -157.907228) (xy 374.219604 -157.899642)
			(xy 374.228831 -157.879636) (xy 374.229376 -157.86862) (xy 374.229376 -157.791404) (xy 374.228843 -157.780384)
			(xy 374.219621 -157.760367) (xy 374.211596 -157.752796) (xy 374.175666 -157.721486) (xy 374.108295 -157.654064)
			(xy 374.046419 -157.581567) (xy 373.990418 -157.504441) (xy 373.940639 -157.423161) (xy 373.897386 -157.338227)
			(xy 373.860928 -157.250163) (xy 373.831488 -157.159511) (xy 373.809247 -157.066829) (xy 373.794343 -156.972689)
			(xy 373.786867 -156.87767) (xy 373.7864 -156.830014) (xy 373.786965 -156.779837) (xy 373.79525 -156.679827)
			(xy 373.811764 -156.580841) (xy 373.836395 -156.483558) (xy 373.868974 -156.38864) (xy 373.909279 -156.296736)
			(xy 373.957035 -156.208474) (xy 374.011915 -156.124457) (xy 374.073545 -156.045257) (xy 374.141503 -155.971417)
			(xy 374.215327 -155.90344) (xy 374.294511 -155.84179) (xy 374.378515 -155.786889) (xy 374.466765 -155.739112)
			(xy 374.558659 -155.698784) (xy 374.653568 -155.666181) (xy 374.750846 -155.641526) (xy 374.849827 -155.624988)
			(xy 374.949835 -155.616678) (xy 375.000012 -155.616148) (xy 375.047675 -155.616602) (xy 375.142705 -155.624089)
			(xy 375.236856 -155.639009) (xy 375.329545 -155.661268) (xy 375.420203 -155.690731) (xy 375.50827 -155.727216)
			(xy 375.593203 -155.770497) (xy 375.674479 -155.820308) (xy 375.751597 -155.876341) (xy 375.824081 -155.938252)
			(xy 375.891484 -156.005658) (xy 375.922794 -156.041598) (xy 375.930371 -156.049616) (xy 375.950384 -156.058837)
			(xy 375.961402 -156.059378) (xy 376.038618 -156.059378) (xy 376.049639 -156.058857) (xy 376.069656 -156.049626)
			(xy 376.077226 -156.041598) (xy 376.108527 -156.005653) (xy 376.175941 -155.93826) (xy 376.248432 -155.876362)
			(xy 376.325555 -155.820339) (xy 376.406833 -155.770536) (xy 376.491766 -155.72726) (xy 376.579831 -155.690779)
			(xy 376.670486 -155.661315) (xy 376.763173 -155.639051) (xy 376.857319 -155.624124) (xy 376.952347 -155.616626)
			(xy 377.000008 -155.616148) (xy 377.050174 -155.616698) (xy 377.150164 -155.624983) (xy 377.249129 -155.641495)
			(xy 377.346392 -155.666122) (xy 377.44129 -155.698696) (xy 377.533174 -155.738994) (xy 377.621418 -155.78674)
			(xy 377.705417 -155.84161) (xy 377.7846 -155.903228) (xy 377.858425 -155.971173) (xy 377.926387 -156.044982)
			(xy 377.988024 -156.12415) (xy 378.042913 -156.208137) (xy 378.090681 -156.296369) (xy 378.131 -156.388243)
			(xy 378.163596 -156.483134) (xy 378.188246 -156.580391) (xy 378.204782 -156.679352) (xy 378.21309 -156.77934)
			(xy 378.21362 -156.829506) (xy 378.21362 -156.830014) (xy 378.213165 -156.877671) (xy 378.205695 -156.972692)
			(xy 378.190795 -157.066834) (xy 378.168557 -157.159517) (xy 378.139117 -157.25017) (xy 378.102657 -157.338235)
			(xy 378.059402 -157.423168) (xy 378.009618 -157.504447) (xy 377.953612 -157.581571) (xy 377.891728 -157.654064)
			(xy 377.82435 -157.721479) (xy 377.788424 -157.752796) (xy 377.780393 -157.76036) (xy 377.771182 -157.780384)
			(xy 377.770644 -157.791404) (xy 377.770644 -157.86862) (xy 377.771157 -157.879642) (xy 377.780393 -157.899659)
			(xy 377.788424 -157.907228) (xy 377.826059 -157.94004) (xy 377.896383 -158.010932) (xy 377.960645 -158.087362)
			(xy 378.01841 -158.168813) (xy 378.069288 -158.254735) (xy 378.112934 -158.344547) (xy 378.149055 -158.43764)
			(xy 378.177405 -158.533387) (xy 378.197793 -158.631139) (xy 378.210081 -158.730235) (xy 378.214186 -158.830006)
			(xy 378.21008 -158.929778) (xy 378.197791 -159.028874) (xy 378.177402 -159.126626) (xy 378.149051 -159.222372)
			(xy 378.112929 -159.315465) (xy 378.069281 -159.405276) (xy 378.018403 -159.491197) (xy 377.960637 -159.572648)
			(xy 377.896374 -159.649078) (xy 377.82605 -159.719969) (xy 377.788424 -159.752792) (xy 377.780395 -159.760358)
			(xy 377.771183 -159.78038) (xy 377.770644 -159.7914) (xy 377.770644 -159.868616) (xy 377.771159 -159.879638)
			(xy 377.780393 -159.899655) (xy 377.788424 -159.907224) (xy 377.824368 -159.938518) (xy 377.891738 -160.005942)
			(xy 377.953613 -160.078441) (xy 378.009613 -160.155569) (xy 378.059391 -160.236851) (xy 378.102642 -160.321787)
			(xy 378.139099 -160.409852) (xy 378.168538 -160.500505) (xy 378.190777 -160.593188) (xy 378.205679 -160.687329)
			(xy 378.213153 -160.782349) (xy 378.21362 -160.830006) (xy 381.986028 -160.830006) (xy 381.986502 -160.782344)
			(xy 381.993988 -160.687314) (xy 382.008905 -160.593164) (xy 382.031164 -160.500475) (xy 382.060625 -160.409817)
			(xy 382.097107 -160.321751) (xy 382.140386 -160.236817) (xy 382.190195 -160.155541) (xy 382.246226 -160.078423)
			(xy 382.308135 -160.005939) (xy 382.375539 -159.938534) (xy 382.411478 -159.907224) (xy 382.4195 -159.899652)
			(xy 382.428716 -159.879634) (xy 382.429258 -159.868616) (xy 382.429258 -159.7914) (xy 382.428734 -159.780379)
			(xy 382.419506 -159.760362) (xy 382.411478 -159.752792) (xy 382.375537 -159.721486) (xy 382.308145 -159.654072)
			(xy 382.246247 -159.581581) (xy 382.190224 -159.504459) (xy 382.140421 -159.423182) (xy 382.097145 -159.338249)
			(xy 382.060663 -159.250184) (xy 382.031199 -159.15953) (xy 382.008934 -159.066844) (xy 381.994006 -158.972698)
			(xy 381.986507 -158.877671) (xy 381.986028 -158.83001) (xy 381.986505 -158.782348) (xy 381.99399 -158.687318)
			(xy 382.008908 -158.593168) (xy 382.031165 -158.500479) (xy 382.060626 -158.409822) (xy 382.097108 -158.321755)
			(xy 382.140387 -158.236822) (xy 382.190196 -158.155546) (xy 382.246227 -158.078427) (xy 382.308135 -158.005943)
			(xy 382.37554 -157.938538) (xy 382.411478 -157.907228) (xy 382.419499 -157.899655) (xy 382.428715 -157.879638)
			(xy 382.429258 -157.86862) (xy 382.429258 -157.791404) (xy 382.428731 -157.780383) (xy 382.419505 -157.760366)
			(xy 382.411478 -157.752796) (xy 382.375539 -157.721488) (xy 382.308147 -157.654074) (xy 382.246249 -157.581583)
			(xy 382.190226 -157.504462) (xy 382.140423 -157.423184) (xy 382.097147 -157.338252) (xy 382.060664 -157.250187)
			(xy 382.0312 -157.159533) (xy 382.008935 -157.066848) (xy 381.994007 -156.972702) (xy 381.986507 -156.877675)
			(xy 381.986028 -156.830014) (xy 381.986552 -156.779829) (xy 381.994839 -156.679803) (xy 382.011358 -156.580802)
			(xy 382.035996 -156.483504) (xy 382.068585 -156.388573) (xy 382.108902 -156.296657) (xy 382.156672 -156.208384)
			(xy 382.211568 -156.124358) (xy 382.273215 -156.045152) (xy 382.341193 -155.971307) (xy 382.415037 -155.903328)
			(xy 382.494242 -155.84168) (xy 382.578267 -155.786782) (xy 382.666539 -155.739011) (xy 382.758454 -155.698693)
			(xy 382.853385 -155.666102) (xy 382.950683 -155.641462) (xy 383.049683 -155.624942) (xy 383.149709 -155.616653)
			(xy 383.199894 -155.616148) (xy 383.247556 -155.616615) (xy 383.342587 -155.624101) (xy 383.436737 -155.639019)
			(xy 383.529426 -155.661277) (xy 383.620084 -155.690739) (xy 383.708151 -155.727222) (xy 383.793084 -155.770502)
			(xy 383.87436 -155.820311) (xy 383.951478 -155.876344) (xy 384.023962 -155.938253) (xy 384.091366 -156.005659)
			(xy 384.122676 -156.041598) (xy 384.13026 -156.049608) (xy 384.150268 -156.058834) (xy 384.161284 -156.059378)
			(xy 384.2385 -156.059378) (xy 384.24952 -156.058847) (xy 384.269537 -156.049623) (xy 384.277108 -156.041598)
			(xy 384.308419 -156.005661) (xy 384.375832 -155.938269) (xy 384.448322 -155.87637) (xy 384.525443 -155.820346)
			(xy 384.60672 -155.770543) (xy 384.691652 -155.727267) (xy 384.779717 -155.690784) (xy 384.870371 -155.661319)
			(xy 384.963056 -155.639054) (xy 385.057202 -155.624126) (xy 385.152229 -155.616627) (xy 385.19989 -155.616148)
			(xy 385.250075 -155.616648) (xy 385.350103 -155.624936) (xy 385.449105 -155.641456) (xy 385.546404 -155.666095)
			(xy 385.641336 -155.698684) (xy 385.733253 -155.739003) (xy 385.821526 -155.786773) (xy 385.905553 -155.841671)
			(xy 385.984759 -155.90332) (xy 386.058604 -155.971299) (xy 386.126583 -156.045144) (xy 386.188232 -156.12435)
			(xy 386.243129 -156.208377) (xy 386.290899 -156.296651) (xy 386.331217 -156.388568) (xy 386.363807 -156.4835)
			(xy 386.388445 -156.580799) (xy 386.404965 -156.679801) (xy 386.413252 -156.779829) (xy 386.413756 -156.830014)
			(xy 386.413302 -156.877677) (xy 386.405815 -156.972707) (xy 386.390895 -157.066858) (xy 386.368635 -157.159547)
			(xy 386.339172 -157.250205) (xy 386.302688 -157.338272) (xy 386.259407 -157.423205) (xy 386.209596 -157.504481)
			(xy 386.153563 -157.581599) (xy 386.091652 -157.654083) (xy 386.024245 -157.721486) (xy 385.988306 -157.752796)
			(xy 385.980288 -157.760372) (xy 385.971066 -157.780386) (xy 385.970526 -157.791404) (xy 385.970526 -157.86862)
			(xy 385.971045 -157.879641) (xy 385.980277 -157.899658) (xy 385.988306 -157.907228) (xy 386.024253 -157.938527)
			(xy 386.091646 -158.005941) (xy 386.153544 -158.078433) (xy 386.209567 -158.155555) (xy 386.259369 -158.236834)
			(xy 386.302644 -158.321767) (xy 386.339126 -158.409833) (xy 386.36859 -158.500488) (xy 386.390853 -158.593174)
			(xy 386.40578 -158.687321) (xy 386.413278 -158.782349) (xy 386.413756 -158.83001) (xy 386.413299 -158.877672)
			(xy 386.405812 -158.972703) (xy 386.390893 -159.066853) (xy 386.368633 -159.159543) (xy 386.339171 -159.250201)
			(xy 386.302686 -159.338268) (xy 386.259406 -159.423201) (xy 386.209595 -159.504477) (xy 386.153562 -159.581594)
			(xy 386.091652 -159.654079) (xy 386.024245 -159.721482) (xy 385.988306 -159.752792) (xy 385.980289 -159.76037)
			(xy 385.971067 -159.780382) (xy 385.970526 -159.7914) (xy 385.970526 -159.868616) (xy 385.971047 -159.879637)
			(xy 385.980278 -159.899654) (xy 385.988306 -159.907224) (xy 386.024251 -159.938525) (xy 386.091644 -160.005939)
			(xy 386.153542 -160.078431) (xy 386.209565 -160.155553) (xy 386.259368 -160.236831) (xy 386.302643 -160.321764)
			(xy 386.339125 -160.409829) (xy 386.368589 -160.500484) (xy 386.390852 -160.593171) (xy 386.405779 -160.687317)
			(xy 386.413277 -160.782345) (xy 386.413756 -160.830006) (xy 386.41359 -160.852381) (xy 386.411813 -160.897097)
			(xy 386.4102 -160.919414) (xy 386.4102 -160.919668) (xy 386.409958 -160.928551) (xy 386.414832 -160.945627)
			(xy 386.425194 -160.960048) (xy 386.432298 -160.965388) (xy 386.50545 -161.014664) (xy 386.512994 -161.019448)
			(xy 386.530299 -161.023851) (xy 386.548064 -161.022055) (xy 386.55625 -161.018474) (xy 386.556504 -161.01822)
			(xy 386.606586 -160.994237) (xy 386.709718 -160.953049) (xy 386.815678 -160.919811) (xy 386.923857 -160.894713)
			(xy 387.033629 -160.877899) (xy 387.14436 -160.869468) (xy 387.255412 -160.869468) (xy 387.366143 -160.877899)
			(xy 387.475915 -160.894713) (xy 387.584094 -160.919811) (xy 387.690054 -160.953049) (xy 387.793186 -160.994237)
			(xy 387.843268 -161.01822) (xy 387.843522 -161.018474) (xy 387.851694 -161.022085) (xy 387.869464 -161.023863)
			(xy 387.886764 -161.019431) (xy 387.894322 -161.014664) (xy 387.967474 -160.965388) (xy 387.974676 -160.960145)
			(xy 387.985104 -160.945713) (xy 387.989919 -160.928571) (xy 387.989572 -160.919668) (xy 387.989572 -160.91916)
			(xy 387.987965 -160.896906) (xy 387.986188 -160.852317) (xy 387.986016 -160.830006) (xy 387.986494 -160.782344)
			(xy 387.99398 -160.687314) (xy 388.008897 -160.593165) (xy 388.031155 -160.500476) (xy 388.060616 -160.409818)
			(xy 388.097098 -160.321752) (xy 388.140377 -160.236818) (xy 388.190185 -160.155542) (xy 388.246216 -160.078424)
			(xy 388.308124 -160.005939) (xy 388.375528 -159.938534) (xy 388.411466 -159.907224) (xy 388.419487 -159.89965)
			(xy 388.428704 -159.879634) (xy 388.429246 -159.868616) (xy 388.429246 -159.7914) (xy 388.428725 -159.780379)
			(xy 388.419496 -159.760361) (xy 388.411466 -159.752792) (xy 388.375523 -159.721489) (xy 388.308131 -159.654075)
			(xy 388.246233 -159.581583) (xy 388.19021 -159.504461) (xy 388.140408 -159.423183) (xy 388.097133 -159.33825)
			(xy 388.06065 -159.250185) (xy 388.031186 -159.15953) (xy 388.008922 -159.066845) (xy 387.993994 -158.972698)
			(xy 387.986495 -158.877671) (xy 387.986016 -158.83001) (xy 387.986497 -158.782348) (xy 387.993982 -158.687318)
			(xy 388.0089 -158.593169) (xy 388.031157 -158.50048) (xy 388.060618 -158.409823) (xy 388.097099 -158.321756)
			(xy 388.140378 -158.236823) (xy 388.190186 -158.155546) (xy 388.246216 -158.078428) (xy 388.308124 -158.005943)
			(xy 388.375528 -157.938538) (xy 388.411466 -157.907228) (xy 388.419485 -157.899653) (xy 388.428703 -157.879638)
			(xy 388.429246 -157.86862) (xy 388.429246 -157.791404) (xy 388.428723 -157.780383) (xy 388.419495 -157.760366)
			(xy 388.411466 -157.752796) (xy 388.375525 -157.721491) (xy 388.308133 -157.654077) (xy 388.246235 -157.581585)
			(xy 388.190212 -157.504463) (xy 388.14041 -157.423186) (xy 388.097134 -157.338253) (xy 388.060652 -157.250188)
			(xy 388.031187 -157.159534) (xy 388.008923 -157.066848) (xy 387.993995 -156.972702) (xy 387.986495 -156.877675)
			(xy 387.986016 -156.830014) (xy 387.986566 -156.77983) (xy 387.994853 -156.679805) (xy 388.011372 -156.580807)
			(xy 388.036009 -156.48351) (xy 388.068597 -156.38858) (xy 388.108913 -156.296666) (xy 388.156682 -156.208395)
			(xy 388.211577 -156.12437) (xy 388.273223 -156.045165) (xy 388.341199 -155.971321) (xy 388.415041 -155.903343)
			(xy 388.494244 -155.841695) (xy 388.578267 -155.786798) (xy 388.666537 -155.739027) (xy 388.758451 -155.698709)
			(xy 388.853379 -155.666118) (xy 388.950675 -155.641478) (xy 389.049674 -155.624957) (xy 389.149698 -155.616667)
			(xy 389.199882 -155.616148) (xy 389.247544 -155.616624) (xy 389.342574 -155.624108) (xy 389.436724 -155.639026)
			(xy 389.529414 -155.661283) (xy 389.620071 -155.690744) (xy 389.708138 -155.727226) (xy 389.793071 -155.770505)
			(xy 389.874347 -155.820314) (xy 389.951465 -155.876345) (xy 390.02395 -155.938254) (xy 390.091354 -156.005659)
			(xy 390.122664 -156.041598) (xy 390.130253 -156.049603) (xy 390.150257 -156.058831) (xy 390.161272 -156.059378)
			(xy 390.238488 -156.059378) (xy 390.249507 -156.05884) (xy 390.269524 -156.049622) (xy 390.277096 -156.041598)
			(xy 390.308413 -156.005667) (xy 390.375826 -155.938274) (xy 390.448315 -155.876375) (xy 390.525436 -155.820351)
			(xy 390.606712 -155.770548) (xy 390.691643 -155.727271) (xy 390.779707 -155.690787) (xy 390.870361 -155.661322)
			(xy 390.963045 -155.639057) (xy 391.057191 -155.624128) (xy 391.152217 -155.616628) (xy 391.199878 -155.616148)
			(xy 391.250063 -155.61666) (xy 391.35009 -155.624946) (xy 391.449092 -155.641465) (xy 391.546391 -155.666103)
			(xy 391.641323 -155.698692) (xy 391.73324 -155.73901) (xy 391.821513 -155.78678) (xy 391.90554 -155.841676)
			(xy 391.984746 -155.903324) (xy 392.058591 -155.971303) (xy 392.12657 -156.045147) (xy 392.188219 -156.124354)
			(xy 392.243116 -156.20838) (xy 392.290887 -156.296653) (xy 392.331205 -156.388569) (xy 392.363794 -156.483501)
			(xy 392.388433 -156.5808) (xy 392.404953 -156.679802) (xy 392.41324 -156.779829) (xy 392.413744 -156.830014)
			(xy 392.413294 -156.877677) (xy 392.405807 -156.972708) (xy 392.390887 -157.066858) (xy 392.368627 -157.159548)
			(xy 392.339164 -157.250206) (xy 392.302679 -157.338273) (xy 392.259397 -157.423206) (xy 392.209586 -157.504482)
			(xy 392.153552 -157.581599) (xy 392.091641 -157.654083) (xy 392.024234 -157.721487) (xy 391.988294 -157.752796)
			(xy 391.980274 -157.760371) (xy 391.971054 -157.780386) (xy 391.970514 -157.791404) (xy 391.970514 -157.86862)
			(xy 391.971036 -157.879641) (xy 391.980266 -157.899658) (xy 391.988294 -157.907228) (xy 392.024239 -157.93853)
			(xy 392.091631 -158.005944) (xy 392.15353 -158.078435) (xy 392.209553 -158.155557) (xy 392.259356 -158.236835)
			(xy 392.302632 -158.321768) (xy 392.339114 -158.409833) (xy 392.368577 -158.500488) (xy 392.390841 -158.593175)
			(xy 392.405768 -158.687321) (xy 392.413266 -158.782349) (xy 392.413744 -158.83001) (xy 392.413291 -158.877673)
			(xy 392.405804 -158.972703) (xy 392.390885 -159.066854) (xy 392.368625 -159.159544) (xy 392.339162 -159.250202)
			(xy 392.302678 -159.338268) (xy 392.259396 -159.423202) (xy 392.209585 -159.504478) (xy 392.153552 -159.581595)
			(xy 392.091641 -159.654079) (xy 392.024234 -159.721482) (xy 391.988294 -159.752792) (xy 391.980276 -159.760368)
			(xy 391.971055 -159.780382) (xy 391.970514 -159.7914) (xy 391.970514 -159.868616) (xy 391.971038 -159.879637)
			(xy 391.980267 -159.899653) (xy 391.988294 -159.907224) (xy 392.024237 -159.938528) (xy 392.09163 -160.005941)
			(xy 392.153528 -160.078433) (xy 392.209552 -160.155554) (xy 392.259354 -160.236832) (xy 392.30263 -160.321765)
			(xy 392.339112 -160.40983) (xy 392.368576 -160.500485) (xy 392.39084 -160.593171) (xy 392.405767 -160.687318)
			(xy 392.413265 -160.782345) (xy 392.413744 -160.830006) (xy 392.413267 -160.880192) (xy 392.404978 -160.98022)
			(xy 392.388457 -161.079222) (xy 392.363817 -161.176522) (xy 392.331225 -161.271455) (xy 392.290906 -161.363372)
			(xy 392.243134 -161.451646) (xy 392.188235 -161.535673) (xy 392.126585 -161.614879) (xy 392.058604 -161.688724)
			(xy 391.984758 -161.756703) (xy 391.90555 -161.818351) (xy 391.821522 -161.873248) (xy 391.733247 -161.921018)
			(xy 391.641329 -161.961335) (xy 391.546395 -161.993925) (xy 391.449095 -162.018563) (xy 391.350092 -162.035082)
			(xy 391.250064 -162.043368) (xy 391.199878 -162.043872) (xy 391.152216 -162.043418) (xy 391.057185 -162.03593)
			(xy 390.963035 -162.02101) (xy 390.870345 -161.99875) (xy 390.779688 -161.969287) (xy 390.691621 -161.932803)
			(xy 390.606688 -161.889522) (xy 390.525412 -161.839711) (xy 390.448294 -161.783678) (xy 390.37581 -161.721767)
			(xy 390.308406 -161.654361) (xy 390.277096 -161.618422) (xy 390.269535 -161.610387) (xy 390.249509 -161.601178)
			(xy 390.238488 -161.600642) (xy 390.161272 -161.600642) (xy 390.150249 -161.601151) (xy 390.130232 -161.61039)
			(xy 390.122664 -161.618422) (xy 390.091374 -161.654377) (xy 390.023958 -161.721768) (xy 389.951465 -161.783666)
			(xy 389.874341 -161.839688) (xy 389.793062 -161.88949) (xy 389.708128 -161.932764) (xy 389.620062 -161.969245)
			(xy 389.529406 -161.998708) (xy 389.436719 -162.020971) (xy 389.342571 -162.035897) (xy 389.247544 -162.043394)
			(xy 389.199882 -162.043872) (xy 389.145602 -162.043262) (xy 389.037477 -162.03354) (xy 388.930654 -162.014192)
			(xy 388.825987 -161.985374) (xy 388.77494 -161.96691) (xy 388.761986 -161.962084) (xy 388.73557 -161.966656)
			(xy 388.646416 -162.040316) (xy 388.637018 -162.06597) (xy 388.639304 -162.079432) (xy 388.648117 -162.132911)
			(xy 388.65875 -162.240785) (xy 388.66136 -162.34915) (xy 388.655931 -162.457411) (xy 388.642494 -162.564971)
			(xy 388.621122 -162.67124) (xy 388.591933 -162.775633) (xy 388.555087 -162.877575) (xy 388.510788 -162.976507)
			(xy 388.459279 -163.071883) (xy 388.400842 -163.163179) (xy 388.335801 -163.249894) (xy 388.264511 -163.331549)
			(xy 388.187366 -163.407697) (xy 388.10479 -163.477918) (xy 388.017236 -163.541825) (xy 387.925187 -163.599069)
			(xy 387.829149 -163.649333) (xy 387.729649 -163.692341) (xy 387.627236 -163.727856) (xy 387.522472 -163.755684)
			(xy 387.415934 -163.775672) (xy 387.308208 -163.787708) (xy 387.199886 -163.791727) (xy 387.091564 -163.787708)
			(xy 386.983838 -163.775672) (xy 386.8773 -163.755684) (xy 386.772536 -163.727856) (xy 386.670123 -163.692341)
			(xy 386.570623 -163.649333) (xy 386.474585 -163.599069) (xy 386.382536 -163.541825) (xy 386.294982 -163.477918)
			(xy 386.212406 -163.407697) (xy 386.135261 -163.331549) (xy 386.063971 -163.249894) (xy 385.99893 -163.163179)
			(xy 385.940493 -163.071883) (xy 385.888984 -162.976507) (xy 385.844685 -162.877575) (xy 385.807839 -162.775633)
			(xy 385.77865 -162.67124) (xy 385.757278 -162.564971) (xy 385.743841 -162.457411) (xy 385.738412 -162.34915)
			(xy 385.741022 -162.240785) (xy 385.751655 -162.132911) (xy 385.760468 -162.079432) (xy 385.762754 -162.06597)
			(xy 385.753356 -162.040316) (xy 385.664202 -161.966656) (xy 385.637786 -161.962084) (xy 385.624832 -161.96691)
			(xy 385.573782 -161.985364) (xy 385.469113 -162.014163) (xy 385.362291 -162.033508) (xy 385.254169 -162.043246)
			(xy 385.19989 -162.043872) (xy 385.152228 -162.04341) (xy 385.057197 -162.035923) (xy 384.963047 -162.021004)
			(xy 384.870358 -161.998744) (xy 384.7797 -161.969282) (xy 384.691634 -161.932798) (xy 384.6067 -161.889518)
			(xy 384.525424 -161.839709) (xy 384.448307 -161.783676) (xy 384.375822 -161.721766) (xy 384.308418 -161.654361)
			(xy 384.277108 -161.618422) (xy 384.269543 -161.610392) (xy 384.24952 -161.601181) (xy 384.2385 -161.600642)
			(xy 384.161284 -161.600642) (xy 384.150262 -161.601158) (xy 384.130245 -161.610391) (xy 384.122676 -161.618422)
			(xy 384.091379 -161.654371) (xy 384.023964 -161.721763) (xy 383.951472 -161.78366) (xy 383.874349 -161.839683)
			(xy 383.793071 -161.889485) (xy 383.708137 -161.93276) (xy 383.620071 -161.969242) (xy 383.529416 -161.998705)
			(xy 383.43673 -162.020969) (xy 383.342583 -162.035895) (xy 383.247555 -162.043394) (xy 383.199894 -162.043872)
			(xy 383.14971 -162.043353) (xy 383.049684 -162.035065) (xy 382.950684 -162.018544) (xy 382.853387 -161.993905)
			(xy 382.758456 -161.961315) (xy 382.666541 -161.920997) (xy 382.57827 -161.873226) (xy 382.494245 -161.81833)
			(xy 382.41504 -161.756682) (xy 382.341196 -161.688704) (xy 382.273218 -161.61486) (xy 382.21157 -161.535655)
			(xy 382.156674 -161.45163) (xy 382.108903 -161.363359) (xy 382.068585 -161.271444) (xy 382.035995 -161.176513)
			(xy 382.011356 -161.079216) (xy 381.994835 -160.980216) (xy 381.986547 -160.88019) (xy 381.986028 -160.830006)
			(xy 378.21362 -160.830006) (xy 378.213154 -160.880185) (xy 378.204867 -160.9802) (xy 378.188349 -161.07919)
			(xy 378.163715 -161.176478) (xy 378.131132 -161.271399) (xy 378.090823 -161.363306) (xy 378.043062 -161.451571)
			(xy 377.988176 -161.535591) (xy 377.92654 -161.614791) (xy 377.858576 -161.688633) (xy 377.784746 -161.75661)
			(xy 377.705555 -161.818259) (xy 377.621544 -161.873158) (xy 377.533288 -161.920934) (xy 377.441387 -161.961259)
			(xy 377.346471 -161.993858) (xy 377.249188 -162.018508) (xy 377.150201 -162.035042) (xy 377.050187 -162.043345)
			(xy 377.000008 -162.043872) (xy 376.952346 -162.043397) (xy 376.857316 -162.035911) (xy 376.763166 -162.020993)
			(xy 376.670477 -161.998736) (xy 376.57982 -161.969275) (xy 376.491753 -161.932792) (xy 376.40682 -161.889513)
			(xy 376.325543 -161.839705) (xy 376.248425 -161.783673) (xy 376.175941 -161.721765) (xy 376.108536 -161.65436)
			(xy 376.077226 -161.618422) (xy 376.069653 -161.6104) (xy 376.049636 -161.601184) (xy 376.038618 -161.600642)
			(xy 375.961402 -161.600642) (xy 375.950381 -161.601168) (xy 375.930364 -161.610394) (xy 375.922794 -161.618422)
			(xy 375.891487 -161.654362) (xy 375.824073 -161.721754) (xy 375.751582 -161.783652) (xy 375.67446 -161.839675)
			(xy 375.593183 -161.889478) (xy 375.50825 -161.932754) (xy 375.420186 -161.969236) (xy 375.329532 -161.998701)
			(xy 375.236846 -162.020965) (xy 375.1427 -162.035893) (xy 375.047673 -162.043393) (xy 375.000012 -162.043872)
			(xy 374.950031 -162.043367) (xy 374.850408 -162.035131) (xy 374.7518 -162.01873) (xy 374.654875 -161.994275)
			(xy 374.56029 -161.961933) (xy 374.468684 -161.921921) (xy 374.380679 -161.874511) (xy 374.296872 -161.820025)
			(xy 374.217828 -161.758831) (xy 374.144086 -161.691345) (xy 374.076142 -161.618022) (xy 374.014459 -161.53936)
			(xy 373.959454 -161.455892) (xy 373.911499 -161.368183) (xy 373.87092 -161.276828) (xy 373.83799 -161.182445)
			(xy 373.812935 -161.085673) (xy 373.803926 -161.036508) (xy 373.801331 -161.024879) (xy 373.787304 -161.005662)
			(xy 373.777002 -160.999678) (xy 373.693436 -160.957514) (xy 373.669814 -160.95726) (xy 373.658892 -160.962594)
			(xy 373.611617 -160.985464) (xy 373.514417 -161.025256) (xy 373.414651 -161.058087) (xy 373.312816 -161.083794)
			(xy 373.20942 -161.102248) (xy 373.10498 -161.113358) (xy 373.000016 -161.117067) (xy 372.895052 -161.113358)
			(xy 372.790612 -161.102248) (xy 372.687216 -161.083794) (xy 372.585381 -161.058087) (xy 372.485615 -161.025256)
			(xy 372.388415 -160.985464) (xy 372.34114 -160.962594) (xy 372.330237 -160.95791) (xy 372.306532 -160.958058)
			(xy 372.295674 -160.962848) (xy 372.22303 -160.999678) (xy 372.212755 -161.0057) (xy 372.198706 -161.024888)
			(xy 372.196106 -161.036508) (xy 372.187109 -161.085678) (xy 372.16207 -161.182458) (xy 372.129154 -161.276851)
			(xy 372.088584 -161.368216) (xy 372.040637 -161.455934) (xy 371.985635 -161.539411) (xy 371.923954 -161.61808)
			(xy 371.856009 -161.691408) (xy 371.782263 -161.758898) (xy 371.703215 -161.820093) (xy 371.619401 -161.874578)
			(xy 371.531389 -161.921984) (xy 371.439775 -161.961989) (xy 371.345181 -161.994321) (xy 371.248248 -162.018763)
			(xy 371.149633 -162.035148) (xy 371.050004 -162.043365) (xy 371.00002 -162.043872) (xy 370.952358 -162.043388)
			(xy 370.857328 -162.035903) (xy 370.763179 -162.020987) (xy 370.67049 -161.99873) (xy 370.579832 -161.96927)
			(xy 370.491766 -161.932788) (xy 370.406832 -161.88951) (xy 370.325556 -161.839702) (xy 370.248438 -161.783672)
			(xy 370.175953 -161.721764) (xy 370.108548 -161.65436) (xy 370.077238 -161.618422) (xy 370.06966 -161.610406)
			(xy 370.049647 -161.601186) (xy 370.03863 -161.600642) (xy 369.961414 -161.600642) (xy 369.950394 -161.601175)
			(xy 369.930377 -161.610396) (xy 369.922806 -161.618422) (xy 369.891493 -161.654356) (xy 369.824079 -161.721748)
			(xy 369.751589 -161.783647) (xy 369.674468 -161.83967) (xy 369.593191 -161.889473) (xy 369.508259 -161.93275)
			(xy 369.420196 -161.969233) (xy 369.329542 -161.998698) (xy 369.236857 -162.020963) (xy 369.142711 -162.035892)
			(xy 369.047685 -162.043392) (xy 369.000024 -162.043872) (xy 368.949856 -162.043371) (xy 368.849863 -162.035088)
			(xy 368.750895 -162.018577) (xy 368.653628 -161.99395) (xy 368.558727 -161.961376) (xy 368.466839 -161.921078)
			(xy 368.378593 -161.873329) (xy 368.294591 -161.818457) (xy 368.215407 -161.756836) (xy 368.141581 -161.688887)
			(xy 368.073618 -161.615075) (xy 368.011981 -161.535903) (xy 367.957093 -161.451911) (xy 367.909327 -161.363675)
			(xy 367.86901 -161.271795) (xy 367.836418 -161.1769) (xy 367.811772 -161.079638) (xy 367.795241 -160.980674)
			(xy 367.786939 -160.880682) (xy 367.786412 -160.830514) (xy 367.786412 -160.830006) (xy 367.786905 -160.78235)
			(xy 367.794373 -160.687331) (xy 367.80927 -160.59319) (xy 367.831506 -160.500508) (xy 367.860943 -160.409856)
			(xy 367.897399 -160.321791) (xy 367.94065 -160.236858) (xy 367.99043 -160.155578) (xy 368.046432 -160.078454)
			(xy 368.108311 -160.00596) (xy 368.175685 -159.938542) (xy 368.211608 -159.907224) (xy 368.219619 -159.899642)
			(xy 368.228844 -159.879632) (xy 368.229388 -159.868616) (xy 368.229388 -159.7914) (xy 368.228854 -159.780381)
			(xy 368.219632 -159.760364) (xy 368.211608 -159.752792) (xy 368.173995 -159.719957) (xy 368.103675 -159.649064)
			(xy 368.039416 -159.572635) (xy 367.981654 -159.491184) (xy 367.930779 -159.405264) (xy 367.887134 -159.315454)
			(xy 367.851015 -159.222363) (xy 367.822666 -159.126619) (xy 367.802279 -159.028869) (xy 367.789991 -158.929775)
			(xy 367.785885 -158.830006) (xy 366.214202 -158.830006) (xy 366.210096 -158.929777) (xy 366.197807 -159.028873)
			(xy 366.177418 -159.126625) (xy 366.149068 -159.22237) (xy 366.112947 -159.315464) (xy 366.0693 -159.405274)
			(xy 366.018422 -159.491196) (xy 365.960657 -159.572647) (xy 365.896396 -159.649077) (xy 365.826073 -159.719969)
			(xy 365.788448 -159.752792) (xy 365.780422 -159.760361) (xy 365.771208 -159.780381) (xy 365.770668 -159.7914)
			(xy 365.770668 -159.868616) (xy 365.771207 -159.879634) (xy 365.780427 -159.89965) (xy 365.788448 -159.907224)
			(xy 365.824398 -159.938513) (xy 365.891767 -160.005937) (xy 365.953641 -160.078437) (xy 366.00964 -160.155566)
			(xy 366.059417 -160.236849) (xy 366.102668 -160.321785) (xy 366.139124 -160.409851) (xy 366.168563 -160.500505)
			(xy 366.190801 -160.593187) (xy 366.205703 -160.687329) (xy 366.213177 -160.782349) (xy 366.213644 -160.830006)
			(xy 366.213154 -160.880184) (xy 366.204867 -160.980199) (xy 366.18835 -161.079187) (xy 366.163717 -161.176473)
			(xy 366.131134 -161.271394) (xy 366.090826 -161.3633) (xy 366.043066 -161.451564) (xy 365.988182 -161.535583)
			(xy 365.926547 -161.614783) (xy 365.858584 -161.688624) (xy 365.784756 -161.756601) (xy 365.705567 -161.81825)
			(xy 365.621558 -161.87315) (xy 365.533303 -161.920926) (xy 365.441404 -161.961252) (xy 365.34649 -161.993852)
			(xy 365.249208 -162.018504) (xy 365.150223 -162.035039) (xy 365.05021 -162.043344) (xy 365.000032 -162.043872)
			(xy 364.95237 -162.043379) (xy 364.857341 -162.035896) (xy 364.763192 -162.02098) (xy 364.670502 -161.998724)
			(xy 364.579845 -161.969265) (xy 364.491778 -161.932784) (xy 364.406845 -161.889507) (xy 364.325569 -161.8397)
			(xy 364.24845 -161.78367) (xy 364.175965 -161.721763) (xy 364.10856 -161.65436) (xy 364.07725 -161.618422)
			(xy 364.069668 -161.610411) (xy 364.049658 -161.601189) (xy 364.038642 -161.600642) (xy 363.961426 -161.600642)
			(xy 363.950407 -161.601181) (xy 363.93039 -161.610398) (xy 363.922818 -161.618422) (xy 363.891498 -161.65435)
			(xy 363.824086 -161.721743) (xy 363.751596 -161.783641) (xy 363.674476 -161.839665) (xy 363.5932 -161.889469)
			(xy 363.508268 -161.932746) (xy 363.420205 -161.969229) (xy 363.329552 -161.998695) (xy 363.236868 -162.020961)
			(xy 363.142723 -162.035891) (xy 363.047697 -162.043392) (xy 363.000036 -162.043872) (xy 362.949868 -162.04336)
			(xy 362.849875 -162.035078) (xy 362.750907 -162.018567) (xy 362.653641 -161.993942) (xy 362.55874 -161.961369)
			(xy 362.466852 -161.92107) (xy 362.378606 -161.873323) (xy 362.294604 -161.818451) (xy 362.21542 -161.756831)
			(xy 362.141594 -161.688883) (xy 362.07363 -161.615071) (xy 362.011994 -161.535899) (xy 361.957105 -161.451909)
			(xy 361.909339 -161.363672) (xy 361.869022 -161.271793) (xy 361.83643 -161.176899) (xy 361.811784 -161.079638)
			(xy 361.795253 -160.980673) (xy 361.786951 -160.880682) (xy 361.786424 -160.830514) (xy 361.786424 -160.830006)
			(xy 361.786913 -160.78235) (xy 361.794381 -160.687331) (xy 361.809279 -160.59319) (xy 361.831514 -160.500508)
			(xy 361.860951 -160.409855) (xy 361.897408 -160.321791) (xy 361.94066 -160.236857) (xy 361.99044 -160.155578)
			(xy 362.046442 -160.078453) (xy 362.108322 -160.005959) (xy 362.175696 -159.938542) (xy 362.21162 -159.907224)
			(xy 362.219633 -159.899643) (xy 362.228856 -159.879633) (xy 362.2294 -159.868616) (xy 362.2294 -159.7914)
			(xy 362.228862 -159.780381) (xy 362.219642 -159.760365) (xy 362.21162 -159.752792) (xy 362.174006 -159.719957)
			(xy 362.103686 -159.649065) (xy 362.039427 -159.572635) (xy 361.981664 -159.491185) (xy 361.930788 -159.405265)
			(xy 361.887143 -159.315455) (xy 361.851024 -159.222363) (xy 361.822675 -159.126619) (xy 361.802287 -159.028869)
			(xy 361.789999 -158.929775) (xy 361.785893 -158.830006) (xy 359.492747 -158.830006) (xy 359.596877 -158.939217)
			(xy 359.706261 -159.065454) (xy 359.809514 -159.196753) (xy 359.906403 -159.332816) (xy 359.996708 -159.473335)
			(xy 360.080225 -159.617992) (xy 360.156764 -159.766459) (xy 360.226152 -159.9184) (xy 360.288231 -160.07347)
			(xy 360.342862 -160.231318) (xy 360.389921 -160.391587) (xy 360.4293 -160.553913) (xy 360.460911 -160.71793)
			(xy 360.484682 -160.883264) (xy 360.50056 -161.049543) (xy 360.508507 -161.216389) (xy 360.509058 -161.299906)
			(xy 360.509058 -166.649908) (xy 360.509557 -166.745241) (xy 360.51765 -166.935736) (xy 360.53382 -167.125715)
			(xy 360.558038 -167.314837) (xy 360.590261 -167.502761) (xy 360.629411 -167.684417) (xy 365.513608 -167.684417)
			(xy 365.513608 -167.575771) (xy 365.521539 -167.467414) (xy 365.537358 -167.359925) (xy 365.560981 -167.253878)
			(xy 365.592282 -167.149838) (xy 365.631094 -167.04836) (xy 365.677209 -166.949986) (xy 365.730383 -166.855241)
			(xy 365.790331 -166.76463) (xy 365.856733 -166.678636) (xy 365.929235 -166.597719) (xy 366.00745 -166.522311)
			(xy 366.090961 -166.452812) (xy 366.179322 -166.389595) (xy 366.272062 -166.332997) (xy 366.368686 -166.283319)
			(xy 366.468678 -166.240827) (xy 366.571506 -166.205747) (xy 366.67662 -166.178267) (xy 366.783459 -166.158532)
			(xy 366.891454 -166.146649) (xy 367.000028 -166.142682) (xy 367.108602 -166.146649) (xy 367.216597 -166.158532)
			(xy 367.323436 -166.178267) (xy 367.42855 -166.205747) (xy 367.531378 -166.240827) (xy 367.63137 -166.283319)
			(xy 367.727994 -166.332997) (xy 367.820734 -166.389595) (xy 367.909095 -166.452812) (xy 367.992606 -166.522311)
			(xy 368.070821 -166.597719) (xy 368.143323 -166.678636) (xy 368.209725 -166.76463) (xy 368.252971 -166.829996)
			(xy 397.160973 -166.829996) (xy 397.165078 -166.730227) (xy 397.177366 -166.631132) (xy 397.197754 -166.533381)
			(xy 397.226103 -166.437636) (xy 397.262222 -166.344543) (xy 397.305867 -166.254733) (xy 397.356743 -166.168811)
			(xy 397.414505 -166.08736) (xy 397.478764 -166.010929) (xy 397.549084 -165.940036) (xy 397.586708 -165.907212)
			(xy 397.594725 -165.899634) (xy 397.603946 -165.879622) (xy 397.604488 -165.868604) (xy 397.604488 -165.791388)
			(xy 397.60396 -165.780368) (xy 397.594734 -165.760351) (xy 397.586708 -165.75278) (xy 397.549083 -165.719958)
			(xy 397.478763 -165.649065) (xy 397.414504 -165.572634) (xy 397.356742 -165.491183) (xy 397.305867 -165.405261)
			(xy 397.262223 -165.315451) (xy 397.226104 -165.222358) (xy 397.197756 -165.126613) (xy 397.177369 -165.028863)
			(xy 397.165081 -164.929768) (xy 397.160976 -164.829999) (xy 397.165081 -164.730229) (xy 397.177369 -164.631135)
			(xy 397.197756 -164.533384) (xy 397.226105 -164.437639) (xy 397.262224 -164.344547) (xy 397.305869 -164.254736)
			(xy 397.356744 -164.168815) (xy 397.414506 -164.087364) (xy 397.478764 -164.010933) (xy 397.549085 -163.94004)
			(xy 397.586708 -163.907216) (xy 397.594723 -163.899637) (xy 397.603946 -163.879625) (xy 397.604488 -163.868608)
			(xy 397.604488 -163.791392) (xy 397.603958 -163.780372) (xy 397.594733 -163.760355) (xy 397.586708 -163.752784)
			(xy 397.549087 -163.719958) (xy 397.478767 -163.649065) (xy 397.414508 -163.572634) (xy 397.356746 -163.491183)
			(xy 397.305871 -163.405262) (xy 397.262227 -163.315452) (xy 397.226108 -163.22236) (xy 397.197759 -163.126615)
			(xy 397.177372 -163.028865) (xy 397.165084 -162.92977) (xy 397.160979 -162.830001) (xy 397.165084 -162.730232)
			(xy 397.177372 -162.631138) (xy 397.197759 -162.533388) (xy 397.226107 -162.437643) (xy 397.262226 -162.34455)
			(xy 397.30587 -162.25474) (xy 397.356745 -162.168819) (xy 397.414507 -162.087368) (xy 397.478765 -162.010937)
			(xy 397.549085 -161.940044) (xy 397.586708 -161.90722) (xy 397.594721 -161.899639) (xy 397.603945 -161.879629)
			(xy 397.604488 -161.868612) (xy 397.604488 -161.791396) (xy 397.603956 -161.780376) (xy 397.594733 -161.76036)
			(xy 397.586708 -161.752788) (xy 397.549091 -161.719957) (xy 397.478771 -161.649065) (xy 397.414512 -161.572634)
			(xy 397.35675 -161.491184) (xy 397.305875 -161.405263) (xy 397.262231 -161.315453) (xy 397.226112 -161.222361)
			(xy 397.197763 -161.126617) (xy 397.177375 -161.028867) (xy 397.165088 -160.929773) (xy 397.160982 -160.830004)
			(xy 397.165087 -160.730235) (xy 397.177374 -160.631141) (xy 397.197761 -160.533391) (xy 397.226109 -160.437646)
			(xy 397.262227 -160.344554) (xy 397.305871 -160.254744) (xy 397.356746 -160.168823) (xy 397.414508 -160.087372)
			(xy 397.478765 -160.010941) (xy 397.549085 -159.940048) (xy 397.586708 -159.907224) (xy 397.594719 -159.899642)
			(xy 397.603944 -159.879632) (xy 397.604488 -159.868616) (xy 397.604488 -159.7914) (xy 397.603954 -159.780381)
			(xy 397.594732 -159.760364) (xy 397.586708 -159.752792) (xy 397.549095 -159.719957) (xy 397.478775 -159.649064)
			(xy 397.414516 -159.572635) (xy 397.356754 -159.491184) (xy 397.305879 -159.405264) (xy 397.262234 -159.315454)
			(xy 397.226115 -159.222363) (xy 397.197766 -159.126619) (xy 397.177379 -159.028869) (xy 397.165091 -158.929775)
			(xy 397.160985 -158.830006) (xy 397.16509 -158.730238) (xy 397.177377 -158.631144) (xy 397.197763 -158.533394)
			(xy 397.226111 -158.43765) (xy 397.262229 -158.344558) (xy 397.305873 -158.254748) (xy 397.356747 -158.168827)
			(xy 397.414508 -158.087376) (xy 397.478766 -158.010945) (xy 397.549085 -157.940052) (xy 397.586708 -157.907228)
			(xy 397.594718 -157.899644) (xy 397.603943 -157.879636) (xy 397.604488 -157.86862) (xy 397.604488 -157.791404)
			(xy 397.603952 -157.780385) (xy 397.594731 -157.760368) (xy 397.586708 -157.752796) (xy 397.549099 -157.719956)
			(xy 397.478779 -157.649064) (xy 397.41452 -157.572635) (xy 397.356758 -157.491185) (xy 397.305883 -157.405265)
			(xy 397.262238 -157.315455) (xy 397.226119 -157.222364) (xy 397.19777 -157.12662) (xy 397.177382 -157.028871)
			(xy 397.165094 -156.929777) (xy 397.160988 -156.830009) (xy 397.165093 -156.730241) (xy 397.177379 -156.631147)
			(xy 397.197766 -156.533397) (xy 397.226113 -156.437653) (xy 397.262231 -156.344561) (xy 397.305874 -156.254751)
			(xy 397.356748 -156.16883) (xy 397.414509 -156.08738) (xy 397.478766 -156.010949) (xy 397.549085 -155.940056)
			(xy 397.586708 -155.907232) (xy 397.594716 -155.899646) (xy 397.603942 -155.87964) (xy 397.604488 -155.868624)
			(xy 397.604488 -155.791408) (xy 397.603949 -155.780389) (xy 397.594731 -155.760372) (xy 397.586708 -155.7528)
			(xy 397.549103 -155.719956) (xy 397.478783 -155.649064) (xy 397.414524 -155.572635) (xy 397.356762 -155.491185)
			(xy 397.305887 -155.405266) (xy 397.262242 -155.315457) (xy 397.226123 -155.222366) (xy 397.197774 -155.126622)
			(xy 397.177386 -155.028873) (xy 397.165097 -154.92978) (xy 397.160991 -154.830012) (xy 397.165095 -154.730244)
			(xy 397.177382 -154.63115) (xy 397.197768 -154.533401) (xy 397.226115 -154.437656) (xy 397.262233 -154.344565)
			(xy 397.305876 -154.254755) (xy 397.35675 -154.168834) (xy 397.41451 -154.087383) (xy 397.478767 -154.010953)
			(xy 397.549085 -153.94006) (xy 397.586708 -153.907236) (xy 397.594714 -153.899649) (xy 397.603942 -153.879643)
			(xy 397.604488 -153.868628) (xy 397.604488 -153.791412) (xy 397.603947 -153.780393) (xy 397.59473 -153.760377)
			(xy 397.586708 -153.752804) (xy 397.550784 -153.721486) (xy 397.483413 -153.654066) (xy 397.421536 -153.58157)
			(xy 397.365535 -153.504444) (xy 397.315755 -153.423165) (xy 397.272502 -153.338232) (xy 397.236043 -153.250169)
			(xy 397.206602 -153.159517) (xy 397.184361 -153.066836) (xy 397.169456 -152.972697) (xy 397.16198 -152.877678)
			(xy 397.161512 -152.830022) (xy 397.162073 -152.779845) (xy 397.170357 -152.679834) (xy 397.186871 -152.580848)
			(xy 397.211501 -152.483564) (xy 397.24408 -152.388646) (xy 397.284385 -152.296742) (xy 397.332141 -152.208479)
			(xy 397.387021 -152.124461) (xy 397.448651 -152.045262) (xy 397.51661 -151.971421) (xy 397.590434 -151.903444)
			(xy 397.669619 -151.841794) (xy 397.753623 -151.786893) (xy 397.841874 -151.739116) (xy 397.933768 -151.698789)
			(xy 398.028678 -151.666187) (xy 398.125957 -151.641532) (xy 398.224938 -151.624994) (xy 398.324947 -151.616685)
			(xy 398.375124 -151.616156) (xy 398.422787 -151.616598) (xy 398.517818 -151.624087) (xy 398.611969 -151.639007)
			(xy 398.704659 -151.661268) (xy 398.795316 -151.690732) (xy 398.883383 -151.727218) (xy 398.968317 -151.7705)
			(xy 399.049592 -151.820312) (xy 399.12671 -151.876346) (xy 399.199193 -151.938258) (xy 399.266597 -152.005666)
			(xy 399.297906 -152.041606) (xy 399.305477 -152.049631) (xy 399.325495 -152.058848) (xy 399.336514 -152.059386)
			(xy 399.41373 -152.059386) (xy 399.424752 -152.058869) (xy 399.444768 -152.049635) (xy 399.452338 -152.041606)
			(xy 399.483634 -152.005656) (xy 399.551049 -151.938264) (xy 399.623541 -151.876366) (xy 399.700663 -151.820343)
			(xy 399.781942 -151.77054) (xy 399.866876 -151.727265) (xy 399.954941 -151.690783) (xy 400.045597 -151.66132)
			(xy 400.138284 -151.639057) (xy 400.232431 -151.624131) (xy 400.327459 -151.616634) (xy 400.37512 -151.616156)
			(xy 400.425287 -151.616687) (xy 400.525277 -151.624972) (xy 400.624243 -151.641486) (xy 400.721506 -151.666114)
			(xy 400.816405 -151.698689) (xy 400.908289 -151.738988) (xy 400.996533 -151.786735) (xy 401.080533 -151.841606)
			(xy 401.159716 -151.903225) (xy 401.23354 -151.971171) (xy 401.301503 -152.044981) (xy 401.363139 -152.12415)
			(xy 401.418028 -152.208138) (xy 401.465796 -152.296372) (xy 401.506115 -152.388247) (xy 401.53871 -152.483139)
			(xy 401.56336 -152.580397) (xy 401.579895 -152.679359) (xy 401.588202 -152.779347) (xy 401.588732 -152.829514)
			(xy 401.588732 -152.830022) (xy 401.588278 -152.877679) (xy 401.580808 -152.9727) (xy 401.565908 -153.066842)
			(xy 401.543669 -153.159525) (xy 401.514229 -153.250178) (xy 401.477769 -153.338243) (xy 401.434513 -153.423176)
			(xy 401.384729 -153.504455) (xy 401.328723 -153.581579) (xy 401.26684 -153.654072) (xy 401.199462 -153.721487)
			(xy 401.163536 -153.752804) (xy 401.155503 -153.760367) (xy 401.146292 -153.780391) (xy 401.145756 -153.791412)
			(xy 401.145756 -153.868628) (xy 401.146261 -153.879651) (xy 401.155502 -153.899669) (xy 401.163536 -153.907236)
			(xy 401.201179 -153.940039) (xy 401.271502 -154.010932) (xy 401.335763 -154.087363) (xy 401.393527 -154.168815)
			(xy 401.444405 -154.254738) (xy 401.488051 -154.34455) (xy 401.524171 -154.437644) (xy 401.55252 -154.533391)
			(xy 401.572908 -154.631143) (xy 401.585195 -154.73024) (xy 401.5893 -154.830012) (xy 401.585193 -154.929783)
			(xy 401.572904 -155.02888) (xy 401.552515 -155.126632) (xy 401.524163 -155.222378) (xy 401.488042 -155.315472)
			(xy 401.444394 -155.405283) (xy 401.393515 -155.491204) (xy 401.335749 -155.572655) (xy 401.271486 -155.649085)
			(xy 401.201162 -155.719977) (xy 401.163536 -155.7528) (xy 401.155505 -155.760364) (xy 401.146293 -155.780388)
			(xy 401.145756 -155.791408) (xy 401.145756 -155.868624) (xy 401.146263 -155.879647) (xy 401.155502 -155.899664)
			(xy 401.163536 -155.907232) (xy 401.201175 -155.94004) (xy 401.271498 -156.010932) (xy 401.335759 -156.087363)
			(xy 401.393523 -156.168815) (xy 401.444401 -156.254737) (xy 401.488047 -156.344549) (xy 401.524167 -156.437643)
			(xy 401.552517 -156.533389) (xy 401.572904 -156.631141) (xy 401.585192 -156.730238) (xy 401.589297 -156.830009)
			(xy 401.585191 -156.92978) (xy 401.572901 -157.028877) (xy 401.552512 -157.126628) (xy 401.524161 -157.222375)
			(xy 401.48804 -157.315468) (xy 401.444392 -157.405279) (xy 401.393514 -157.4912) (xy 401.335748 -157.572651)
			(xy 401.271486 -157.649081) (xy 401.201161 -157.719973) (xy 401.163536 -157.752796) (xy 401.155507 -157.760362)
			(xy 401.146294 -157.780384) (xy 401.145756 -157.791404) (xy 401.145756 -157.86862) (xy 401.146265 -157.879643)
			(xy 401.155503 -157.89966) (xy 401.163536 -157.907228) (xy 401.201171 -157.94004) (xy 401.271494 -158.010933)
			(xy 401.335755 -158.087363) (xy 401.393519 -158.168814) (xy 401.444397 -158.254736) (xy 401.488043 -158.344548)
			(xy 401.524163 -158.437641) (xy 401.552513 -158.533387) (xy 401.572901 -158.631139) (xy 401.585189 -158.730236)
			(xy 401.589294 -158.830006) (xy 401.585188 -158.929777) (xy 401.572899 -159.028874) (xy 401.55251 -159.126625)
			(xy 401.524159 -159.222371) (xy 401.488038 -159.315464) (xy 401.444391 -159.405275) (xy 401.393512 -159.491197)
			(xy 401.335747 -159.572647) (xy 401.271485 -159.649077) (xy 401.201161 -159.719969) (xy 401.163536 -159.752792)
			(xy 401.155508 -159.760359) (xy 401.146295 -159.78038) (xy 401.145756 -159.7914) (xy 401.145756 -159.868616)
			(xy 401.146267 -159.879639) (xy 401.155504 -159.899656) (xy 401.163536 -159.907224) (xy 401.201167 -159.940041)
			(xy 401.27149 -160.010933) (xy 401.335751 -160.087363) (xy 401.393516 -160.168814) (xy 401.444393 -160.254735)
			(xy 401.488039 -160.344546) (xy 401.52416 -160.43764) (xy 401.55251 -160.533386) (xy 401.572898 -160.631137)
			(xy 401.585186 -160.730233) (xy 401.589291 -160.830004) (xy 401.585185 -160.929774) (xy 401.572896 -161.028871)
			(xy 401.552508 -161.126622) (xy 401.524157 -161.222368) (xy 401.488036 -161.315461) (xy 401.444389 -161.405272)
			(xy 401.393511 -161.491193) (xy 401.335746 -161.572643) (xy 401.271485 -161.649073) (xy 401.201161 -161.719965)
			(xy 401.163536 -161.752788) (xy 401.15551 -161.760357) (xy 401.146296 -161.780377) (xy 401.145756 -161.791396)
			(xy 401.145756 -161.868612) (xy 401.146269 -161.879634) (xy 401.155504 -161.899652) (xy 401.163536 -161.90722)
			(xy 401.201163 -161.940041) (xy 401.271486 -162.010933) (xy 401.335747 -162.087363) (xy 401.393512 -162.168813)
			(xy 401.444389 -162.254734) (xy 401.488036 -162.344545) (xy 401.524156 -162.437638) (xy 401.552506 -162.533384)
			(xy 401.572894 -162.631135) (xy 401.585182 -162.730231) (xy 401.589288 -162.830001) (xy 401.585182 -162.929772)
			(xy 401.572894 -163.028867) (xy 401.552505 -163.126619) (xy 401.524155 -163.222364) (xy 401.488035 -163.315457)
			(xy 401.444388 -163.405268) (xy 401.39351 -163.491189) (xy 401.335745 -163.57264) (xy 401.271484 -163.649069)
			(xy 401.201161 -163.719961) (xy 401.163536 -163.752784) (xy 401.155512 -163.760355) (xy 401.146296 -163.780373)
			(xy 401.145756 -163.791392) (xy 401.145756 -163.868608) (xy 401.146272 -163.87963) (xy 401.155505 -163.899648)
			(xy 401.163536 -163.907216) (xy 401.201159 -163.940041) (xy 401.271482 -164.010933) (xy 401.335743 -164.087362)
			(xy 401.393508 -164.168813) (xy 401.444385 -164.254734) (xy 401.488032 -164.344544) (xy 401.524152 -164.437637)
			(xy 401.552503 -164.533382) (xy 401.572891 -164.631133) (xy 401.585179 -164.730229) (xy 401.589285 -164.829999)
			(xy 401.585179 -164.929769) (xy 401.572891 -165.028864) (xy 401.552503 -165.126615) (xy 401.524153 -165.222361)
			(xy 401.488033 -165.315454) (xy 401.444386 -165.405264) (xy 401.393509 -165.491185) (xy 401.335745 -165.572636)
			(xy 401.271484 -165.649065) (xy 401.201161 -165.719957) (xy 401.163536 -165.75278) (xy 401.155514 -165.760352)
			(xy 401.146297 -165.78037) (xy 401.145756 -165.791388) (xy 401.145756 -165.868604) (xy 401.146274 -165.879626)
			(xy 401.155505 -165.899643) (xy 401.163536 -165.907212) (xy 401.201155 -165.940042) (xy 401.271478 -166.010933)
			(xy 401.335739 -166.087362) (xy 401.393504 -166.168812) (xy 401.444381 -166.254733) (xy 401.488028 -166.344543)
			(xy 401.524149 -166.437635) (xy 401.552499 -166.53338) (xy 401.572887 -166.631131) (xy 401.585176 -166.730226)
			(xy 401.589282 -166.829996) (xy 401.585177 -166.929766) (xy 401.572889 -167.028861) (xy 401.552501 -167.126612)
			(xy 401.524151 -167.222357) (xy 401.488031 -167.31545) (xy 401.444385 -167.40526) (xy 401.393508 -167.491181)
			(xy 401.335744 -167.572632) (xy 401.271483 -167.649061) (xy 401.201161 -167.719953) (xy 401.163536 -167.752776)
			(xy 401.155516 -167.76035) (xy 401.146298 -167.780366) (xy 401.145756 -167.791384) (xy 401.145756 -167.8686)
			(xy 401.146276 -167.879622) (xy 401.155506 -167.899639) (xy 401.163536 -167.907208) (xy 401.199475 -167.938508)
			(xy 401.266845 -168.005932) (xy 401.32872 -168.07843) (xy 401.384719 -168.155558) (xy 401.434498 -168.236839)
			(xy 401.477749 -168.321774) (xy 401.514207 -168.409839) (xy 401.543646 -168.500491) (xy 401.565886 -168.593173)
			(xy 401.58079 -168.687314) (xy 401.588265 -168.782333) (xy 401.588732 -168.82999) (xy 401.588238 -168.880168)
			(xy 401.579953 -168.980183) (xy 401.563437 -169.079172) (xy 401.538804 -169.176459) (xy 401.506223 -169.271379)
			(xy 401.465915 -169.363286) (xy 401.418156 -169.45155) (xy 401.363272 -169.53557) (xy 401.301637 -169.61477)
			(xy 401.233674 -169.688611) (xy 401.159846 -169.756589) (xy 401.080657 -169.818238) (xy 400.996648 -169.873138)
			(xy 400.908392 -169.920914) (xy 400.816494 -169.961239) (xy 400.721579 -169.993839) (xy 400.624297 -170.01849)
			(xy 400.525311 -170.035024) (xy 400.425298 -170.043329) (xy 400.37512 -170.043856) (xy 400.327458 -170.043378)
			(xy 400.232428 -170.035893) (xy 400.138278 -170.020976) (xy 400.045589 -169.998719) (xy 399.954931 -169.969258)
			(xy 399.866864 -169.932776) (xy 399.781931 -169.889498) (xy 399.700655 -169.839689) (xy 399.623537 -169.783658)
			(xy 399.551052 -169.721749) (xy 399.483648 -169.654345) (xy 399.452338 -169.618406) (xy 399.444748 -169.610403)
			(xy 399.424745 -169.601173) (xy 399.41373 -169.600626) (xy 399.336514 -169.600626) (xy 399.325495 -169.601163)
			(xy 399.305478 -169.610382) (xy 399.297906 -169.618406) (xy 399.266589 -169.654337) (xy 399.199176 -169.721729)
			(xy 399.126687 -169.783628) (xy 399.049566 -169.839652) (xy 398.96829 -169.889456) (xy 398.883358 -169.932733)
			(xy 398.795295 -169.969216) (xy 398.704641 -169.998681) (xy 398.611956 -170.020947) (xy 398.517811 -170.035876)
			(xy 398.422785 -170.043376) (xy 398.375124 -170.043856) (xy 398.324958 -170.043271) (xy 398.224969 -170.034989)
			(xy 398.126005 -170.018479) (xy 398.028743 -169.993855) (xy 397.933845 -169.961284) (xy 397.841961 -169.920988)
			(xy 397.753718 -169.873244) (xy 397.669718 -169.818376) (xy 397.590535 -169.756761) (xy 397.516711 -169.688817)
			(xy 397.448748 -169.61501) (xy 397.387111 -169.535844) (xy 397.332221 -169.451859) (xy 397.284453 -169.363628)
			(xy 397.244133 -169.271755) (xy 397.211537 -169.176866) (xy 397.186887 -169.07961) (xy 397.170351 -168.98065)
			(xy 397.162042 -168.880664) (xy 397.161512 -168.830498) (xy 397.161512 -168.82999) (xy 397.161994 -168.782334)
			(xy 397.169463 -168.687314) (xy 397.184361 -168.593173) (xy 397.206598 -168.500491) (xy 397.236036 -168.409839)
			(xy 397.272493 -168.321774) (xy 397.315746 -168.236841) (xy 397.365527 -168.155562) (xy 397.42153 -168.078437)
			(xy 397.483409 -168.005943) (xy 397.550784 -167.938526) (xy 397.586708 -167.907208) (xy 397.594727 -167.899632)
			(xy 397.603947 -167.879618) (xy 397.604488 -167.8686) (xy 397.604488 -167.791384) (xy 397.603963 -167.780363)
			(xy 397.594735 -167.760347) (xy 397.586708 -167.752776) (xy 397.549079 -167.719959) (xy 397.478759 -167.649065)
			(xy 397.4145 -167.572634) (xy 397.356739 -167.491182) (xy 397.305863 -167.40526) (xy 397.262219 -167.31545)
			(xy 397.226101 -167.222357) (xy 397.197752 -167.126611) (xy 397.177365 -167.028861) (xy 397.165078 -166.929766)
			(xy 397.160973 -166.829996) (xy 368.252971 -166.829996) (xy 368.269673 -166.855241) (xy 368.322847 -166.949986)
			(xy 368.368962 -167.04836) (xy 368.407774 -167.149838) (xy 368.439075 -167.253878) (xy 368.462698 -167.359925)
			(xy 368.478517 -167.467414) (xy 368.486448 -167.575771) (xy 368.486944 -167.630094) (xy 368.486448 -167.684417)
			(xy 368.478517 -167.792774) (xy 368.462698 -167.900263) (xy 368.439075 -168.00631) (xy 368.407774 -168.11035)
			(xy 368.368962 -168.211828) (xy 368.322847 -168.310202) (xy 368.269673 -168.404947) (xy 368.209725 -168.495558)
			(xy 368.143323 -168.581552) (xy 368.070821 -168.662469) (xy 367.992606 -168.737877) (xy 367.909095 -168.807376)
			(xy 367.820734 -168.870593) (xy 367.727994 -168.927191) (xy 367.63137 -168.976869) (xy 367.531378 -169.019361)
			(xy 367.42855 -169.054441) (xy 367.323436 -169.081921) (xy 367.216597 -169.101656) (xy 367.108602 -169.113539)
			(xy 367.000028 -169.117507) (xy 366.891454 -169.113539) (xy 366.783459 -169.101656) (xy 366.67662 -169.081921)
			(xy 366.571506 -169.054441) (xy 366.468678 -169.019361) (xy 366.368686 -168.976869) (xy 366.272062 -168.927191)
			(xy 366.179322 -168.870593) (xy 366.090961 -168.807376) (xy 366.00745 -168.737877) (xy 365.929235 -168.662469)
			(xy 365.856733 -168.581552) (xy 365.790331 -168.495558) (xy 365.730383 -168.404947) (xy 365.677209 -168.310202)
			(xy 365.631094 -168.211828) (xy 365.592282 -168.11035) (xy 365.560981 -168.00631) (xy 365.537358 -167.900263)
			(xy 365.521539 -167.792774) (xy 365.513608 -167.684417) (xy 360.629411 -167.684417) (xy 360.630431 -167.689148)
			(xy 360.678475 -167.873662) (xy 360.734307 -168.05597) (xy 360.797826 -168.235745) (xy 360.868918 -168.412662)
			(xy 360.947454 -168.586403) (xy 361.033294 -168.756653) (xy 361.126281 -168.923107) (xy 361.22625 -169.085465)
			(xy 361.333019 -169.243433) (xy 361.446396 -169.396728) (xy 361.566177 -169.545073) (xy 361.692146 -169.6882)
			(xy 361.824076 -169.825852) (xy 361.961729 -169.957781) (xy 362.104858 -170.083749) (xy 362.253204 -170.203529)
			(xy 362.406499 -170.316905) (xy 362.564469 -170.423672) (xy 362.726827 -170.523639) (xy 362.893282 -170.616625)
			(xy 363.063534 -170.702463) (xy 363.237275 -170.780998) (xy 363.414192 -170.852088) (xy 363.593968 -170.915605)
			(xy 363.776277 -170.971436) (xy 363.960791 -171.019478) (xy 364.147178 -171.059646) (xy 364.335102 -171.091868)
			(xy 364.524225 -171.116085) (xy 364.714204 -171.132253) (xy 364.904699 -171.140344) (xy 365.000032 -171.140882)
			(xy 403.999954 -171.140882) (xy 404.095288 -171.140384) (xy 404.285785 -171.132294) (xy 404.475767 -171.116126)
			(xy 404.664891 -171.091909) (xy 404.852817 -171.059688) (xy 405.039206 -171.01952) (xy 405.223723 -170.971477)
			(xy 405.406034 -170.915647) (xy 405.585812 -170.852129) (xy 405.762731 -170.781038) (xy 405.936475 -170.702503)
			(xy 406.106728 -170.616665) (xy 406.273185 -170.523678) (xy 406.435545 -170.423711) (xy 406.593517 -170.316942)
			(xy 406.746814 -170.203565) (xy 406.895162 -170.083785) (xy 407.038292 -169.957816) (xy 407.175947 -169.825886)
			(xy 407.307879 -169.688232) (xy 407.43385 -169.545103) (xy 407.553632 -169.396757) (xy 407.667011 -169.243461)
			(xy 407.773781 -169.085491) (xy 407.873751 -168.923132) (xy 407.96674 -168.756676) (xy 408.05258 -168.586423)
			(xy 408.131117 -168.412681) (xy 408.20221 -168.235762) (xy 408.26573 -168.055986) (xy 408.321562 -167.873675)
			(xy 408.369607 -167.689159) (xy 408.409778 -167.50277) (xy 408.442001 -167.314844) (xy 408.46622 -167.12572)
			(xy 408.48239 -166.935739) (xy 408.490483 -166.745242) (xy 408.490928 -166.649908) (xy 408.490928 -163.299902)
			(xy 408.491427 -163.194368) (xy 408.499512 -162.983455) (xy 408.515669 -162.773006) (xy 408.539875 -162.563331)
			(xy 408.572094 -162.354737) (xy 408.61228 -162.14753) (xy 408.660372 -161.942014) (xy 408.716302 -161.738491)
			(xy 408.779985 -161.53726) (xy 408.85133 -161.338616) (xy 408.930231 -161.14285) (xy 409.016573 -160.95025)
			(xy 409.110228 -160.761098) (xy 409.21106 -160.575672) (xy 409.31892 -160.394245) (xy 409.43365 -160.217082)
			(xy 409.555081 -160.044444) (xy 409.683036 -159.876583) (xy 409.817327 -159.713747) (xy 409.957756 -159.556174)
			(xy 410.104118 -159.404096) (xy 410.256198 -159.257735) (xy 410.413771 -159.117306) (xy 410.576608 -158.983016)
			(xy 410.74447 -158.855062) (xy 410.917109 -158.733632) (xy 411.094272 -158.618903) (xy 411.2757 -158.511044)
			(xy 411.461126 -158.410213) (xy 411.650279 -158.316559) (xy 411.842879 -158.230219) (xy 412.038645 -158.151319)
			(xy 412.23729 -158.079975) (xy 412.438522 -158.016293) (xy 412.642045 -157.960365) (xy 412.847561 -157.912273)
			(xy 413.054769 -157.872089) (xy 413.263363 -157.839871) (xy 413.473038 -157.815666) (xy 413.683487 -157.79951)
			(xy 413.8944 -157.791427) (xy 413.999934 -157.790896) (xy 434.999892 -157.790896) (xy 435.095226 -157.79039)
			(xy 435.285721 -157.782299) (xy 435.475702 -157.766129) (xy 435.664825 -157.741911) (xy 435.85275 -157.709689)
			(xy 436.039137 -157.66952) (xy 436.223653 -157.621476) (xy 436.405963 -157.565645) (xy 436.585739 -157.502126)
			(xy 436.762657 -157.431035) (xy 436.936399 -157.3525) (xy 437.106651 -157.266661) (xy 437.273106 -157.173674)
			(xy 437.435465 -157.073706) (xy 437.593435 -156.966938) (xy 437.746732 -156.853561) (xy 437.895078 -156.73378)
			(xy 438.038207 -156.607812) (xy 438.175861 -156.475882) (xy 438.307792 -156.338229) (xy 438.433761 -156.195101)
			(xy 438.553543 -156.046755) (xy 438.66692 -155.89346) (xy 438.77369 -155.73549) (xy 438.873659 -155.573132)
			(xy 438.966647 -155.406677) (xy 439.052487 -155.236426) (xy 439.131023 -155.062685) (xy 439.202116 -154.885767)
			(xy 439.265635 -154.705991) (xy 439.321468 -154.523682) (xy 439.369513 -154.339167) (xy 439.409683 -154.152779)
			(xy 439.441907 -153.964854) (xy 439.466126 -153.775732) (xy 439.482297 -153.585751) (xy 439.49039 -153.395256)
			(xy 439.490866 -153.299922) (xy 439.490866 -136.77011) (xy 439.491377 -136.664578) (xy 439.499472 -136.453669)
			(xy 439.515639 -136.243225) (xy 439.539854 -136.033554) (xy 439.572082 -135.824965) (xy 439.612275 -135.617763)
			(xy 439.660375 -135.412253) (xy 439.71631 -135.208736) (xy 439.78 -135.00751) (xy 439.851349 -134.808871)
			(xy 439.930254 -134.613111) (xy 440.016599 -134.420517) (xy 440.110257 -134.231371) (xy 440.211091 -134.045951)
			(xy 440.318953 -133.864528) (xy 440.433684 -133.687371) (xy 440.555116 -133.514737) (xy 440.68307 -133.346881)
			(xy 440.81736 -133.184049) (xy 440.957788 -133.026479) (xy 441.104148 -132.874404) (xy 441.256225 -132.728046)
			(xy 441.413796 -132.58762) (xy 441.576629 -132.453332) (xy 441.744487 -132.325379) (xy 441.917122 -132.203949)
			(xy 442.094281 -132.08922) (xy 442.275704 -131.981361) (xy 442.461126 -131.880529) (xy 442.650273 -131.786873)
			(xy 442.842868 -131.70053) (xy 443.038629 -131.621627) (xy 443.237269 -131.55028) (xy 443.438495 -131.486593)
			(xy 443.642013 -131.430659) (xy 443.847524 -131.382562) (xy 444.054726 -131.342371) (xy 444.263316 -131.310146)
			(xy 444.472987 -131.285933) (xy 444.683431 -131.269768) (xy 444.89434 -131.261676) (xy 444.999872 -131.261104)
			(xy 471.000074 -131.261104) (xy 471.095408 -131.260599) (xy 471.285904 -131.252508) (xy 471.475885 -131.236339)
			(xy 471.665009 -131.212122) (xy 471.852935 -131.1799) (xy 472.039323 -131.139731) (xy 472.223839 -131.091688)
			(xy 472.40615 -131.035857) (xy 472.585927 -130.972339) (xy 472.762846 -130.901249) (xy 472.936588 -130.822713)
			(xy 473.106841 -130.736875) (xy 473.273298 -130.643888) (xy 473.435658 -130.543921) (xy 473.593628 -130.437152)
			(xy 473.746926 -130.323776) (xy 473.895273 -130.203995) (xy 474.038403 -130.078027) (xy 474.176057 -129.946097)
			(xy 474.307989 -129.808444) (xy 474.433959 -129.665316) (xy 474.553742 -129.51697) (xy 474.66712 -129.363674)
			(xy 474.77389 -129.205705) (xy 474.87386 -129.043346) (xy 474.966849 -128.876891) (xy 475.052689 -128.706639)
			(xy 475.131227 -128.532897) (xy 475.20232 -128.355979) (xy 475.26584 -128.176203) (xy 475.321673 -127.993893)
			(xy 475.369718 -127.809378) (xy 475.409889 -127.62299) (xy 475.442114 -127.435064) (xy 475.466333 -127.245941)
			(xy 475.482504 -127.05596) (xy 475.490597 -126.865464) (xy 475.491048 -126.77013) (xy 475.491048 -21.770086)
			(xy 475.490549 -21.674753) (xy 475.482456 -21.484258) (xy 475.466286 -21.294279) (xy 475.442067 -21.105157)
			(xy 475.409844 -20.917234) (xy 475.369674 -20.730847) (xy 475.321629 -20.546333) (xy 475.265797 -20.364024)
			(xy 475.202278 -20.18425) (xy 475.131186 -20.007333) (xy 475.05265 -19.833593) (xy 474.966811 -19.663342)
			(xy 474.873823 -19.496888) (xy 474.773855 -19.334531) (xy 474.667086 -19.176562) (xy 474.553708 -19.023267)
			(xy 474.433927 -18.874923) (xy 474.307958 -18.731795) (xy 474.176028 -18.594143) (xy 474.038375 -18.462215)
			(xy 473.895247 -18.336247) (xy 473.746901 -18.216467) (xy 473.593605 -18.103091) (xy 473.435636 -17.996324)
			(xy 473.273277 -17.896357) (xy 473.106823 -17.803371) (xy 472.936571 -17.717533) (xy 472.76283 -17.638998)
			(xy 472.585913 -17.567908) (xy 472.406138 -17.50439) (xy 472.223829 -17.44856) (xy 472.039314 -17.400517)
			(xy 471.852927 -17.360349) (xy 471.665003 -17.328127) (xy 471.475881 -17.30391) (xy 471.285902 -17.287741)
			(xy 471.095407 -17.27965) (xy 471.000074 -17.279112) (xy 444.999872 -17.279112) (xy 444.894339 -17.278602)
			(xy 444.683429 -17.27051) (xy 444.472984 -17.254345) (xy 444.263312 -17.230132) (xy 444.054721 -17.197906)
			(xy 443.847518 -17.157714) (xy 443.642006 -17.109616) (xy 443.438487 -17.053682) (xy 443.237259 -16.989994)
			(xy 443.038619 -16.918645) (xy 442.842857 -16.839741) (xy 442.650261 -16.753397) (xy 442.461113 -16.65974)
			(xy 442.275691 -16.558907) (xy 442.094267 -16.451046) (xy 441.917108 -16.336315) (xy 441.744473 -16.214883)
			(xy 441.576615 -16.086929) (xy 441.413781 -15.952639) (xy 441.25621 -15.812211) (xy 441.104134 -15.665851)
			(xy 440.957774 -15.513774) (xy 440.817347 -15.356202) (xy 440.683058 -15.193368) (xy 440.555104 -15.02551)
			(xy 440.433673 -14.852874) (xy 440.318943 -14.675714) (xy 440.211083 -14.49429) (xy 440.11025 -14.308867)
			(xy 440.016594 -14.119719) (xy 439.93025 -13.927123) (xy 439.851347 -13.73136) (xy 439.779999 -13.53272)
			(xy 439.716312 -13.331492) (xy 439.660379 -13.127973) (xy 439.612281 -12.922461) (xy 439.572091 -12.715257)
			(xy 439.539865 -12.506666) (xy 439.515653 -12.296994) (xy 439.499489 -12.086549) (xy 439.491397 -11.875639)
			(xy 439.490866 -11.770106) (xy 439.490866 -4.99999) (xy 439.49036 -4.904657) (xy 439.482267 -4.714162)
			(xy 439.466097 -4.524183) (xy 439.441879 -4.335061) (xy 439.409656 -4.147137) (xy 439.369486 -3.96075)
			(xy 439.321442 -3.776236) (xy 439.26561 -3.593927) (xy 439.202091 -3.414153) (xy 439.130999 -3.237235)
			(xy 439.052463 -3.063495) (xy 438.966624 -2.893244) (xy 438.873637 -2.72679) (xy 438.773669 -2.564432)
			(xy 438.6669 -2.406464) (xy 438.553523 -2.253169) (xy 438.433742 -2.104824) (xy 438.307774 -1.961696)
			(xy 438.175844 -1.824043) (xy 438.038191 -1.692114) (xy 437.895063 -1.566146) (xy 437.746717 -1.446366)
			(xy 437.593422 -1.33299) (xy 437.435453 -1.226222) (xy 437.273094 -1.126254) (xy 437.10664 -1.033267)
			(xy 436.936389 -0.947429) (xy 436.762648 -0.868894) (xy 436.585731 -0.797803) (xy 436.405955 -0.734284)
			(xy 436.223646 -0.678453) (xy 436.039132 -0.63041) (xy 435.852745 -0.590241) (xy 435.664821 -0.558018)
			(xy 435.475699 -0.533801) (xy 435.28572 -0.517631) (xy 435.095225 -0.50954) (xy 434.999892 -0.509016)
			(xy 4.99999 -0.509016) (xy 4.904657 -0.509522) (xy 4.714162 -0.517614) (xy 4.524182 -0.533784) (xy 4.335059 -0.558002)
			(xy 4.147135 -0.590225) (xy 3.960748 -0.630394) (xy 3.776233 -0.678438) (xy 3.593924 -0.73427) (xy 3.414149 -0.797788)
			(xy 3.237231 -0.86888) (xy 3.06349 -0.947415) (xy 2.893239 -1.033254) (xy 2.726784 -1.126242) (xy 2.564426 -1.22621)
			(xy 2.406456 -1.332978) (xy 2.253161 -1.446355) (xy 2.104815 -1.566136) (xy 1.961687 -1.692104) (xy 1.824034 -1.824034)
			(xy 1.692104 -1.961687) (xy 1.566136 -2.104815) (xy 1.446355 -2.253161) (xy 1.332978 -2.406456) (xy 1.22621 -2.564426)
			(xy 1.126242 -2.726784) (xy 1.033254 -2.893239) (xy 0.947415 -3.06349) (xy 0.86888 -3.237231) (xy 0.797788 -3.414149)
			(xy 0.73427 -3.593924) (xy 0.678438 -3.776233) (xy 0.646137 -3.900286) (xy 59.465106 -3.900286) (xy 59.471831 -3.783378)
			(xy 59.486516 -3.667201) (xy 59.509092 -3.552297) (xy 59.539454 -3.4392) (xy 59.577461 -3.328438)
			(xy 59.622935 -3.220527) (xy 59.675664 -3.115969) (xy 59.735404 -3.015253) (xy 59.801875 -2.918846)
			(xy 59.874768 -2.827198) (xy 59.953743 -2.740736) (xy 60.038433 -2.659864) (xy 60.128442 -2.584957)
			(xy 60.223352 -2.516365) (xy 60.32272 -2.454408) (xy 60.426083 -2.399373) (xy 60.532959 -2.351518)
			(xy 60.642851 -2.311065) (xy 60.755247 -2.278204) (xy 60.869623 -2.253086) (xy 60.985446 -2.23583)
			(xy 61.102176 -2.226514) (xy 61.219269 -2.225184) (xy 61.336181 -2.231845) (xy 61.452366 -2.246466)
			(xy 61.567283 -2.268978) (xy 61.680396 -2.299278) (xy 61.791179 -2.337224) (xy 61.899115 -2.382638)
			(xy 62.003702 -2.43531) (xy 62.104452 -2.494994) (xy 62.200895 -2.561413) (xy 62.292583 -2.634255)
			(xy 62.336172 -2.67335) (xy 62.343731 -2.679658) (xy 62.362196 -2.686443) (xy 62.381859 -2.68581)
			(xy 62.391036 -2.68224) (xy 62.476126 -2.644394) (xy 62.484905 -2.639997) (xy 62.498544 -2.625901)
			(xy 62.505902 -2.607719) (xy 62.506352 -2.597912) (xy 62.506352 -2.590038) (xy 62.506852 -2.540721)
			(xy 62.514857 -2.442413) (xy 62.530814 -2.345078) (xy 62.554617 -2.24936) (xy 62.58611 -2.155889)
			(xy 62.625084 -2.065282) (xy 62.671283 -1.978137) (xy 62.724402 -1.895029) (xy 62.784091 -1.816506)
			(xy 62.849955 -1.743086) (xy 62.92156 -1.675253) (xy 62.998434 -1.613455) (xy 63.08007 -1.5581) (xy 63.165929 -1.509552)
			(xy 63.255444 -1.468132) (xy 63.348026 -1.434114) (xy 63.443063 -1.407721) (xy 63.539928 -1.389129)
			(xy 63.637983 -1.378458) (xy 63.73658 -1.375781) (xy 63.83507 -1.381114) (xy 63.932801 -1.394422)
			(xy 64.029131 -1.415618) (xy 64.123422 -1.444561) (xy 64.215054 -1.481062) (xy 64.303421 -1.524878)
			(xy 64.38794 -1.575721) (xy 64.468055 -1.633256) (xy 64.543236 -1.697102) (xy 64.612988 -1.76684)
			(xy 64.67685 -1.842008) (xy 64.734401 -1.922111) (xy 64.785262 -2.00662) (xy 64.829096 -2.094978)
			(xy 64.865616 -2.186602) (xy 64.894579 -2.280887) (xy 64.915794 -2.377212) (xy 64.929123 -2.474941)
			(xy 64.934476 -2.57343) (xy 64.934028 -2.590038) (xy 65.045593 -2.590038) (xy 65.049633 -2.491055)
			(xy 65.061728 -2.392732) (xy 65.081798 -2.295721) (xy 65.109708 -2.200669) (xy 65.145272 -2.108208)
			(xy 65.188255 -2.018953) (xy 65.23837 -1.933499) (xy 65.295283 -1.852414) (xy 65.358616 -1.776238)
			(xy 65.427947 -1.705478) (xy 65.502816 -1.640604) (xy 65.582723 -1.582049) (xy 65.667137 -1.530201)
			(xy 65.755496 -1.485407) (xy 65.847212 -1.447964) (xy 65.941675 -1.418121) (xy 66.038256 -1.396077)
			(xy 66.136313 -1.381978) (xy 66.235193 -1.375919) (xy 66.334237 -1.37794) (xy 66.432787 -1.388027)
			(xy 66.530187 -1.406113) (xy 66.625789 -1.432078) (xy 66.718956 -1.46575) (xy 66.809069 -1.506903)
			(xy 66.895527 -1.555264) (xy 66.977756 -1.610511) (xy 67.055208 -1.672277) (xy 67.127368 -1.740151)
			(xy 67.193756 -1.81368) (xy 67.253929 -1.892376) (xy 67.307487 -1.975715) (xy 67.354075 -2.063142)
			(xy 67.393381 -2.154075) (xy 67.425145 -2.24791) (xy 67.449154 -2.344021) (xy 67.46525 -2.44177)
			(xy 67.473325 -2.540506) (xy 67.47383 -2.590038) (xy 67.473325 -2.63957) (xy 67.472584 -2.648633)
			(xy 74.704694 -2.648633) (xy 74.704694 -2.531443) (xy 74.712691 -2.414525) (xy 74.728649 -2.298426)
			(xy 74.752492 -2.183686) (xy 74.78411 -2.070841) (xy 74.823355 -1.960417) (xy 74.870043 -1.852928)
			(xy 74.923959 -1.748876) (xy 74.984849 -1.648746) (xy 75.052431 -1.553005) (xy 75.126389 -1.462099)
			(xy 75.206377 -1.376451) (xy 75.292025 -1.296463) (xy 75.382931 -1.222505) (xy 75.478672 -1.154923)
			(xy 75.578802 -1.094033) (xy 75.682854 -1.040117) (xy 75.790343 -0.993429) (xy 75.900767 -0.954184)
			(xy 76.013612 -0.922566) (xy 76.128352 -0.898723) (xy 76.244451 -0.882765) (xy 76.361369 -0.874768)
			(xy 76.478559 -0.874768) (xy 76.595477 -0.882765) (xy 76.711576 -0.898723) (xy 76.826316 -0.922566)
			(xy 76.939161 -0.954184) (xy 77.049585 -0.993429) (xy 77.157074 -1.040117) (xy 77.261126 -1.094033)
			(xy 77.361256 -1.154923) (xy 77.456997 -1.222505) (xy 77.547903 -1.296463) (xy 77.633551 -1.376451)
			(xy 77.713539 -1.462099) (xy 77.787497 -1.553005) (xy 77.855079 -1.648746) (xy 77.915969 -1.748876)
			(xy 77.969885 -1.852928) (xy 78.016573 -1.960417) (xy 78.055818 -2.070841) (xy 78.087436 -2.183686)
			(xy 78.111279 -2.298426) (xy 78.127237 -2.414525) (xy 78.135234 -2.531443) (xy 78.135734 -2.590038)
			(xy 78.135234 -2.648633) (xy 78.127237 -2.765551) (xy 78.111279 -2.88165) (xy 78.087436 -2.99639)
			(xy 78.055818 -3.109235) (xy 78.016573 -3.219659) (xy 77.969885 -3.327148) (xy 77.915969 -3.4312)
			(xy 77.855079 -3.53133) (xy 77.787497 -3.627071) (xy 77.713539 -3.717977) (xy 77.633551 -3.803625)
			(xy 77.547903 -3.883613) (xy 77.456997 -3.957571) (xy 77.361256 -4.025153) (xy 77.261126 -4.086043)
			(xy 77.157074 -4.139959) (xy 77.049585 -4.186647) (xy 76.939161 -4.225892) (xy 76.826316 -4.25751)
			(xy 76.711576 -4.281353) (xy 76.595477 -4.297311) (xy 76.478559 -4.305308) (xy 76.361369 -4.305308)
			(xy 76.244451 -4.297311) (xy 76.128352 -4.281353) (xy 76.013612 -4.25751) (xy 75.900767 -4.225892)
			(xy 75.790343 -4.186647) (xy 75.682854 -4.139959) (xy 75.578802 -4.086043) (xy 75.478672 -4.025153)
			(xy 75.382931 -3.957571) (xy 75.292025 -3.883613) (xy 75.206377 -3.803625) (xy 75.126389 -3.717977)
			(xy 75.052431 -3.627071) (xy 74.984849 -3.53133) (xy 74.923959 -3.4312) (xy 74.870043 -3.327148)
			(xy 74.823355 -3.219659) (xy 74.78411 -3.109235) (xy 74.752492 -2.99639) (xy 74.728649 -2.88165)
			(xy 74.712691 -2.765551) (xy 74.704694 -2.648633) (xy 67.472584 -2.648633) (xy 67.46525 -2.738306)
			(xy 67.449154 -2.836055) (xy 67.425145 -2.932166) (xy 67.393381 -3.026001) (xy 67.354075 -3.116934)
			(xy 67.307487 -3.204361) (xy 67.253929 -3.2877) (xy 67.193756 -3.366396) (xy 67.127368 -3.439925)
			(xy 67.055208 -3.507799) (xy 66.977756 -3.569565) (xy 66.895527 -3.624812) (xy 66.809069 -3.673173)
			(xy 66.718956 -3.714326) (xy 66.625789 -3.747998) (xy 66.530187 -3.773963) (xy 66.432787 -3.792049)
			(xy 66.334237 -3.802136) (xy 66.235193 -3.804157) (xy 66.136313 -3.798098) (xy 66.038256 -3.783999)
			(xy 65.941675 -3.761955) (xy 65.847212 -3.732112) (xy 65.755496 -3.694669) (xy 65.667137 -3.649875)
			(xy 65.582723 -3.598027) (xy 65.502816 -3.539472) (xy 65.427947 -3.474598) (xy 65.358616 -3.403838)
			(xy 65.295283 -3.327662) (xy 65.23837 -3.246577) (xy 65.188255 -3.161123) (xy 65.145272 -3.071868)
			(xy 65.109708 -2.979407) (xy 65.081798 -2.884355) (xy 65.061728 -2.787344) (xy 65.049633 -2.689021)
			(xy 65.045593 -2.590038) (xy 64.934028 -2.590038) (xy 64.931819 -2.672028) (xy 64.921169 -2.770085)
			(xy 64.902596 -2.866954) (xy 64.876223 -2.961996) (xy 64.842223 -3.054585) (xy 64.800822 -3.144109)
			(xy 64.752292 -3.229978) (xy 64.696954 -3.311625) (xy 64.635172 -3.388512) (xy 64.567354 -3.460131)
			(xy 64.493947 -3.52601) (xy 64.415436 -3.585715) (xy 64.332339 -3.638851) (xy 64.245203 -3.685068)
			(xy 64.154604 -3.724061) (xy 64.06114 -3.755573) (xy 63.965427 -3.779396) (xy 63.868095 -3.795372)
			(xy 63.769789 -3.803397) (xy 63.720472 -3.803904) (xy 63.719964 -3.803904) (xy 63.667939 -3.803349)
			(xy 63.564271 -3.794428) (xy 63.461748 -3.776665) (xy 63.361123 -3.750189) (xy 63.263133 -3.715195)
			(xy 63.1685 -3.67194) (xy 63.077917 -3.620741) (xy 63.034672 -3.591814) (xy 63.022226 -3.583178)
			(xy 62.992 -3.58267) (xy 62.887352 -3.647948) (xy 62.874652 -3.67538) (xy 62.876938 -3.690366) (xy 62.88499 -3.748362)
			(xy 62.894112 -3.865108) (xy 62.895249 -3.982203) (xy 62.888395 -4.099104) (xy 62.873582 -4.215265)
			(xy 62.85088 -4.330144) (xy 62.820393 -4.443207) (xy 62.782264 -4.553927) (xy 62.736672 -4.661788)
			(xy 62.683827 -4.766287) (xy 62.623976 -4.866938) (xy 62.557399 -4.963272) (xy 62.484405 -5.054839)
			(xy 62.405335 -5.141214) (xy 62.320556 -5.221993) (xy 62.230464 -5.296801) (xy 62.178873 -5.334)
			(xy 81.787492 -5.334) (xy 81.787492 -5.333492) (xy 81.788098 -5.28716) (xy 81.797769 -5.195002) (xy 81.816965 -5.104348)
			(xy 81.845477 -5.016179) (xy 81.863692 -4.973574) (xy 81.867498 -4.963632) (xy 81.867498 -4.942368)
			(xy 81.863692 -4.932426) (xy 81.845447 -4.889764) (xy 81.816903 -4.801471) (xy 81.79771 -4.710686)
			(xy 81.788077 -4.618396) (xy 81.787492 -4.572) (xy 81.788075 -4.525604) (xy 81.79772 -4.433316) (xy 81.816916 -4.342532)
			(xy 81.845454 -4.254239) (xy 81.863692 -4.211574) (xy 81.867498 -4.201632) (xy 81.867498 -4.180368)
			(xy 81.863692 -4.170426) (xy 81.84547 -4.127823) (xy 81.816952 -4.039656) (xy 81.79776 -3.949) (xy 81.7881 -3.85684)
			(xy 81.787492 -3.810508) (xy 81.787492 -3.81) (xy 81.787967 -3.768898) (xy 81.795552 -3.687043) (xy 81.810657 -3.606238)
			(xy 81.833153 -3.527171) (xy 81.862849 -3.450517) (xy 81.899491 -3.37693) (xy 81.942766 -3.307038)
			(xy 81.992306 -3.241437) (xy 82.047687 -3.180687) (xy 82.108437 -3.125306) (xy 82.174038 -3.075766)
			(xy 82.24393 -3.032491) (xy 82.317517 -2.995849) (xy 82.394171 -2.966153) (xy 82.473238 -2.943657)
			(xy 82.554043 -2.928552) (xy 82.635898 -2.920967) (xy 82.677 -2.920492) (xy 82.677508 -2.920492)
			(xy 82.72384 -2.921098) (xy 82.815998 -2.930769) (xy 82.906652 -2.949965) (xy 82.994821 -2.978477)
			(xy 83.037426 -2.996692) (xy 83.047368 -3.000498) (xy 83.068632 -3.000498) (xy 83.078574 -2.996692)
			(xy 83.121236 -2.978447) (xy 83.209529 -2.949903) (xy 83.300314 -2.93071) (xy 83.392604 -2.921077)
			(xy 83.439 -2.920492) (xy 83.485396 -2.921075) (xy 83.577684 -2.93072) (xy 83.668468 -2.949916) (xy 83.756761 -2.978454)
			(xy 83.799426 -2.996692) (xy 83.809368 -3.000498) (xy 83.830632 -3.000498) (xy 83.840574 -2.996692)
			(xy 83.883236 -2.978447) (xy 83.971529 -2.949903) (xy 84.062314 -2.93071) (xy 84.154604 -2.921077)
			(xy 84.201 -2.920492) (xy 84.247396 -2.921075) (xy 84.339684 -2.93072) (xy 84.430468 -2.949916) (xy 84.518761 -2.978454)
			(xy 84.561426 -2.996692) (xy 84.571368 -3.000498) (xy 84.592632 -3.000498) (xy 84.602574 -2.996692)
			(xy 84.645236 -2.978447) (xy 84.733529 -2.949903) (xy 84.824314 -2.93071) (xy 84.916604 -2.921077)
			(xy 84.963 -2.920492) (xy 85.009396 -2.921075) (xy 85.101684 -2.93072) (xy 85.192468 -2.949916) (xy 85.280761 -2.978454)
			(xy 85.323426 -2.996692) (xy 85.333368 -3.000498) (xy 85.354632 -3.000498) (xy 85.364574 -2.996692)
			(xy 85.407236 -2.978447) (xy 85.495529 -2.949903) (xy 85.586314 -2.93071) (xy 85.678604 -2.921077)
			(xy 85.725 -2.920492) (xy 85.771396 -2.921075) (xy 85.863684 -2.93072) (xy 85.954468 -2.949916) (xy 86.042761 -2.978454)
			(xy 86.085426 -2.996692) (xy 86.095368 -3.000498) (xy 86.116632 -3.000498) (xy 86.126574 -2.996692)
			(xy 86.169177 -2.97847) (xy 86.257344 -2.949952) (xy 86.348 -2.93076) (xy 86.44016 -2.9211) (xy 86.486492 -2.920492)
			(xy 86.487 -2.920492) (xy 86.528102 -2.920967) (xy 86.609957 -2.928552) (xy 86.690762 -2.943657)
			(xy 86.769829 -2.966153) (xy 86.846483 -2.995849) (xy 86.92007 -3.032491) (xy 86.989962 -3.075766)
			(xy 87.055563 -3.125306) (xy 87.116313 -3.180687) (xy 87.171694 -3.241437) (xy 87.221234 -3.307038)
			(xy 87.264509 -3.37693) (xy 87.301151 -3.450517) (xy 87.330847 -3.527171) (xy 87.353343 -3.606238)
			(xy 87.368448 -3.687043) (xy 87.376033 -3.768898) (xy 87.376508 -3.81) (xy 87.376508 -3.810508) (xy 87.375902 -3.85684)
			(xy 87.366231 -3.948998) (xy 87.347035 -4.039652) (xy 87.318523 -4.127821) (xy 87.300308 -4.170426)
			(xy 87.296502 -4.180368) (xy 87.296502 -4.201632) (xy 87.300308 -4.211574) (xy 87.318553 -4.254236)
			(xy 87.347097 -4.342529) (xy 87.36629 -4.433314) (xy 87.375923 -4.525604) (xy 87.376508 -4.572) (xy 87.375925 -4.618396)
			(xy 87.36628 -4.710684) (xy 87.347084 -4.801468) (xy 87.318546 -4.889761) (xy 87.300308 -4.932426)
			(xy 87.296502 -4.942368) (xy 87.296502 -4.963632) (xy 87.300308 -4.973574) (xy 87.31853 -5.016177)
			(xy 87.347048 -5.104344) (xy 87.36624 -5.195) (xy 87.3759 -5.28716) (xy 87.376508 -5.333492) (xy 87.376508 -5.334)
			(xy 87.376285 -5.353304) (xy 354.006912 -5.353304) (xy 354.006912 -5.352796) (xy 354.007518 -5.306464)
			(xy 354.017189 -5.214306) (xy 354.036385 -5.123652) (xy 354.064897 -5.035483) (xy 354.083112 -4.992878)
			(xy 354.086914 -4.982935) (xy 354.086915 -4.961672) (xy 354.083112 -4.95173) (xy 354.06487 -4.909067)
			(xy 354.036325 -4.820775) (xy 354.017131 -4.72999) (xy 354.007497 -4.6377) (xy 354.006912 -4.591304)
			(xy 354.007495 -4.544908) (xy 354.017139 -4.45262) (xy 354.036335 -4.361836) (xy 354.064874 -4.273543)
			(xy 354.083112 -4.230878) (xy 354.086914 -4.220935) (xy 354.086915 -4.199672) (xy 354.083112 -4.18973)
			(xy 354.064892 -4.147126) (xy 354.036374 -4.058959) (xy 354.01718 -3.968304) (xy 354.00752 -3.876144)
			(xy 354.006912 -3.829812) (xy 354.006912 -3.829304) (xy 354.007356 -3.7882) (xy 354.014941 -3.706344)
			(xy 354.030046 -3.625536) (xy 354.052543 -3.546467) (xy 354.08224 -3.469811) (xy 354.118884 -3.396222)
			(xy 354.162161 -3.326328) (xy 354.211702 -3.260725) (xy 354.267085 -3.199974) (xy 354.327838 -3.144592)
			(xy 354.393441 -3.095051) (xy 354.463336 -3.051776) (xy 354.536925 -3.015134) (xy 354.613582 -2.985438)
			(xy 354.692652 -2.962943) (xy 354.773459 -2.947839) (xy 354.855316 -2.940255) (xy 354.89642 -2.939796)
			(xy 354.896928 -2.939796) (xy 354.94326 -2.940395) (xy 355.035418 -2.950068) (xy 355.126072 -2.969266)
			(xy 355.214241 -2.99778) (xy 355.256846 -3.015996) (xy 355.266788 -3.019802) (xy 355.288052 -3.019802)
			(xy 355.297994 -3.015996) (xy 355.340654 -2.997745) (xy 355.428947 -2.969202) (xy 355.519733 -2.950011)
			(xy 355.612024 -2.94038) (xy 355.65842 -2.939796) (xy 355.704815 -2.940407) (xy 355.797102 -2.950044)
			(xy 355.887886 -2.969231) (xy 355.97618 -2.997762) (xy 356.018846 -3.015996) (xy 356.028788 -3.019802)
			(xy 356.050052 -3.019802) (xy 356.059994 -3.015996) (xy 356.102654 -2.997745) (xy 356.190947 -2.969202)
			(xy 356.281733 -2.950011) (xy 356.374024 -2.94038) (xy 356.42042 -2.939796) (xy 356.466815 -2.940407)
			(xy 356.559102 -2.950044) (xy 356.649886 -2.969231) (xy 356.73818 -2.997762) (xy 356.780846 -3.015996)
			(xy 356.790788 -3.019802) (xy 356.812052 -3.019802) (xy 356.821994 -3.015996) (xy 356.864654 -2.997745)
			(xy 356.952947 -2.969202) (xy 357.043733 -2.950011) (xy 357.136024 -2.94038) (xy 357.18242 -2.939796)
			(xy 357.228815 -2.940407) (xy 357.321102 -2.950044) (xy 357.411886 -2.969231) (xy 357.50018 -2.997762)
			(xy 357.542846 -3.015996) (xy 357.552788 -3.019802) (xy 357.574052 -3.019802) (xy 357.583994 -3.015996)
			(xy 357.626654 -2.997745) (xy 357.714947 -2.969202) (xy 357.805733 -2.950011) (xy 357.898024 -2.94038)
			(xy 357.94442 -2.939796) (xy 357.990815 -2.940407) (xy 358.083102 -2.950044) (xy 358.173886 -2.969231)
			(xy 358.26218 -2.997762) (xy 358.304846 -3.015996) (xy 358.314788 -3.019802) (xy 358.336052 -3.019802)
			(xy 358.345994 -3.015996) (xy 358.388594 -2.997768) (xy 358.476763 -2.969252) (xy 358.567419 -2.950061)
			(xy 358.65958 -2.940403) (xy 358.705912 -2.939796) (xy 358.70642 -2.939796) (xy 358.747523 -2.940248)
			(xy 358.829378 -2.947834) (xy 358.910184 -2.962941) (xy 358.989251 -2.985439) (xy 359.065905 -3.015137)
			(xy 359.139492 -3.051781) (xy 359.209385 -3.095058) (xy 359.274986 -3.144599) (xy 359.335736 -3.199981)
			(xy 359.391117 -3.260733) (xy 359.440656 -3.326335) (xy 359.483931 -3.396229) (xy 359.520573 -3.469817)
			(xy 359.550268 -3.546472) (xy 359.572764 -3.62554) (xy 359.587869 -3.706346) (xy 359.595454 -3.788201)
			(xy 359.595928 -3.829304) (xy 359.595928 -3.829812) (xy 359.595322 -3.876144) (xy 359.592786 -3.900309)
			(xy 361.865136 -3.900309) (xy 361.87186 -3.783404) (xy 361.886543 -3.667229) (xy 361.909117 -3.552327)
			(xy 361.939477 -3.439232) (xy 361.977481 -3.328472) (xy 362.022952 -3.220563) (xy 362.075679 -3.116006)
			(xy 362.135416 -3.015291) (xy 362.201884 -2.918885) (xy 362.274775 -2.827238) (xy 362.353747 -2.740777)
			(xy 362.438434 -2.659905) (xy 362.52844 -2.584998) (xy 362.623346 -2.516406) (xy 362.722711 -2.454448)
			(xy 362.826071 -2.399413) (xy 362.932945 -2.351557) (xy 363.042834 -2.311104) (xy 363.155227 -2.278241)
			(xy 363.269599 -2.253122) (xy 363.38542 -2.235864) (xy 363.502147 -2.226547) (xy 363.619238 -2.225214)
			(xy 363.736148 -2.231873) (xy 363.85233 -2.246491) (xy 363.967245 -2.269002) (xy 364.080357 -2.299299)
			(xy 364.191138 -2.337241) (xy 364.299073 -2.382653) (xy 364.403658 -2.435322) (xy 364.504407 -2.495003)
			(xy 364.60085 -2.561418) (xy 364.692537 -2.634257) (xy 364.736126 -2.67335) (xy 364.74371 -2.679623)
			(xy 364.762161 -2.686419) (xy 364.781815 -2.685801) (xy 364.79099 -2.68224) (xy 364.87608 -2.644394)
			(xy 364.88487 -2.640018) (xy 364.898503 -2.62591) (xy 364.905858 -2.607721) (xy 364.906306 -2.597912)
			(xy 364.906306 -2.597658) (xy 364.906052 -2.5908) (xy 364.906052 -2.589276) (xy 364.90662 -2.539112)
			(xy 364.914961 -2.439131) (xy 364.931528 -2.340179) (xy 364.956206 -2.242933) (xy 364.988828 -2.148056)
			(xy 365.02917 -2.056196) (xy 365.076958 -1.967979) (xy 365.131864 -1.884009) (xy 365.193515 -1.804857)
			(xy 365.261489 -1.731065) (xy 365.335323 -1.663135) (xy 365.414513 -1.601533) (xy 365.498517 -1.546678)
			(xy 365.586763 -1.498944) (xy 365.678648 -1.458658) (xy 365.773545 -1.426094) (xy 365.870806 -1.401475)
			(xy 365.969767 -1.384969) (xy 366.069754 -1.376689) (xy 366.119918 -1.376172) (xy 366.168816 -1.376589)
			(xy 366.266296 -1.38446) (xy 366.362826 -1.400149) (xy 366.457781 -1.423554) (xy 366.550544 -1.454524)
			(xy 366.640514 -1.492858) (xy 366.727109 -1.538308) (xy 366.809765 -1.590578) (xy 366.887947 -1.649329)
			(xy 366.961149 -1.714181) (xy 367.028894 -1.784712) (xy 367.090745 -1.860467) (xy 367.146299 -1.940952)
			(xy 367.195197 -2.025647) (xy 367.237122 -2.114001) (xy 367.271801 -2.205443) (xy 367.299009 -2.299379)
			(xy 367.318571 -2.395199) (xy 367.330359 -2.492283) (xy 367.334297 -2.59) (xy 367.334295 -2.590038)
			(xy 367.445547 -2.590038) (xy 367.449587 -2.491055) (xy 367.461682 -2.392732) (xy 367.481752 -2.295721)
			(xy 367.509662 -2.200669) (xy 367.545226 -2.108208) (xy 367.588209 -2.018953) (xy 367.638324 -1.933499)
			(xy 367.695237 -1.852414) (xy 367.75857 -1.776238) (xy 367.827901 -1.705478) (xy 367.90277 -1.640604)
			(xy 367.982677 -1.582049) (xy 368.067091 -1.530201) (xy 368.15545 -1.485407) (xy 368.247166 -1.447964)
			(xy 368.341629 -1.418121) (xy 368.43821 -1.396077) (xy 368.536267 -1.381978) (xy 368.635147 -1.375919)
			(xy 368.734191 -1.37794) (xy 368.832741 -1.388027) (xy 368.930141 -1.406113) (xy 369.025743 -1.432078)
			(xy 369.11891 -1.46575) (xy 369.209023 -1.506903) (xy 369.295481 -1.555264) (xy 369.37771 -1.610511)
			(xy 369.455162 -1.672277) (xy 369.527322 -1.740151) (xy 369.59371 -1.81368) (xy 369.653883 -1.892376)
			(xy 369.707441 -1.975715) (xy 369.754029 -2.063142) (xy 369.793335 -2.154075) (xy 369.825099 -2.24791)
			(xy 369.849108 -2.344021) (xy 369.865204 -2.44177) (xy 369.873279 -2.540506) (xy 369.873784 -2.590038)
			(xy 369.873279 -2.63957) (xy 369.872538 -2.648633) (xy 377.104648 -2.648633) (xy 377.104648 -2.531443)
			(xy 377.112645 -2.414525) (xy 377.128603 -2.298426) (xy 377.152446 -2.183686) (xy 377.184064 -2.070841)
			(xy 377.223309 -1.960417) (xy 377.269997 -1.852928) (xy 377.323913 -1.748876) (xy 377.384803 -1.648746)
			(xy 377.452385 -1.553005) (xy 377.526343 -1.462099) (xy 377.606331 -1.376451) (xy 377.691979 -1.296463)
			(xy 377.782885 -1.222505) (xy 377.878626 -1.154923) (xy 377.978756 -1.094033) (xy 378.082808 -1.040117)
			(xy 378.190297 -0.993429) (xy 378.300721 -0.954184) (xy 378.413566 -0.922566) (xy 378.528306 -0.898723)
			(xy 378.644405 -0.882765) (xy 378.761323 -0.874768) (xy 378.878513 -0.874768) (xy 378.995431 -0.882765)
			(xy 379.11153 -0.898723) (xy 379.22627 -0.922566) (xy 379.339115 -0.954184) (xy 379.449539 -0.993429)
			(xy 379.557028 -1.040117) (xy 379.66108 -1.094033) (xy 379.76121 -1.154923) (xy 379.856951 -1.222505)
			(xy 379.947857 -1.296463) (xy 380.033505 -1.376451) (xy 380.113493 -1.462099) (xy 380.187451 -1.553005)
			(xy 380.255033 -1.648746) (xy 380.315923 -1.748876) (xy 380.369839 -1.852928) (xy 380.416527 -1.960417)
			(xy 380.455772 -2.070841) (xy 380.48739 -2.183686) (xy 380.511233 -2.298426) (xy 380.527191 -2.414525)
			(xy 380.535188 -2.531443) (xy 380.535688 -2.590038) (xy 380.535188 -2.648633) (xy 380.527191 -2.765551)
			(xy 380.511233 -2.88165) (xy 380.48739 -2.99639) (xy 380.455772 -3.109235) (xy 380.416527 -3.219659)
			(xy 380.369839 -3.327148) (xy 380.315923 -3.4312) (xy 380.255033 -3.53133) (xy 380.187451 -3.627071)
			(xy 380.113493 -3.717977) (xy 380.033505 -3.803625) (xy 379.947857 -3.883613) (xy 379.856951 -3.957571)
			(xy 379.76121 -4.025153) (xy 379.66108 -4.086043) (xy 379.557028 -4.139959) (xy 379.449539 -4.186647)
			(xy 379.339115 -4.225892) (xy 379.22627 -4.25751) (xy 379.11153 -4.281353) (xy 378.995431 -4.297311)
			(xy 378.878513 -4.305308) (xy 378.761323 -4.305308) (xy 378.644405 -4.297311) (xy 378.528306 -4.281353)
			(xy 378.413566 -4.25751) (xy 378.300721 -4.225892) (xy 378.190297 -4.186647) (xy 378.082808 -4.139959)
			(xy 377.978756 -4.086043) (xy 377.878626 -4.025153) (xy 377.782885 -3.957571) (xy 377.691979 -3.883613)
			(xy 377.606331 -3.803625) (xy 377.526343 -3.717977) (xy 377.452385 -3.627071) (xy 377.384803 -3.53133)
			(xy 377.323913 -3.4312) (xy 377.269997 -3.327148) (xy 377.223309 -3.219659) (xy 377.184064 -3.109235)
			(xy 377.152446 -2.99639) (xy 377.128603 -2.88165) (xy 377.112645 -2.765551) (xy 377.104648 -2.648633)
			(xy 369.872538 -2.648633) (xy 369.865204 -2.738306) (xy 369.849108 -2.836055) (xy 369.825099 -2.932166)
			(xy 369.793335 -3.026001) (xy 369.754029 -3.116934) (xy 369.707441 -3.204361) (xy 369.653883 -3.2877)
			(xy 369.59371 -3.366396) (xy 369.527322 -3.439925) (xy 369.455162 -3.507799) (xy 369.37771 -3.569565)
			(xy 369.295481 -3.624812) (xy 369.209023 -3.673173) (xy 369.11891 -3.714326) (xy 369.025743 -3.747998)
			(xy 368.930141 -3.773963) (xy 368.832741 -3.792049) (xy 368.734191 -3.802136) (xy 368.635147 -3.804157)
			(xy 368.536267 -3.798098) (xy 368.43821 -3.783999) (xy 368.341629 -3.761955) (xy 368.247166 -3.732112)
			(xy 368.15545 -3.694669) (xy 368.067091 -3.649875) (xy 367.982677 -3.598027) (xy 367.90277 -3.539472)
			(xy 367.827901 -3.474598) (xy 367.75857 -3.403838) (xy 367.695237 -3.327662) (xy 367.638324 -3.246577)
			(xy 367.588209 -3.161123) (xy 367.545226 -3.071868) (xy 367.509662 -2.979407) (xy 367.481752 -2.884355)
			(xy 367.461682 -2.787344) (xy 367.449587 -2.689021) (xy 367.445547 -2.590038) (xy 367.334295 -2.590038)
			(xy 367.330359 -2.687717) (xy 367.318571 -2.784801) (xy 367.299009 -2.880621) (xy 367.271801 -2.974557)
			(xy 367.237122 -3.065999) (xy 367.195197 -3.154353) (xy 367.146299 -3.239048) (xy 367.090745 -3.319533)
			(xy 367.028894 -3.395288) (xy 366.961149 -3.465819) (xy 366.887947 -3.530671) (xy 366.809765 -3.589422)
			(xy 366.727109 -3.641692) (xy 366.640514 -3.687142) (xy 366.550544 -3.725476) (xy 366.457781 -3.756446)
			(xy 366.362826 -3.779851) (xy 366.266296 -3.79554) (xy 366.168816 -3.803411) (xy 366.119918 -3.803904)
			(xy 366.067892 -3.803373) (xy 365.964224 -3.794448) (xy 365.861701 -3.776681) (xy 365.761075 -3.750202)
			(xy 365.663086 -3.715204) (xy 365.568453 -3.671945) (xy 365.477871 -3.620743) (xy 365.434626 -3.591814)
			(xy 365.42218 -3.583178) (xy 365.391954 -3.58267) (xy 365.287306 -3.647948) (xy 365.274606 -3.67538)
			(xy 365.276892 -3.690366) (xy 365.284958 -3.748359) (xy 365.294081 -3.865102) (xy 365.295218 -3.982195)
			(xy 365.288365 -4.099093) (xy 365.273553 -4.215251) (xy 365.250851 -4.330129) (xy 365.220366 -4.44319)
			(xy 365.182239 -4.553907) (xy 365.136647 -4.661766) (xy 365.083804 -4.766264) (xy 365.023956 -4.866913)
			(xy 364.95738 -4.963245) (xy 364.884389 -5.054811) (xy 364.80532 -5.141184) (xy 364.720544 -5.221962)
			(xy 364.630454 -5.296769) (xy 364.535472 -5.365256) (xy 364.436038 -5.427103) (xy 364.332617 -5.482023)
			(xy 364.225691 -5.52976) (xy 364.115757 -5.570092) (xy 364.003327 -5.60283) (xy 363.888927 -5.627822)
			(xy 363.773088 -5.644952) (xy 363.65635 -5.654139) (xy 363.539257 -5.655341) (xy 363.422355 -5.648553)
			(xy 363.306189 -5.633805) (xy 363.191299 -5.611168) (xy 363.078221 -5.580745) (xy 362.967482 -5.542679)
			(xy 362.859598 -5.497148) (xy 362.755071 -5.444363) (xy 362.654389 -5.38457) (xy 362.55802 -5.318048)
			(xy 362.466413 -5.245107) (xy 362.379996 -5.166087) (xy 362.299171 -5.081355) (xy 362.224314 -4.991308)
			(xy 362.155775 -4.896363) (xy 362.093872 -4.796964) (xy 362.038895 -4.693573) (xy 361.991098 -4.586673)
			(xy 361.950706 -4.476762) (xy 361.917905 -4.36435) (xy 361.89285 -4.249964) (xy 361.875656 -4.134134)
			(xy 361.866404 -4.017401) (xy 361.865136 -3.900309) (xy 359.592786 -3.900309) (xy 359.58565 -3.968302)
			(xy 359.566455 -4.058956) (xy 359.537943 -4.147125) (xy 359.519728 -4.18973) (xy 359.515919 -4.199671)
			(xy 359.515921 -4.220936) (xy 359.519728 -4.230878) (xy 359.537975 -4.273539) (xy 359.566518 -4.361832)
			(xy 359.585711 -4.452617) (xy 359.595343 -4.544908) (xy 359.595928 -4.591304) (xy 359.595345 -4.6377)
			(xy 359.5857 -4.729988) (xy 359.566504 -4.820772) (xy 359.537966 -4.909065) (xy 359.519728 -4.95173)
			(xy 359.515919 -4.961671) (xy 359.515921 -4.982936) (xy 359.519728 -4.992878) (xy 359.537953 -5.03548)
			(xy 359.566469 -5.123648) (xy 359.585661 -5.214303) (xy 359.59532 -5.306464) (xy 359.595928 -5.352796)
			(xy 359.595928 -5.353304) (xy 359.595437 -5.394406) (xy 359.587852 -5.476259) (xy 359.572747 -5.557063)
			(xy 359.550251 -5.636129) (xy 359.520556 -5.712782) (xy 359.483914 -5.786368) (xy 359.44064 -5.85626)
			(xy 359.391101 -5.92186) (xy 359.335722 -5.98261) (xy 359.274973 -6.037991) (xy 359.209373 -6.087531)
			(xy 359.139482 -6.130807) (xy 359.065897 -6.167449) (xy 358.989245 -6.197146) (xy 358.910179 -6.219643)
			(xy 358.829375 -6.23475) (xy 358.747522 -6.242336) (xy 358.70642 -6.242812) (xy 358.705912 -6.242812)
			(xy 358.65958 -6.242199) (xy 358.567423 -6.232529) (xy 358.476769 -6.213336) (xy 358.3886 -6.184826)
			(xy 358.345994 -6.166612) (xy 358.336052 -6.162806) (xy 358.314788 -6.162806) (xy 358.304846 -6.166612)
			(xy 358.262181 -6.18485) (xy 358.17389 -6.213396) (xy 358.083106 -6.232591) (xy 357.990816 -6.242226)
			(xy 357.94442 -6.242812) (xy 357.898025 -6.242222) (xy 357.805736 -6.232579) (xy 357.714953 -6.213385)
			(xy 357.626659 -6.184849) (xy 357.583994 -6.166612) (xy 357.574052 -6.162806) (xy 357.552788 -6.162806)
			(xy 357.542846 -6.166612) (xy 357.500181 -6.18485) (xy 357.41189 -6.213396) (xy 357.321106 -6.232591)
			(xy 357.228816 -6.242226) (xy 357.18242 -6.242812) (xy 357.136025 -6.242222) (xy 357.043736 -6.232579)
			(xy 356.952953 -6.213385) (xy 356.864659 -6.184849) (xy 356.821994 -6.166612) (xy 356.812052 -6.162806)
			(xy 356.790788 -6.162806) (xy 356.780846 -6.166612) (xy 356.738181 -6.18485) (xy 356.64989 -6.213396)
			(xy 356.559106 -6.232591) (xy 356.466816 -6.242226) (xy 356.42042 -6.242812) (xy 356.374025 -6.242222)
			(xy 356.281736 -6.232579) (xy 356.190953 -6.213385) (xy 356.102659 -6.184849) (xy 356.059994 -6.166612)
			(xy 356.050052 -6.162806) (xy 356.028788 -6.162806) (xy 356.018846 -6.166612) (xy 355.976181 -6.18485)
			(xy 355.88789 -6.213396) (xy 355.797106 -6.232591) (xy 355.704816 -6.242226) (xy 355.65842 -6.242812)
			(xy 355.612025 -6.242222) (xy 355.519736 -6.232579) (xy 355.428953 -6.213385) (xy 355.340659 -6.184849)
			(xy 355.297994 -6.166612) (xy 355.288052 -6.162806) (xy 355.266788 -6.162806) (xy 355.256846 -6.166612)
			(xy 355.214241 -6.184828) (xy 355.126074 -6.213347) (xy 355.035419 -6.232541) (xy 354.94326 -6.242203)
			(xy 354.896928 -6.242812) (xy 354.89642 -6.242812) (xy 354.855317 -6.242329) (xy 354.773462 -6.234746)
			(xy 354.692656 -6.219642) (xy 354.613589 -6.197147) (xy 354.536934 -6.167452) (xy 354.463346 -6.130811)
			(xy 354.393453 -6.087537) (xy 354.327851 -6.037998) (xy 354.267099 -5.982618) (xy 354.211717 -5.921868)
			(xy 354.162177 -5.856267) (xy 354.1189 -5.786375) (xy 354.082257 -5.712788) (xy 354.052561 -5.636134)
			(xy 354.030063 -5.557067) (xy 354.014958 -5.476261) (xy 354.007372 -5.394407) (xy 354.006912 -5.353304)
			(xy 87.376285 -5.353304) (xy 87.376033 -5.375102) (xy 87.368448 -5.456957) (xy 87.353343 -5.537762)
			(xy 87.330847 -5.616829) (xy 87.301151 -5.693483) (xy 87.264509 -5.76707) (xy 87.221234 -5.836962)
			(xy 87.171694 -5.902563) (xy 87.116313 -5.963313) (xy 87.055563 -6.018694) (xy 86.989962 -6.068234)
			(xy 86.92007 -6.111509) (xy 86.846483 -6.148151) (xy 86.769829 -6.177847) (xy 86.690762 -6.200343)
			(xy 86.609957 -6.215448) (xy 86.528102 -6.223033) (xy 86.487 -6.223508) (xy 86.486492 -6.223508)
			(xy 86.44016 -6.222902) (xy 86.348002 -6.213231) (xy 86.257348 -6.194035) (xy 86.169179 -6.165523)
			(xy 86.126574 -6.147308) (xy 86.116632 -6.143502) (xy 86.095368 -6.143502) (xy 86.085426 -6.147308)
			(xy 86.042764 -6.165553) (xy 85.954471 -6.194097) (xy 85.863686 -6.21329) (xy 85.771396 -6.222923)
			(xy 85.725 -6.223508) (xy 85.678604 -6.222925) (xy 85.586316 -6.21328) (xy 85.495532 -6.194084) (xy 85.407239 -6.165546)
			(xy 85.364574 -6.147308) (xy 85.354632 -6.143502) (xy 85.333368 -6.143502) (xy 85.323426 -6.147308)
			(xy 85.280764 -6.165553) (xy 85.192471 -6.194097) (xy 85.101686 -6.21329) (xy 85.009396 -6.222923)
			(xy 84.963 -6.223508) (xy 84.916604 -6.222925) (xy 84.824316 -6.21328) (xy 84.733532 -6.194084) (xy 84.645239 -6.165546)
			(xy 84.602574 -6.147308) (xy 84.592632 -6.143502) (xy 84.571368 -6.143502) (xy 84.561426 -6.147308)
			(xy 84.518764 -6.165553) (xy 84.430471 -6.194097) (xy 84.339686 -6.21329) (xy 84.247396 -6.222923)
			(xy 84.201 -6.223508) (xy 84.154604 -6.222925) (xy 84.062316 -6.21328) (xy 83.971532 -6.194084) (xy 83.883239 -6.165546)
			(xy 83.840574 -6.147308) (xy 83.830632 -6.143502) (xy 83.809368 -6.143502) (xy 83.799426 -6.147308)
			(xy 83.756764 -6.165553) (xy 83.668471 -6.194097) (xy 83.577686 -6.21329) (xy 83.485396 -6.222923)
			(xy 83.439 -6.223508) (xy 83.392604 -6.222925) (xy 83.300316 -6.21328) (xy 83.209532 -6.194084) (xy 83.121239 -6.165546)
			(xy 83.078574 -6.147308) (xy 83.068632 -6.143502) (xy 83.047368 -6.143502) (xy 83.037426 -6.147308)
			(xy 82.994823 -6.16553) (xy 82.906656 -6.194048) (xy 82.816 -6.21324) (xy 82.72384 -6.2229) (xy 82.677508 -6.223508)
			(xy 82.677 -6.223508) (xy 82.635898 -6.223033) (xy 82.554043 -6.215448) (xy 82.473238 -6.200343)
			(xy 82.394171 -6.177847) (xy 82.317517 -6.148151) (xy 82.24393 -6.111509) (xy 82.174038 -6.068234)
			(xy 82.108437 -6.018694) (xy 82.047687 -5.963313) (xy 81.992306 -5.902563) (xy 81.942766 -5.836962)
			(xy 81.899491 -5.76707) (xy 81.862849 -5.693483) (xy 81.833153 -5.616829) (xy 81.810657 -5.537762)
			(xy 81.795552 -5.456957) (xy 81.787967 -5.375102) (xy 81.787492 -5.334) (xy 62.178873 -5.334) (xy 62.135479 -5.365288)
			(xy 62.036043 -5.427136) (xy 61.932619 -5.482057) (xy 61.82569 -5.529794) (xy 61.715754 -5.570126)
			(xy 61.603322 -5.602863) (xy 61.488918 -5.627855) (xy 61.373077 -5.644984) (xy 61.256336 -5.654171)
			(xy 61.139241 -5.655372) (xy 61.022337 -5.648582) (xy 60.906168 -5.633833) (xy 60.791276 -5.611194)
			(xy 60.678196 -5.58077) (xy 60.567455 -5.542702) (xy 60.459569 -5.497169) (xy 60.355041 -5.444382)
			(xy 60.254357 -5.384586) (xy 60.157987 -5.318062) (xy 60.066379 -5.245119) (xy 59.979961 -5.166096)
			(xy 59.899135 -5.081362) (xy 59.824278 -4.991311) (xy 59.755738 -4.896364) (xy 59.693835 -4.796962)
			(xy 59.638858 -4.693568) (xy 59.591062 -4.586666) (xy 59.55067 -4.476751) (xy 59.51787 -4.364337)
			(xy 59.492815 -4.249948) (xy 59.475623 -4.134116) (xy 59.466372 -4.01738) (xy 59.465106 -3.900286)
			(xy 0.646137 -3.900286) (xy 0.630394 -3.960748) (xy 0.590225 -4.147135) (xy 0.558002 -4.335059) (xy 0.533784 -4.524182)
			(xy 0.517614 -4.714162) (xy 0.509522 -4.904657) (xy 0.509016 -4.99999) (xy 0.509016 -17.272) (xy 111.565944 -17.272)
			(xy 111.565944 -17.271492) (xy 111.566546 -17.22516) (xy 111.576218 -17.133002) (xy 111.595414 -17.042348)
			(xy 111.623928 -16.954179) (xy 111.642144 -16.911574) (xy 111.645952 -16.901632) (xy 111.645952 -16.880368)
			(xy 111.642144 -16.870426) (xy 111.623902 -16.827762) (xy 111.595357 -16.739471) (xy 111.576163 -16.648686)
			(xy 111.566529 -16.556396) (xy 111.565944 -16.51) (xy 111.566522 -16.463604) (xy 111.576168 -16.371316)
			(xy 111.595365 -16.280532) (xy 111.623905 -16.192239) (xy 111.642144 -16.149574) (xy 111.645952 -16.139632)
			(xy 111.645952 -16.118368) (xy 111.642144 -16.108426) (xy 111.623902 -16.065762) (xy 111.595357 -15.977471)
			(xy 111.576163 -15.886686) (xy 111.566529 -15.794396) (xy 111.565944 -15.748) (xy 111.566522 -15.701604)
			(xy 111.576168 -15.609316) (xy 111.595365 -15.518532) (xy 111.623905 -15.430239) (xy 111.642144 -15.387574)
			(xy 111.645952 -15.377632) (xy 111.645952 -15.356368) (xy 111.642144 -15.346426) (xy 111.623902 -15.303762)
			(xy 111.595357 -15.215471) (xy 111.576163 -15.124686) (xy 111.566529 -15.032396) (xy 111.565944 -14.986)
			(xy 111.566522 -14.939604) (xy 111.576168 -14.847316) (xy 111.595365 -14.756532) (xy 111.623905 -14.668239)
			(xy 111.642144 -14.625574) (xy 111.645952 -14.615632) (xy 111.645952 -14.594368) (xy 111.642144 -14.584426)
			(xy 111.623919 -14.541824) (xy 111.595403 -14.453656) (xy 111.576211 -14.363) (xy 111.566552 -14.27084)
			(xy 111.565944 -14.224508) (xy 111.565944 -14.224) (xy 111.566467 -14.182899) (xy 111.574051 -14.101047)
			(xy 111.589155 -14.020245) (xy 111.61165 -13.94118) (xy 111.641344 -13.864529) (xy 111.677983 -13.790944)
			(xy 111.721256 -13.721053) (xy 111.770792 -13.655454) (xy 111.82617 -13.594704) (xy 111.886917 -13.539323)
			(xy 111.952514 -13.489783) (xy 112.022402 -13.446507) (xy 112.095985 -13.409863) (xy 112.172635 -13.380165)
			(xy 112.251698 -13.357666) (xy 112.3325 -13.342558) (xy 112.414351 -13.334969) (xy 112.455452 -13.334492)
			(xy 112.45596 -13.334492) (xy 112.502291 -13.335115) (xy 112.594449 -13.344781) (xy 112.685103 -13.363972)
			(xy 112.773272 -13.392479) (xy 112.815878 -13.410692) (xy 112.82582 -13.414498) (xy 112.847084 -13.414498)
			(xy 112.857026 -13.410692) (xy 112.899695 -13.392463) (xy 112.987985 -13.363915) (xy 113.078768 -13.344717)
			(xy 113.171056 -13.335079) (xy 113.217452 -13.334492) (xy 113.263847 -13.335092) (xy 113.356135 -13.344732)
			(xy 113.446919 -13.363923) (xy 113.535213 -13.392456) (xy 113.577878 -13.410692) (xy 113.58782 -13.414498)
			(xy 113.609084 -13.414498) (xy 113.619026 -13.410692) (xy 113.661695 -13.392463) (xy 113.749985 -13.363915)
			(xy 113.840768 -13.344717) (xy 113.933056 -13.335079) (xy 113.979452 -13.334492) (xy 114.025847 -13.335092)
			(xy 114.118135 -13.344732) (xy 114.208919 -13.363923) (xy 114.297213 -13.392456) (xy 114.339878 -13.410692)
			(xy 114.34982 -13.414498) (xy 114.371084 -13.414498) (xy 114.381026 -13.410692) (xy 114.423695 -13.392463)
			(xy 114.511985 -13.363915) (xy 114.602768 -13.344717) (xy 114.695056 -13.335079) (xy 114.741452 -13.334492)
			(xy 114.787847 -13.335092) (xy 114.880135 -13.344732) (xy 114.970919 -13.363923) (xy 115.059213 -13.392456)
			(xy 115.101878 -13.410692) (xy 115.11182 -13.414498) (xy 115.133084 -13.414498) (xy 115.143026 -13.410692)
			(xy 115.185635 -13.392486) (xy 115.2738 -13.363964) (xy 115.364454 -13.344767) (xy 115.456612 -13.335103)
			(xy 115.502944 -13.334492) (xy 115.503452 -13.334492) (xy 115.544554 -13.334998) (xy 115.626409 -13.342579)
			(xy 115.707215 -13.35768) (xy 115.786282 -13.380173) (xy 115.862937 -13.409865) (xy 115.936525 -13.446504)
			(xy 116.006418 -13.489777) (xy 116.072021 -13.539314) (xy 116.132772 -13.594694) (xy 116.188155 -13.655442)
			(xy 116.237696 -13.721042) (xy 116.280972 -13.790933) (xy 116.317615 -13.864519) (xy 116.347312 -13.941172)
			(xy 116.369809 -14.020239) (xy 116.384915 -14.101044) (xy 116.3925 -14.182898) (xy 116.39296 -14.224)
			(xy 116.39296 -14.224508) (xy 116.392358 -14.27084) (xy 116.382686 -14.362998) (xy 116.363489 -14.453652)
			(xy 116.334976 -14.541821) (xy 116.31676 -14.584426) (xy 116.312952 -14.594368) (xy 116.312952 -14.615632)
			(xy 116.31676 -14.625574) (xy 116.335002 -14.668237) (xy 116.363547 -14.756529) (xy 116.382741 -14.847314)
			(xy 116.392375 -14.939604) (xy 116.39296 -14.986) (xy 116.392381 -15.032396) (xy 116.382736 -15.124684)
			(xy 116.363539 -15.215468) (xy 116.334999 -15.303761) (xy 116.31676 -15.346426) (xy 116.312952 -15.356368)
			(xy 116.312952 -15.377632) (xy 116.31676 -15.387574) (xy 116.335002 -15.430237) (xy 116.363547 -15.518529)
			(xy 116.382741 -15.609314) (xy 116.392375 -15.701604) (xy 116.39296 -15.748) (xy 116.392381 -15.794396)
			(xy 116.382736 -15.886684) (xy 116.363539 -15.977468) (xy 116.334999 -16.065761) (xy 116.31676 -16.108426)
			(xy 116.312952 -16.118368) (xy 116.312952 -16.139632) (xy 116.31676 -16.149574) (xy 116.335002 -16.192237)
			(xy 116.363547 -16.280529) (xy 116.382741 -16.371314) (xy 116.392375 -16.463604) (xy 116.39296 -16.51)
			(xy 116.392381 -16.556396) (xy 116.382736 -16.648684) (xy 116.363539 -16.739468) (xy 116.334999 -16.827761)
			(xy 116.31676 -16.870426) (xy 116.312952 -16.880368) (xy 116.312952 -16.901632) (xy 116.31676 -16.911574)
			(xy 116.334985 -16.954176) (xy 116.363501 -17.042344) (xy 116.382693 -17.132999) (xy 116.392352 -17.22516)
			(xy 116.39296 -17.271492) (xy 116.39296 -17.272) (xy 116.392548 -17.313105) (xy 116.384962 -17.394963)
			(xy 116.369856 -17.475772) (xy 116.347357 -17.554843) (xy 116.317659 -17.6315) (xy 116.281014 -17.70509)
			(xy 116.237735 -17.774985) (xy 116.188192 -17.840588) (xy 116.132806 -17.90134) (xy 116.072051 -17.956722)
			(xy 116.006446 -18.006262) (xy 115.936548 -18.049538) (xy 115.862956 -18.086179) (xy 115.786297 -18.115873)
			(xy 115.707226 -18.138367) (xy 115.626415 -18.153469) (xy 115.544557 -18.16105) (xy 115.503452 -18.161508)
			(xy 115.502944 -18.161508) (xy 115.456613 -18.160884) (xy 115.364455 -18.151218) (xy 115.273801 -18.132027)
			(xy 115.185632 -18.103521) (xy 115.143026 -18.085308) (xy 115.133084 -18.081502) (xy 115.11182 -18.081502)
			(xy 115.101878 -18.085308) (xy 115.059209 -18.103536) (xy 114.970919 -18.132084) (xy 114.880136 -18.151282)
			(xy 114.787847 -18.16092) (xy 114.741452 -18.161508) (xy 114.695057 -18.160907) (xy 114.602769 -18.151267)
			(xy 114.511985 -18.132076) (xy 114.423691 -18.103543) (xy 114.381026 -18.085308) (xy 114.371084 -18.081502)
			(xy 114.34982 -18.081502) (xy 114.339878 -18.085308) (xy 114.297209 -18.103536) (xy 114.208919 -18.132084)
			(xy 114.118136 -18.151282) (xy 114.025847 -18.16092) (xy 113.979452 -18.161508) (xy 113.933057 -18.160907)
			(xy 113.840769 -18.151267) (xy 113.749985 -18.132076) (xy 113.661691 -18.103543) (xy 113.619026 -18.085308)
			(xy 113.609084 -18.081502) (xy 113.58782 -18.081502) (xy 113.577878 -18.085308) (xy 113.535209 -18.103536)
			(xy 113.446919 -18.132084) (xy 113.356136 -18.151282) (xy 113.263847 -18.16092) (xy 113.217452 -18.161508)
			(xy 113.171057 -18.160907) (xy 113.078769 -18.151267) (xy 112.987985 -18.132076) (xy 112.899691 -18.103543)
			(xy 112.857026 -18.085308) (xy 112.847084 -18.081502) (xy 112.82582 -18.081502) (xy 112.815878 -18.085308)
			(xy 112.773268 -18.103513) (xy 112.685103 -18.132035) (xy 112.59445 -18.151233) (xy 112.502292 -18.160897)
			(xy 112.45596 -18.161508) (xy 112.455452 -18.161508) (xy 112.414349 -18.161079) (xy 112.332493 -18.15349)
			(xy 112.251687 -18.138381) (xy 112.17262 -18.11588) (xy 112.095965 -18.086181) (xy 112.022379 -18.049535)
			(xy 111.952487 -18.006257) (xy 111.886886 -17.956714) (xy 111.826136 -17.90133) (xy 111.770755 -17.840577)
			(xy 111.721216 -17.774974) (xy 111.677941 -17.705079) (xy 111.6413 -17.631491) (xy 111.611604 -17.554835)
			(xy 111.589108 -17.475766) (xy 111.574003 -17.394959) (xy 111.566419 -17.313103) (xy 111.565944 -17.272)
			(xy 0.509016 -17.272) (xy 0.509016 -20.63857) (xy 56.730635 -20.63857) (xy 56.730635 -20.50943) (xy 56.738585 -20.380535)
			(xy 56.754455 -20.252375) (xy 56.778184 -20.125434) (xy 56.809683 -20.000195) (xy 56.848832 -19.877132)
			(xy 56.895483 -19.756713) (xy 56.949458 -19.639394) (xy 57.010553 -19.52562) (xy 57.078536 -19.415823)
			(xy 57.15315 -19.31042) (xy 57.234111 -19.20981) (xy 57.321111 -19.114375) (xy 57.413822 -19.024476)
			(xy 57.511892 -18.940455) (xy 57.614947 -18.862631) (xy 57.722598 -18.791299) (xy 57.834437 -18.726729)
			(xy 57.950038 -18.669167) (xy 58.068963 -18.61883) (xy 58.190762 -18.57591) (xy 58.314972 -18.540569)
			(xy 58.441121 -18.512942) (xy 58.568733 -18.493133) (xy 58.697322 -18.481217) (xy 58.8264 -18.477241)
			(xy 58.955478 -18.481217) (xy 59.084067 -18.493133) (xy 59.211679 -18.512942) (xy 59.337828 -18.540569)
			(xy 59.462038 -18.57591) (xy 59.583837 -18.61883) (xy 59.702762 -18.669167) (xy 59.818363 -18.726729)
			(xy 59.930202 -18.791299) (xy 60.037853 -18.862631) (xy 60.140908 -18.940455) (xy 60.238978 -19.024476)
			(xy 60.331689 -19.114375) (xy 60.418689 -19.20981) (xy 60.49965 -19.31042) (xy 60.574264 -19.415823)
			(xy 60.642247 -19.52562) (xy 60.703342 -19.639394) (xy 60.757317 -19.756713) (xy 60.803968 -19.877132)
			(xy 60.843117 -20.000195) (xy 60.874616 -20.125434) (xy 60.898345 -20.252375) (xy 60.914215 -20.380535)
			(xy 60.922165 -20.50943) (xy 60.922662 -20.574) (xy 60.922165 -20.63857) (xy 60.914215 -20.767465)
			(xy 60.898345 -20.895625) (xy 60.874616 -21.022566) (xy 60.843117 -21.147805) (xy 60.803968 -21.270868)
			(xy 60.757317 -21.391287) (xy 60.703342 -21.508606) (xy 60.642247 -21.62238) (xy 60.574264 -21.732177)
			(xy 60.49965 -21.83758) (xy 60.418689 -21.93819) (xy 60.331689 -22.033625) (xy 60.238978 -22.123524)
			(xy 60.140908 -22.207545) (xy 60.037853 -22.285369) (xy 59.988365 -22.318161) (xy 111.362994 -22.318161)
			(xy 111.362994 -22.233439) (xy 111.371047 -22.149102) (xy 111.387081 -22.065912) (xy 111.410949 -21.984622)
			(xy 111.442437 -21.90597) (xy 111.481259 -21.830667) (xy 111.527062 -21.759395) (xy 111.579433 -21.692799)
			(xy 111.637898 -21.631484) (xy 111.701926 -21.576003) (xy 111.770938 -21.52686) (xy 111.844308 -21.4845)
			(xy 111.921373 -21.449305) (xy 112.001435 -21.421596) (xy 112.083768 -21.401622) (xy 112.167627 -21.389565)
			(xy 112.252252 -21.385534) (xy 112.336877 -21.389565) (xy 112.420736 -21.401622) (xy 112.503069 -21.421596)
			(xy 112.583131 -21.449305) (xy 112.660196 -21.4845) (xy 112.733566 -21.52686) (xy 112.802578 -21.576003)
			(xy 112.866606 -21.631484) (xy 112.925071 -21.692799) (xy 112.977442 -21.759395) (xy 113.023245 -21.830667)
			(xy 113.062067 -21.90597) (xy 113.093555 -21.984622) (xy 113.117423 -22.065912) (xy 113.133457 -22.149102)
			(xy 113.14151 -22.233439) (xy 113.142014 -22.2758) (xy 113.14151 -22.318161) (xy 113.133457 -22.402498)
			(xy 113.117423 -22.485688) (xy 113.093555 -22.566978) (xy 113.062067 -22.64563) (xy 113.023245 -22.720933)
			(xy 112.977442 -22.792205) (xy 112.925071 -22.858801) (xy 112.866606 -22.920116) (xy 112.802578 -22.975597)
			(xy 112.733566 -23.02474) (xy 112.660196 -23.0671) (xy 112.583131 -23.102295) (xy 112.503069 -23.130004)
			(xy 112.420736 -23.149978) (xy 112.336877 -23.162035) (xy 112.252252 -23.166067) (xy 112.167627 -23.162035)
			(xy 112.083768 -23.149978) (xy 112.001435 -23.130004) (xy 111.921373 -23.102295) (xy 111.844308 -23.0671)
			(xy 111.770938 -23.02474) (xy 111.701926 -22.975597) (xy 111.637898 -22.920116) (xy 111.579433 -22.858801)
			(xy 111.527062 -22.792205) (xy 111.481259 -22.720933) (xy 111.442437 -22.64563) (xy 111.410949 -22.566978)
			(xy 111.387081 -22.485688) (xy 111.371047 -22.402498) (xy 111.362994 -22.318161) (xy 59.988365 -22.318161)
			(xy 59.930202 -22.356701) (xy 59.818363 -22.421271) (xy 59.702762 -22.478833) (xy 59.583837 -22.52917)
			(xy 59.462038 -22.57209) (xy 59.337828 -22.607431) (xy 59.211679 -22.635058) (xy 59.084067 -22.654867)
			(xy 58.955478 -22.666783) (xy 58.8264 -22.67076) (xy 58.697322 -22.666783) (xy 58.568733 -22.654867)
			(xy 58.441121 -22.635058) (xy 58.314972 -22.607431) (xy 58.190762 -22.57209) (xy 58.068963 -22.52917)
			(xy 57.950038 -22.478833) (xy 57.834437 -22.421271) (xy 57.722598 -22.356701) (xy 57.614947 -22.285369)
			(xy 57.511892 -22.207545) (xy 57.413822 -22.123524) (xy 57.321111 -22.033625) (xy 57.234111 -21.93819)
			(xy 57.15315 -21.83758) (xy 57.078536 -21.732177) (xy 57.010553 -21.62238) (xy 56.949458 -21.508606)
			(xy 56.895483 -21.391287) (xy 56.848832 -21.270868) (xy 56.809683 -21.147805) (xy 56.778184 -21.022566)
			(xy 56.754455 -20.895625) (xy 56.738585 -20.767465) (xy 56.730635 -20.63857) (xy 0.509016 -20.63857)
			(xy 0.509016 -28.5496) (xy 111.565944 -28.5496) (xy 111.565944 -28.549092) (xy 111.566546 -28.50276)
			(xy 111.576218 -28.410602) (xy 111.595414 -28.319948) (xy 111.623928 -28.231779) (xy 111.642144 -28.189174)
			(xy 111.645952 -28.179232) (xy 111.645952 -28.157968) (xy 111.642144 -28.148026) (xy 111.623902 -28.105362)
			(xy 111.595357 -28.017071) (xy 111.576163 -27.926286) (xy 111.566529 -27.833996) (xy 111.565944 -27.7876)
			(xy 111.566522 -27.741204) (xy 111.576168 -27.648916) (xy 111.595365 -27.558132) (xy 111.623905 -27.469839)
			(xy 111.642144 -27.427174) (xy 111.645952 -27.417232) (xy 111.645952 -27.395968) (xy 111.642144 -27.386026)
			(xy 111.623902 -27.343362) (xy 111.595357 -27.255071) (xy 111.576163 -27.164286) (xy 111.566529 -27.071996)
			(xy 111.565944 -27.0256) (xy 111.566522 -26.979204) (xy 111.576168 -26.886916) (xy 111.595365 -26.796132)
			(xy 111.623905 -26.707839) (xy 111.642144 -26.665174) (xy 111.645952 -26.655232) (xy 111.645952 -26.633968)
			(xy 111.642144 -26.624026) (xy 111.623902 -26.581362) (xy 111.595357 -26.493071) (xy 111.576163 -26.402286)
			(xy 111.566529 -26.309996) (xy 111.565944 -26.2636) (xy 111.566522 -26.217204) (xy 111.576168 -26.124916)
			(xy 111.595365 -26.034132) (xy 111.623905 -25.945839) (xy 111.642144 -25.903174) (xy 111.645952 -25.893232)
			(xy 111.645952 -25.871968) (xy 111.642144 -25.862026) (xy 111.623919 -25.819424) (xy 111.595403 -25.731256)
			(xy 111.576211 -25.6406) (xy 111.566552 -25.54844) (xy 111.565944 -25.502108) (xy 111.565944 -25.5016)
			(xy 111.566467 -25.460499) (xy 111.574051 -25.378647) (xy 111.589155 -25.297845) (xy 111.61165 -25.21878)
			(xy 111.641344 -25.142129) (xy 111.677983 -25.068544) (xy 111.721256 -24.998653) (xy 111.770792 -24.933054)
			(xy 111.82617 -24.872304) (xy 111.886917 -24.816923) (xy 111.952514 -24.767383) (xy 112.022402 -24.724107)
			(xy 112.095985 -24.687463) (xy 112.172635 -24.657765) (xy 112.251698 -24.635266) (xy 112.3325 -24.620158)
			(xy 112.414351 -24.612569) (xy 112.455452 -24.612092) (xy 112.45596 -24.612092) (xy 112.502291 -24.612715)
			(xy 112.594449 -24.622381) (xy 112.685103 -24.641572) (xy 112.773272 -24.670079) (xy 112.815878 -24.688292)
			(xy 112.82582 -24.692098) (xy 112.847084 -24.692098) (xy 112.857026 -24.688292) (xy 112.899695 -24.670063)
			(xy 112.987985 -24.641515) (xy 113.078768 -24.622317) (xy 113.171056 -24.612679) (xy 113.217452 -24.612092)
			(xy 113.263847 -24.612692) (xy 113.356135 -24.622332) (xy 113.446919 -24.641523) (xy 113.535213 -24.670056)
			(xy 113.577878 -24.688292) (xy 113.58782 -24.692098) (xy 113.609084 -24.692098) (xy 113.619026 -24.688292)
			(xy 113.661695 -24.670063) (xy 113.749985 -24.641515) (xy 113.840768 -24.622317) (xy 113.933056 -24.612679)
			(xy 113.979452 -24.612092) (xy 114.025847 -24.612692) (xy 114.118135 -24.622332) (xy 114.208919 -24.641523)
			(xy 114.297213 -24.670056) (xy 114.339878 -24.688292) (xy 114.34982 -24.692098) (xy 114.371084 -24.692098)
			(xy 114.381026 -24.688292) (xy 114.423695 -24.670063) (xy 114.511985 -24.641515) (xy 114.602768 -24.622317)
			(xy 114.695056 -24.612679) (xy 114.741452 -24.612092) (xy 114.787847 -24.612692) (xy 114.880135 -24.622332)
			(xy 114.970919 -24.641523) (xy 115.059213 -24.670056) (xy 115.101878 -24.688292) (xy 115.11182 -24.692098)
			(xy 115.133084 -24.692098) (xy 115.143026 -24.688292) (xy 115.185635 -24.670086) (xy 115.2738 -24.641564)
			(xy 115.364454 -24.622367) (xy 115.456612 -24.612703) (xy 115.502944 -24.612092) (xy 115.503452 -24.612092)
			(xy 115.544554 -24.612598) (xy 115.626409 -24.620179) (xy 115.707215 -24.63528) (xy 115.786282 -24.657773)
			(xy 115.862937 -24.687465) (xy 115.936525 -24.724104) (xy 116.006418 -24.767377) (xy 116.072021 -24.816914)
			(xy 116.132772 -24.872294) (xy 116.188155 -24.933042) (xy 116.237696 -24.998642) (xy 116.280972 -25.068533)
			(xy 116.317615 -25.142119) (xy 116.347312 -25.218772) (xy 116.369809 -25.297839) (xy 116.384915 -25.378644)
			(xy 116.3925 -25.460498) (xy 116.39296 -25.5016) (xy 116.39296 -25.502108) (xy 116.392358 -25.54844)
			(xy 116.382686 -25.640598) (xy 116.363489 -25.731252) (xy 116.334976 -25.819421) (xy 116.31676 -25.862026)
			(xy 116.312952 -25.871968) (xy 116.312952 -25.893232) (xy 116.31676 -25.903174) (xy 116.335002 -25.945837)
			(xy 116.363547 -26.034129) (xy 116.382741 -26.124914) (xy 116.392375 -26.217204) (xy 116.39296 -26.2636)
			(xy 116.392381 -26.309996) (xy 116.382736 -26.402284) (xy 116.363539 -26.493068) (xy 116.334999 -26.581361)
			(xy 116.31676 -26.624026) (xy 116.312952 -26.633968) (xy 116.312952 -26.655232) (xy 116.31676 -26.665174)
			(xy 116.335002 -26.707837) (xy 116.363547 -26.796129) (xy 116.382741 -26.886914) (xy 116.392375 -26.979204)
			(xy 116.39296 -27.0256) (xy 116.392381 -27.071996) (xy 116.382736 -27.164284) (xy 116.363539 -27.255068)
			(xy 116.334999 -27.343361) (xy 116.31676 -27.386026) (xy 116.312952 -27.395968) (xy 116.312952 -27.417232)
			(xy 116.31676 -27.427174) (xy 116.335002 -27.469837) (xy 116.363547 -27.558129) (xy 116.382741 -27.648914)
			(xy 116.392375 -27.741204) (xy 116.39296 -27.7876) (xy 116.392381 -27.833996) (xy 116.382736 -27.926284)
			(xy 116.363539 -28.017068) (xy 116.334999 -28.105361) (xy 116.31676 -28.148026) (xy 116.312952 -28.157968)
			(xy 116.312952 -28.179232) (xy 116.31676 -28.189174) (xy 116.334985 -28.231776) (xy 116.363501 -28.319944)
			(xy 116.382693 -28.410599) (xy 116.392352 -28.50276) (xy 116.39296 -28.549092) (xy 116.39296 -28.5496)
			(xy 116.392548 -28.590705) (xy 116.384962 -28.672563) (xy 116.369856 -28.753372) (xy 116.347357 -28.832443)
			(xy 116.317659 -28.9091) (xy 116.281014 -28.98269) (xy 116.237735 -29.052585) (xy 116.188192 -29.118188)
			(xy 116.132806 -29.17894) (xy 116.072051 -29.234322) (xy 116.006446 -29.283862) (xy 115.936548 -29.327138)
			(xy 115.862956 -29.363779) (xy 115.786297 -29.393473) (xy 115.707226 -29.415967) (xy 115.626415 -29.431069)
			(xy 115.544557 -29.43865) (xy 115.503452 -29.439108) (xy 115.502944 -29.439108) (xy 115.456613 -29.438484)
			(xy 115.364455 -29.428818) (xy 115.273801 -29.409627) (xy 115.185632 -29.381121) (xy 115.143026 -29.362908)
			(xy 115.133084 -29.359102) (xy 115.11182 -29.359102) (xy 115.101878 -29.362908) (xy 115.059209 -29.381136)
			(xy 114.970919 -29.409684) (xy 114.880136 -29.428882) (xy 114.787847 -29.43852) (xy 114.741452 -29.439108)
			(xy 114.695057 -29.438507) (xy 114.602769 -29.428867) (xy 114.511985 -29.409676) (xy 114.423691 -29.381143)
			(xy 114.381026 -29.362908) (xy 114.371084 -29.359102) (xy 114.34982 -29.359102) (xy 114.339878 -29.362908)
			(xy 114.297209 -29.381136) (xy 114.208919 -29.409684) (xy 114.118136 -29.428882) (xy 114.025847 -29.43852)
			(xy 113.979452 -29.439108) (xy 113.933057 -29.438507) (xy 113.840769 -29.428867) (xy 113.749985 -29.409676)
			(xy 113.661691 -29.381143) (xy 113.619026 -29.362908) (xy 113.609084 -29.359102) (xy 113.58782 -29.359102)
			(xy 113.577878 -29.362908) (xy 113.535209 -29.381136) (xy 113.446919 -29.409684) (xy 113.356136 -29.428882)
			(xy 113.263847 -29.43852) (xy 113.217452 -29.439108) (xy 113.171057 -29.438507) (xy 113.078769 -29.428867)
			(xy 112.987985 -29.409676) (xy 112.899691 -29.381143) (xy 112.857026 -29.362908) (xy 112.847084 -29.359102)
			(xy 112.82582 -29.359102) (xy 112.815878 -29.362908) (xy 112.773268 -29.381113) (xy 112.685103 -29.409635)
			(xy 112.59445 -29.428833) (xy 112.502292 -29.438497) (xy 112.45596 -29.439108) (xy 112.455452 -29.439108)
			(xy 112.414349 -29.438679) (xy 112.332493 -29.43109) (xy 112.251687 -29.415981) (xy 112.17262 -29.39348)
			(xy 112.095965 -29.363781) (xy 112.022379 -29.327135) (xy 111.952487 -29.283857) (xy 111.886886 -29.234314)
			(xy 111.826136 -29.17893) (xy 111.770755 -29.118177) (xy 111.721216 -29.052574) (xy 111.677941 -28.982679)
			(xy 111.6413 -28.909091) (xy 111.611604 -28.832435) (xy 111.589108 -28.753366) (xy 111.574003 -28.672559)
			(xy 111.566419 -28.590703) (xy 111.565944 -28.5496) (xy 0.509016 -28.5496) (xy 0.509016 -33.595761)
			(xy 111.362994 -33.595761) (xy 111.362994 -33.511039) (xy 111.371047 -33.426702) (xy 111.387081 -33.343512)
			(xy 111.410949 -33.262222) (xy 111.442437 -33.18357) (xy 111.481259 -33.108267) (xy 111.527062 -33.036995)
			(xy 111.579433 -32.970399) (xy 111.637898 -32.909084) (xy 111.701926 -32.853603) (xy 111.770938 -32.80446)
			(xy 111.844308 -32.7621) (xy 111.921373 -32.726905) (xy 112.001435 -32.699196) (xy 112.083768 -32.679222)
			(xy 112.167627 -32.667165) (xy 112.252252 -32.663134) (xy 112.336877 -32.667165) (xy 112.420736 -32.679222)
			(xy 112.503069 -32.699196) (xy 112.583131 -32.726905) (xy 112.660196 -32.7621) (xy 112.733566 -32.80446)
			(xy 112.802578 -32.853603) (xy 112.866606 -32.909084) (xy 112.925071 -32.970399) (xy 112.977442 -33.036995)
			(xy 113.023245 -33.108267) (xy 113.062067 -33.18357) (xy 113.093555 -33.262222) (xy 113.117423 -33.343512)
			(xy 113.133457 -33.426702) (xy 113.14151 -33.511039) (xy 113.142014 -33.5534) (xy 113.14151 -33.595761)
			(xy 113.133457 -33.680098) (xy 113.117423 -33.763288) (xy 113.093555 -33.844578) (xy 113.062067 -33.92323)
			(xy 113.023245 -33.998533) (xy 112.977442 -34.069805) (xy 112.925071 -34.136401) (xy 112.866606 -34.197716)
			(xy 112.802578 -34.253197) (xy 112.733566 -34.30234) (xy 112.660196 -34.3447) (xy 112.583131 -34.379895)
			(xy 112.503069 -34.407604) (xy 112.420736 -34.427578) (xy 112.336877 -34.439635) (xy 112.252252 -34.443667)
			(xy 112.167627 -34.439635) (xy 112.083768 -34.427578) (xy 112.001435 -34.407604) (xy 111.921373 -34.379895)
			(xy 111.844308 -34.3447) (xy 111.770938 -34.30234) (xy 111.701926 -34.253197) (xy 111.637898 -34.197716)
			(xy 111.579433 -34.136401) (xy 111.527062 -34.069805) (xy 111.481259 -33.998533) (xy 111.442437 -33.92323)
			(xy 111.410949 -33.844578) (xy 111.387081 -33.763288) (xy 111.371047 -33.680098) (xy 111.362994 -33.595761)
			(xy 0.509016 -33.595761) (xy 0.509016 -39.8272) (xy 111.565944 -39.8272) (xy 111.565944 -39.826692)
			(xy 111.566546 -39.78036) (xy 111.576218 -39.688202) (xy 111.595414 -39.597548) (xy 111.623928 -39.509379)
			(xy 111.642144 -39.466774) (xy 111.645952 -39.456832) (xy 111.645952 -39.435568) (xy 111.642144 -39.425626)
			(xy 111.623902 -39.382962) (xy 111.595357 -39.294671) (xy 111.576163 -39.203886) (xy 111.566529 -39.111596)
			(xy 111.565944 -39.0652) (xy 111.566522 -39.018804) (xy 111.576168 -38.926516) (xy 111.595365 -38.835732)
			(xy 111.623905 -38.747439) (xy 111.642144 -38.704774) (xy 111.645952 -38.694832) (xy 111.645952 -38.673568)
			(xy 111.642144 -38.663626) (xy 111.623902 -38.620962) (xy 111.595357 -38.532671) (xy 111.576163 -38.441886)
			(xy 111.566529 -38.349596) (xy 111.565944 -38.3032) (xy 111.566522 -38.256804) (xy 111.576168 -38.164516)
			(xy 111.595365 -38.073732) (xy 111.623905 -37.985439) (xy 111.642144 -37.942774) (xy 111.645952 -37.932832)
			(xy 111.645952 -37.911568) (xy 111.642144 -37.901626) (xy 111.623902 -37.858962) (xy 111.595357 -37.770671)
			(xy 111.576163 -37.679886) (xy 111.566529 -37.587596) (xy 111.565944 -37.5412) (xy 111.566522 -37.494804)
			(xy 111.576168 -37.402516) (xy 111.595365 -37.311732) (xy 111.623905 -37.223439) (xy 111.642144 -37.180774)
			(xy 111.645952 -37.170832) (xy 111.645952 -37.149568) (xy 111.642144 -37.139626) (xy 111.623919 -37.097024)
			(xy 111.595403 -37.008856) (xy 111.576211 -36.9182) (xy 111.566552 -36.82604) (xy 111.565944 -36.779708)
			(xy 111.565944 -36.7792) (xy 111.566467 -36.738099) (xy 111.574051 -36.656247) (xy 111.589155 -36.575445)
			(xy 111.61165 -36.49638) (xy 111.641344 -36.419729) (xy 111.677983 -36.346144) (xy 111.721256 -36.276253)
			(xy 111.770792 -36.210654) (xy 111.82617 -36.149904) (xy 111.886917 -36.094523) (xy 111.952514 -36.044983)
			(xy 112.022402 -36.001707) (xy 112.095985 -35.965063) (xy 112.172635 -35.935365) (xy 112.251698 -35.912866)
			(xy 112.3325 -35.897758) (xy 112.414351 -35.890169) (xy 112.455452 -35.889692) (xy 112.45596 -35.889692)
			(xy 112.502291 -35.890315) (xy 112.594449 -35.899981) (xy 112.685103 -35.919172) (xy 112.773272 -35.947679)
			(xy 112.815878 -35.965892) (xy 112.82582 -35.969698) (xy 112.847084 -35.969698) (xy 112.857026 -35.965892)
			(xy 112.899695 -35.947663) (xy 112.987985 -35.919115) (xy 113.078768 -35.899917) (xy 113.171056 -35.890279)
			(xy 113.217452 -35.889692) (xy 113.263847 -35.890292) (xy 113.356135 -35.899932) (xy 113.446919 -35.919123)
			(xy 113.535213 -35.947656) (xy 113.577878 -35.965892) (xy 113.58782 -35.969698) (xy 113.609084 -35.969698)
			(xy 113.619026 -35.965892) (xy 113.661695 -35.947663) (xy 113.749985 -35.919115) (xy 113.840768 -35.899917)
			(xy 113.933056 -35.890279) (xy 113.979452 -35.889692) (xy 114.025847 -35.890292) (xy 114.118135 -35.899932)
			(xy 114.208919 -35.919123) (xy 114.297213 -35.947656) (xy 114.339878 -35.965892) (xy 114.34982 -35.969698)
			(xy 114.371084 -35.969698) (xy 114.381026 -35.965892) (xy 114.423695 -35.947663) (xy 114.511985 -35.919115)
			(xy 114.602768 -35.899917) (xy 114.695056 -35.890279) (xy 114.741452 -35.889692) (xy 114.787847 -35.890292)
			(xy 114.880135 -35.899932) (xy 114.970919 -35.919123) (xy 115.059213 -35.947656) (xy 115.101878 -35.965892)
			(xy 115.11182 -35.969698) (xy 115.133084 -35.969698) (xy 115.143026 -35.965892) (xy 115.185635 -35.947686)
			(xy 115.2738 -35.919164) (xy 115.364454 -35.899967) (xy 115.456612 -35.890303) (xy 115.502944 -35.889692)
			(xy 115.503452 -35.889692) (xy 115.544554 -35.890198) (xy 115.626409 -35.897779) (xy 115.707215 -35.91288)
			(xy 115.786282 -35.935373) (xy 115.862937 -35.965065) (xy 115.936525 -36.001704) (xy 116.006418 -36.044977)
			(xy 116.072021 -36.094514) (xy 116.132772 -36.149894) (xy 116.188155 -36.210642) (xy 116.237696 -36.276242)
			(xy 116.280972 -36.346133) (xy 116.317615 -36.419719) (xy 116.347312 -36.496372) (xy 116.369809 -36.575439)
			(xy 116.384915 -36.656244) (xy 116.3925 -36.738098) (xy 116.39296 -36.7792) (xy 116.39296 -36.779708)
			(xy 116.392358 -36.82604) (xy 116.382686 -36.918198) (xy 116.363489 -37.008852) (xy 116.334976 -37.097021)
			(xy 116.31676 -37.139626) (xy 116.312952 -37.149568) (xy 116.312952 -37.170832) (xy 116.31676 -37.180774)
			(xy 116.335002 -37.223437) (xy 116.363547 -37.311729) (xy 116.382741 -37.402514) (xy 116.392375 -37.494804)
			(xy 116.39296 -37.5412) (xy 116.392381 -37.587596) (xy 116.382736 -37.679884) (xy 116.363539 -37.770668)
			(xy 116.334999 -37.858961) (xy 116.31676 -37.901626) (xy 116.312952 -37.911568) (xy 116.312952 -37.932832)
			(xy 116.31676 -37.942774) (xy 116.335002 -37.985437) (xy 116.363547 -38.073729) (xy 116.382741 -38.164514)
			(xy 116.392375 -38.256804) (xy 116.39296 -38.3032) (xy 116.392381 -38.349596) (xy 116.382736 -38.441884)
			(xy 116.363539 -38.532668) (xy 116.334999 -38.620961) (xy 116.31676 -38.663626) (xy 116.312952 -38.673568)
			(xy 116.312952 -38.694832) (xy 116.31676 -38.704774) (xy 116.335002 -38.747437) (xy 116.363547 -38.835729)
			(xy 116.382741 -38.926514) (xy 116.392375 -39.018804) (xy 116.39296 -39.0652) (xy 116.392381 -39.111596)
			(xy 116.382736 -39.203884) (xy 116.363539 -39.294668) (xy 116.334999 -39.382961) (xy 116.31676 -39.425626)
			(xy 116.312952 -39.435568) (xy 116.312952 -39.456832) (xy 116.31676 -39.466774) (xy 116.334985 -39.509376)
			(xy 116.363501 -39.597544) (xy 116.382693 -39.688199) (xy 116.392352 -39.78036) (xy 116.39296 -39.826692)
			(xy 116.39296 -39.8272) (xy 116.392548 -39.868305) (xy 116.384962 -39.950163) (xy 116.369856 -40.030972)
			(xy 116.347357 -40.110043) (xy 116.317659 -40.1867) (xy 116.281014 -40.26029) (xy 116.237735 -40.330185)
			(xy 116.188192 -40.395788) (xy 116.132806 -40.45654) (xy 116.072051 -40.511922) (xy 116.006446 -40.561462)
			(xy 115.936548 -40.604738) (xy 115.862956 -40.641379) (xy 115.786297 -40.671073) (xy 115.707226 -40.693567)
			(xy 115.626415 -40.708669) (xy 115.544557 -40.71625) (xy 115.503452 -40.716708) (xy 115.502944 -40.716708)
			(xy 115.456613 -40.716084) (xy 115.364455 -40.706418) (xy 115.273801 -40.687227) (xy 115.185632 -40.658721)
			(xy 115.143026 -40.640508) (xy 115.133084 -40.636702) (xy 115.11182 -40.636702) (xy 115.101878 -40.640508)
			(xy 115.059209 -40.658736) (xy 114.970919 -40.687284) (xy 114.880136 -40.706482) (xy 114.787847 -40.71612)
			(xy 114.741452 -40.716708) (xy 114.695057 -40.716107) (xy 114.602769 -40.706467) (xy 114.511985 -40.687276)
			(xy 114.423691 -40.658743) (xy 114.381026 -40.640508) (xy 114.371084 -40.636702) (xy 114.34982 -40.636702)
			(xy 114.339878 -40.640508) (xy 114.297209 -40.658736) (xy 114.208919 -40.687284) (xy 114.118136 -40.706482)
			(xy 114.025847 -40.71612) (xy 113.979452 -40.716708) (xy 113.933057 -40.716107) (xy 113.840769 -40.706467)
			(xy 113.749985 -40.687276) (xy 113.661691 -40.658743) (xy 113.619026 -40.640508) (xy 113.609084 -40.636702)
			(xy 113.58782 -40.636702) (xy 113.577878 -40.640508) (xy 113.535209 -40.658736) (xy 113.446919 -40.687284)
			(xy 113.356136 -40.706482) (xy 113.263847 -40.71612) (xy 113.217452 -40.716708) (xy 113.171057 -40.716107)
			(xy 113.078769 -40.706467) (xy 112.987985 -40.687276) (xy 112.899691 -40.658743) (xy 112.857026 -40.640508)
			(xy 112.847084 -40.636702) (xy 112.82582 -40.636702) (xy 112.815878 -40.640508) (xy 112.773268 -40.658713)
			(xy 112.685103 -40.687235) (xy 112.59445 -40.706433) (xy 112.502292 -40.716097) (xy 112.45596 -40.716708)
			(xy 112.455452 -40.716708) (xy 112.414349 -40.716279) (xy 112.332493 -40.70869) (xy 112.251687 -40.693581)
			(xy 112.17262 -40.67108) (xy 112.095965 -40.641381) (xy 112.022379 -40.604735) (xy 111.952487 -40.561457)
			(xy 111.886886 -40.511914) (xy 111.826136 -40.45653) (xy 111.770755 -40.395777) (xy 111.721216 -40.330174)
			(xy 111.677941 -40.260279) (xy 111.6413 -40.186691) (xy 111.611604 -40.110035) (xy 111.589108 -40.030966)
			(xy 111.574003 -39.950159) (xy 111.566419 -39.868303) (xy 111.565944 -39.8272) (xy 0.509016 -39.8272)
			(xy 0.509016 -42.474585) (xy 107.8931 -42.474585) (xy 107.8931 -42.389863) (xy 107.901153 -42.305526)
			(xy 107.917187 -42.222336) (xy 107.941055 -42.141046) (xy 107.972543 -42.062394) (xy 108.011365 -41.987091)
			(xy 108.057168 -41.915819) (xy 108.109539 -41.849223) (xy 108.168004 -41.787908) (xy 108.232032 -41.732427)
			(xy 108.301044 -41.683284) (xy 108.374414 -41.640924) (xy 108.451479 -41.605729) (xy 108.531541 -41.57802)
			(xy 108.613874 -41.558046) (xy 108.697733 -41.545989) (xy 108.782358 -41.541958) (xy 108.866983 -41.545989)
			(xy 108.950842 -41.558046) (xy 109.033175 -41.57802) (xy 109.113237 -41.605729) (xy 109.190302 -41.640924)
			(xy 109.263672 -41.683284) (xy 109.332684 -41.732427) (xy 109.396712 -41.787908) (xy 109.455177 -41.849223)
			(xy 109.507548 -41.915819) (xy 109.553351 -41.987091) (xy 109.592173 -42.062394) (xy 109.623661 -42.141046)
			(xy 109.647529 -42.222336) (xy 109.663563 -42.305526) (xy 109.671616 -42.389863) (xy 109.67212 -42.432224)
			(xy 109.671616 -42.474585) (xy 109.663563 -42.558922) (xy 109.647529 -42.642112) (xy 109.623661 -42.723402)
			(xy 109.592173 -42.802054) (xy 109.553351 -42.877357) (xy 109.507548 -42.948629) (xy 109.455177 -43.015225)
			(xy 109.396712 -43.07654) (xy 109.332684 -43.132021) (xy 109.263672 -43.181164) (xy 109.192316 -43.222361)
			(xy 110.388142 -43.222361) (xy 110.388142 -43.137639) (xy 110.396195 -43.053302) (xy 110.412229 -42.970112)
			(xy 110.436097 -42.888822) (xy 110.467585 -42.81017) (xy 110.506407 -42.734867) (xy 110.55221 -42.663595)
			(xy 110.604581 -42.596999) (xy 110.663046 -42.535684) (xy 110.727074 -42.480203) (xy 110.796086 -42.43106)
			(xy 110.869456 -42.3887) (xy 110.946521 -42.353505) (xy 111.026583 -42.325796) (xy 111.108916 -42.305822)
			(xy 111.192775 -42.293765) (xy 111.2774 -42.289734) (xy 111.362025 -42.293765) (xy 111.445884 -42.305822)
			(xy 111.528217 -42.325796) (xy 111.608279 -42.353505) (xy 111.685344 -42.3887) (xy 111.758714 -42.43106)
			(xy 111.827726 -42.480203) (xy 111.891754 -42.535684) (xy 111.950219 -42.596999) (xy 112.00259 -42.663595)
			(xy 112.048393 -42.734867) (xy 112.087215 -42.81017) (xy 112.118703 -42.888822) (xy 112.142571 -42.970112)
			(xy 112.158605 -43.053302) (xy 112.166658 -43.137639) (xy 112.167162 -43.18) (xy 112.166658 -43.222361)
			(xy 112.158605 -43.306698) (xy 112.142571 -43.389888) (xy 112.118703 -43.471178) (xy 112.087215 -43.54983)
			(xy 112.048393 -43.625133) (xy 112.00259 -43.696405) (xy 111.950219 -43.763001) (xy 111.891754 -43.824316)
			(xy 111.827726 -43.879797) (xy 111.758714 -43.92894) (xy 111.685344 -43.9713) (xy 111.608279 -44.006495)
			(xy 111.528217 -44.034204) (xy 111.445884 -44.054178) (xy 111.362025 -44.066235) (xy 111.2774 -44.070267)
			(xy 111.192775 -44.066235) (xy 111.108916 -44.054178) (xy 111.026583 -44.034204) (xy 110.946521 -44.006495)
			(xy 110.869456 -43.9713) (xy 110.796086 -43.92894) (xy 110.727074 -43.879797) (xy 110.663046 -43.824316)
			(xy 110.604581 -43.763001) (xy 110.55221 -43.696405) (xy 110.506407 -43.625133) (xy 110.467585 -43.54983)
			(xy 110.436097 -43.471178) (xy 110.412229 -43.389888) (xy 110.396195 -43.306698) (xy 110.388142 -43.222361)
			(xy 109.192316 -43.222361) (xy 109.190302 -43.223524) (xy 109.113237 -43.258719) (xy 109.033175 -43.286428)
			(xy 108.950842 -43.306402) (xy 108.866983 -43.318459) (xy 108.782358 -43.322491) (xy 108.697733 -43.318459)
			(xy 108.613874 -43.306402) (xy 108.531541 -43.286428) (xy 108.451479 -43.258719) (xy 108.374414 -43.223524)
			(xy 108.301044 -43.181164) (xy 108.232032 -43.132021) (xy 108.168004 -43.07654) (xy 108.109539 -43.015225)
			(xy 108.057168 -42.948629) (xy 108.011365 -42.877357) (xy 107.972543 -42.802054) (xy 107.941055 -42.723402)
			(xy 107.917187 -42.642112) (xy 107.901153 -42.558922) (xy 107.8931 -42.474585) (xy 0.509016 -42.474585)
			(xy 0.509016 -44.873361) (xy 111.362994 -44.873361) (xy 111.362994 -44.788639) (xy 111.371047 -44.704302)
			(xy 111.387081 -44.621112) (xy 111.410949 -44.539822) (xy 111.442437 -44.46117) (xy 111.481259 -44.385867)
			(xy 111.527062 -44.314595) (xy 111.579433 -44.247999) (xy 111.637898 -44.186684) (xy 111.701926 -44.131203)
			(xy 111.770938 -44.08206) (xy 111.844308 -44.0397) (xy 111.921373 -44.004505) (xy 112.001435 -43.976796)
			(xy 112.083768 -43.956822) (xy 112.167627 -43.944765) (xy 112.252252 -43.940734) (xy 112.336877 -43.944765)
			(xy 112.420736 -43.956822) (xy 112.503069 -43.976796) (xy 112.583131 -44.004505) (xy 112.660196 -44.0397)
			(xy 112.733566 -44.08206) (xy 112.802578 -44.131203) (xy 112.866606 -44.186684) (xy 112.925071 -44.247999)
			(xy 112.977442 -44.314595) (xy 113.023245 -44.385867) (xy 113.062067 -44.46117) (xy 113.093555 -44.539822)
			(xy 113.117423 -44.621112) (xy 113.133457 -44.704302) (xy 113.14151 -44.788639) (xy 113.142014 -44.831)
			(xy 113.14151 -44.873361) (xy 113.133457 -44.957698) (xy 113.117423 -45.040888) (xy 113.093555 -45.122178)
			(xy 113.062067 -45.20083) (xy 113.023245 -45.276133) (xy 112.977442 -45.347405) (xy 112.925071 -45.414001)
			(xy 112.866606 -45.475316) (xy 112.802578 -45.530797) (xy 112.733566 -45.57994) (xy 112.660196 -45.6223)
			(xy 112.583131 -45.657495) (xy 112.503069 -45.685204) (xy 112.420736 -45.705178) (xy 112.336877 -45.717235)
			(xy 112.252252 -45.721267) (xy 112.167627 -45.717235) (xy 112.083768 -45.705178) (xy 112.001435 -45.685204)
			(xy 111.921373 -45.657495) (xy 111.844308 -45.6223) (xy 111.770938 -45.57994) (xy 111.701926 -45.530797)
			(xy 111.637898 -45.475316) (xy 111.579433 -45.414001) (xy 111.527062 -45.347405) (xy 111.481259 -45.276133)
			(xy 111.442437 -45.20083) (xy 111.410949 -45.122178) (xy 111.387081 -45.040888) (xy 111.371047 -44.957698)
			(xy 111.362994 -44.873361) (xy 0.509016 -44.873361) (xy 0.509016 -50.919888) (xy 41.345622 -50.919888)
			(xy 41.349604 -50.829938) (xy 41.361521 -50.740691) (xy 41.381279 -50.652847) (xy 41.408723 -50.567093)
			(xy 41.443639 -50.4841) (xy 41.485753 -50.404518) (xy 41.534736 -50.328969) (xy 41.590204 -50.258045)
			(xy 41.651724 -50.1923) (xy 41.718813 -50.13225) (xy 41.790947 -50.078365) (xy 41.867561 -50.031065)
			(xy 41.948055 -49.990722) (xy 42.0318 -49.95765) (xy 42.118141 -49.93211) (xy 42.2064 -49.9143) (xy 42.295889 -49.90436)
			(xy 42.385905 -49.902369) (xy 42.475746 -49.90834) (xy 42.564707 -49.922229) (xy 42.652092 -49.943925)
			(xy 42.737218 -49.97326) (xy 42.819418 -50.010003) (xy 42.898049 -50.053867) (xy 42.972496 -50.104509)
			(xy 43.042176 -50.161533) (xy 43.106543 -50.224492) (xy 43.165094 -50.292893) (xy 43.217371 -50.366201)
			(xy 43.262964 -50.443843) (xy 43.301517 -50.52521) (xy 43.332728 -50.609666) (xy 43.356352 -50.69655)
			(xy 43.372205 -50.785182) (xy 43.380162 -50.874869) (xy 43.38066 -50.919888) (xy 60.903622 -50.919888)
			(xy 60.907604 -50.829938) (xy 60.919521 -50.740691) (xy 60.939279 -50.652847) (xy 60.966723 -50.567093)
			(xy 61.001639 -50.4841) (xy 61.043753 -50.404518) (xy 61.092736 -50.328969) (xy 61.148204 -50.258045)
			(xy 61.209724 -50.1923) (xy 61.276813 -50.13225) (xy 61.348947 -50.078365) (xy 61.425561 -50.031065)
			(xy 61.506055 -49.990722) (xy 61.5898 -49.95765) (xy 61.676141 -49.93211) (xy 61.7644 -49.9143) (xy 61.853889 -49.90436)
			(xy 61.943905 -49.902369) (xy 62.033746 -49.90834) (xy 62.122707 -49.922229) (xy 62.210092 -49.943925)
			(xy 62.295218 -49.97326) (xy 62.377418 -50.010003) (xy 62.456049 -50.053867) (xy 62.530496 -50.104509)
			(xy 62.600176 -50.161533) (xy 62.664543 -50.224492) (xy 62.723094 -50.292893) (xy 62.775371 -50.366201)
			(xy 62.820964 -50.443843) (xy 62.859517 -50.52521) (xy 62.890728 -50.609666) (xy 62.914352 -50.69655)
			(xy 62.930205 -50.785182) (xy 62.938162 -50.874869) (xy 62.93866 -50.919888) (xy 62.938162 -50.964907)
			(xy 62.930205 -51.054594) (xy 62.921225 -51.1048) (xy 111.565944 -51.1048) (xy 111.565944 -51.104292)
			(xy 111.566546 -51.05796) (xy 111.576218 -50.965802) (xy 111.595414 -50.875148) (xy 111.623928 -50.786979)
			(xy 111.642144 -50.744374) (xy 111.645952 -50.734432) (xy 111.645952 -50.713168) (xy 111.642144 -50.703226)
			(xy 111.623902 -50.660562) (xy 111.595357 -50.572271) (xy 111.576163 -50.481486) (xy 111.566529 -50.389196)
			(xy 111.565944 -50.3428) (xy 111.566522 -50.296404) (xy 111.576168 -50.204116) (xy 111.595365 -50.113332)
			(xy 111.623905 -50.025039) (xy 111.642144 -49.982374) (xy 111.645952 -49.972432) (xy 111.645952 -49.951168)
			(xy 111.642144 -49.941226) (xy 111.623902 -49.898562) (xy 111.595357 -49.810271) (xy 111.576163 -49.719486)
			(xy 111.566529 -49.627196) (xy 111.565944 -49.5808) (xy 111.566522 -49.534404) (xy 111.576168 -49.442116)
			(xy 111.595365 -49.351332) (xy 111.623905 -49.263039) (xy 111.642144 -49.220374) (xy 111.645952 -49.210432)
			(xy 111.645952 -49.189168) (xy 111.642144 -49.179226) (xy 111.623902 -49.136562) (xy 111.595357 -49.048271)
			(xy 111.576163 -48.957486) (xy 111.566529 -48.865196) (xy 111.565944 -48.8188) (xy 111.566522 -48.772404)
			(xy 111.576168 -48.680116) (xy 111.595365 -48.589332) (xy 111.623905 -48.501039) (xy 111.642144 -48.458374)
			(xy 111.645952 -48.448432) (xy 111.645952 -48.427168) (xy 111.642144 -48.417226) (xy 111.623919 -48.374624)
			(xy 111.595403 -48.286456) (xy 111.576211 -48.1958) (xy 111.566552 -48.10364) (xy 111.565944 -48.057308)
			(xy 111.565944 -48.0568) (xy 111.566467 -48.015699) (xy 111.574051 -47.933847) (xy 111.589155 -47.853045)
			(xy 111.61165 -47.77398) (xy 111.641344 -47.697329) (xy 111.677983 -47.623744) (xy 111.721256 -47.553853)
			(xy 111.770792 -47.488254) (xy 111.82617 -47.427504) (xy 111.886917 -47.372123) (xy 111.952514 -47.322583)
			(xy 112.022402 -47.279307) (xy 112.095985 -47.242663) (xy 112.172635 -47.212965) (xy 112.251698 -47.190466)
			(xy 112.3325 -47.175358) (xy 112.414351 -47.167769) (xy 112.455452 -47.167292) (xy 112.45596 -47.167292)
			(xy 112.502291 -47.167915) (xy 112.594449 -47.177581) (xy 112.685103 -47.196772) (xy 112.773272 -47.225279)
			(xy 112.815878 -47.243492) (xy 112.82582 -47.247298) (xy 112.847084 -47.247298) (xy 112.857026 -47.243492)
			(xy 112.899695 -47.225263) (xy 112.987985 -47.196715) (xy 113.078768 -47.177517) (xy 113.171056 -47.167879)
			(xy 113.217452 -47.167292) (xy 113.263847 -47.167892) (xy 113.356135 -47.177532) (xy 113.446919 -47.196723)
			(xy 113.535213 -47.225256) (xy 113.577878 -47.243492) (xy 113.58782 -47.247298) (xy 113.609084 -47.247298)
			(xy 113.619026 -47.243492) (xy 113.661695 -47.225263) (xy 113.749985 -47.196715) (xy 113.840768 -47.177517)
			(xy 113.933056 -47.167879) (xy 113.979452 -47.167292) (xy 114.025847 -47.167892) (xy 114.118135 -47.177532)
			(xy 114.208919 -47.196723) (xy 114.297213 -47.225256) (xy 114.339878 -47.243492) (xy 114.34982 -47.247298)
			(xy 114.371084 -47.247298) (xy 114.381026 -47.243492) (xy 114.423695 -47.225263) (xy 114.511985 -47.196715)
			(xy 114.602768 -47.177517) (xy 114.695056 -47.167879) (xy 114.741452 -47.167292) (xy 114.787847 -47.167892)
			(xy 114.880135 -47.177532) (xy 114.970919 -47.196723) (xy 115.059213 -47.225256) (xy 115.101878 -47.243492)
			(xy 115.11182 -47.247298) (xy 115.133084 -47.247298) (xy 115.143026 -47.243492) (xy 115.185635 -47.225286)
			(xy 115.2738 -47.196764) (xy 115.364454 -47.177567) (xy 115.456612 -47.167903) (xy 115.502944 -47.167292)
			(xy 115.503452 -47.167292) (xy 115.544554 -47.167798) (xy 115.626409 -47.175379) (xy 115.707215 -47.19048)
			(xy 115.786282 -47.212973) (xy 115.862937 -47.242665) (xy 115.936525 -47.279304) (xy 116.006418 -47.322577)
			(xy 116.072021 -47.372114) (xy 116.132772 -47.427494) (xy 116.188155 -47.488242) (xy 116.237696 -47.553842)
			(xy 116.280972 -47.623733) (xy 116.317615 -47.697319) (xy 116.347312 -47.773972) (xy 116.369809 -47.853039)
			(xy 116.384915 -47.933844) (xy 116.3925 -48.015698) (xy 116.39296 -48.0568) (xy 116.39296 -48.057308)
			(xy 116.392358 -48.10364) (xy 116.382686 -48.195798) (xy 116.363489 -48.286452) (xy 116.334976 -48.374621)
			(xy 116.31676 -48.417226) (xy 116.312952 -48.427168) (xy 116.312952 -48.448432) (xy 116.31676 -48.458374)
			(xy 116.335002 -48.501037) (xy 116.363547 -48.589329) (xy 116.382741 -48.680114) (xy 116.392375 -48.772404)
			(xy 116.39296 -48.8188) (xy 116.392381 -48.865196) (xy 116.382736 -48.957484) (xy 116.363539 -49.048268)
			(xy 116.334999 -49.136561) (xy 116.31676 -49.179226) (xy 116.312952 -49.189168) (xy 116.312952 -49.210432)
			(xy 116.31676 -49.220374) (xy 116.335002 -49.263037) (xy 116.363547 -49.351329) (xy 116.382741 -49.442114)
			(xy 116.392375 -49.534404) (xy 116.39296 -49.5808) (xy 116.392381 -49.627196) (xy 116.382736 -49.719484)
			(xy 116.363539 -49.810268) (xy 116.334999 -49.898561) (xy 116.31676 -49.941226) (xy 116.312952 -49.951168)
			(xy 116.312952 -49.972432) (xy 116.31676 -49.982374) (xy 116.335002 -50.025037) (xy 116.363547 -50.113329)
			(xy 116.382741 -50.204114) (xy 116.392375 -50.296404) (xy 116.39296 -50.3428) (xy 116.392381 -50.389196)
			(xy 116.382736 -50.481484) (xy 116.363539 -50.572268) (xy 116.334999 -50.660561) (xy 116.31676 -50.703226)
			(xy 116.312952 -50.713168) (xy 116.312952 -50.734432) (xy 116.31676 -50.744374) (xy 116.334985 -50.786976)
			(xy 116.363501 -50.875144) (xy 116.382693 -50.965799) (xy 116.392352 -51.05796) (xy 116.39296 -51.104292)
			(xy 116.39296 -51.1048) (xy 116.392548 -51.145905) (xy 116.384962 -51.227763) (xy 116.369856 -51.308572)
			(xy 116.347357 -51.387643) (xy 116.317659 -51.4643) (xy 116.281014 -51.53789) (xy 116.237735 -51.607785)
			(xy 116.188192 -51.673388) (xy 116.132806 -51.73414) (xy 116.072051 -51.789522) (xy 116.006446 -51.839062)
			(xy 115.936548 -51.882338) (xy 115.862956 -51.918979) (xy 115.786297 -51.948673) (xy 115.707226 -51.971167)
			(xy 115.626415 -51.986269) (xy 115.544557 -51.99385) (xy 115.503452 -51.994308) (xy 115.502944 -51.994308)
			(xy 115.456613 -51.993684) (xy 115.364455 -51.984018) (xy 115.273801 -51.964827) (xy 115.185632 -51.936321)
			(xy 115.143026 -51.918108) (xy 115.133084 -51.914302) (xy 115.11182 -51.914302) (xy 115.101878 -51.918108)
			(xy 115.059209 -51.936336) (xy 114.970919 -51.964884) (xy 114.880136 -51.984082) (xy 114.787847 -51.99372)
			(xy 114.741452 -51.994308) (xy 114.695057 -51.993707) (xy 114.602769 -51.984067) (xy 114.511985 -51.964876)
			(xy 114.423691 -51.936343) (xy 114.381026 -51.918108) (xy 114.371084 -51.914302) (xy 114.34982 -51.914302)
			(xy 114.339878 -51.918108) (xy 114.297209 -51.936336) (xy 114.208919 -51.964884) (xy 114.118136 -51.984082)
			(xy 114.025847 -51.99372) (xy 113.979452 -51.994308) (xy 113.933057 -51.993707) (xy 113.840769 -51.984067)
			(xy 113.749985 -51.964876) (xy 113.661691 -51.936343) (xy 113.619026 -51.918108) (xy 113.609084 -51.914302)
			(xy 113.58782 -51.914302) (xy 113.577878 -51.918108) (xy 113.535209 -51.936336) (xy 113.446919 -51.964884)
			(xy 113.356136 -51.984082) (xy 113.263847 -51.99372) (xy 113.217452 -51.994308) (xy 113.171057 -51.993707)
			(xy 113.078769 -51.984067) (xy 112.987985 -51.964876) (xy 112.899691 -51.936343) (xy 112.857026 -51.918108)
			(xy 112.847084 -51.914302) (xy 112.82582 -51.914302) (xy 112.815878 -51.918108) (xy 112.773268 -51.936313)
			(xy 112.685103 -51.964835) (xy 112.59445 -51.984033) (xy 112.502292 -51.993697) (xy 112.45596 -51.994308)
			(xy 112.455452 -51.994308) (xy 112.414349 -51.993879) (xy 112.332493 -51.98629) (xy 112.251687 -51.971181)
			(xy 112.17262 -51.94868) (xy 112.095965 -51.918981) (xy 112.022379 -51.882335) (xy 111.952487 -51.839057)
			(xy 111.886886 -51.789514) (xy 111.826136 -51.73413) (xy 111.770755 -51.673377) (xy 111.721216 -51.607774)
			(xy 111.677941 -51.537879) (xy 111.6413 -51.464291) (xy 111.611604 -51.387635) (xy 111.589108 -51.308566)
			(xy 111.574003 -51.227759) (xy 111.566419 -51.145903) (xy 111.565944 -51.1048) (xy 62.921225 -51.1048)
			(xy 62.914352 -51.143226) (xy 62.890728 -51.23011) (xy 62.859517 -51.314566) (xy 62.820964 -51.395933)
			(xy 62.775371 -51.473575) (xy 62.723094 -51.546883) (xy 62.664543 -51.615284) (xy 62.600176 -51.678243)
			(xy 62.530496 -51.735267) (xy 62.456049 -51.785909) (xy 62.377418 -51.829773) (xy 62.295218 -51.866516)
			(xy 62.210092 -51.895851) (xy 62.122707 -51.917547) (xy 62.033746 -51.931436) (xy 61.943905 -51.937407)
			(xy 61.853889 -51.935416) (xy 61.7644 -51.925476) (xy 61.676141 -51.907666) (xy 61.5898 -51.882126)
			(xy 61.506055 -51.849054) (xy 61.425561 -51.808711) (xy 61.348947 -51.761411) (xy 61.276813 -51.707526)
			(xy 61.209724 -51.647476) (xy 61.148204 -51.581731) (xy 61.092736 -51.510807) (xy 61.043753 -51.435258)
			(xy 61.001639 -51.355676) (xy 60.966723 -51.272683) (xy 60.939279 -51.186929) (xy 60.919521 -51.099085)
			(xy 60.907604 -51.009838) (xy 60.903622 -50.919888) (xy 43.38066 -50.919888) (xy 43.380162 -50.964907)
			(xy 43.372205 -51.054594) (xy 43.356352 -51.143226) (xy 43.332728 -51.23011) (xy 43.301517 -51.314566)
			(xy 43.262964 -51.395933) (xy 43.217371 -51.473575) (xy 43.165094 -51.546883) (xy 43.106543 -51.615284)
			(xy 43.042176 -51.678243) (xy 42.972496 -51.735267) (xy 42.898049 -51.785909) (xy 42.819418 -51.829773)
			(xy 42.737218 -51.866516) (xy 42.652092 -51.895851) (xy 42.564707 -51.917547) (xy 42.475746 -51.931436)
			(xy 42.385905 -51.937407) (xy 42.295889 -51.935416) (xy 42.2064 -51.925476) (xy 42.118141 -51.907666)
			(xy 42.0318 -51.882126) (xy 41.948055 -51.849054) (xy 41.867561 -51.808711) (xy 41.790947 -51.761411)
			(xy 41.718813 -51.707526) (xy 41.651724 -51.647476) (xy 41.590204 -51.581731) (xy 41.534736 -51.510807)
			(xy 41.485753 -51.435258) (xy 41.443639 -51.355676) (xy 41.408723 -51.272683) (xy 41.381279 -51.186929)
			(xy 41.361521 -51.099085) (xy 41.349604 -51.009838) (xy 41.345622 -50.919888) (xy 0.509016 -50.919888)
			(xy 0.509016 -53.735167) (xy 108.485174 -53.735167) (xy 108.485174 -53.650445) (xy 108.493227 -53.566108)
			(xy 108.509261 -53.482918) (xy 108.533129 -53.401628) (xy 108.564617 -53.322976) (xy 108.603439 -53.247673)
			(xy 108.649242 -53.176401) (xy 108.701613 -53.109805) (xy 108.760078 -53.04849) (xy 108.824106 -52.993009)
			(xy 108.893118 -52.943866) (xy 108.966488 -52.901506) (xy 109.043553 -52.866311) (xy 109.123615 -52.838602)
			(xy 109.205948 -52.818628) (xy 109.289807 -52.806571) (xy 109.374432 -52.80254) (xy 109.459057 -52.806571)
			(xy 109.542916 -52.818628) (xy 109.625249 -52.838602) (xy 109.705311 -52.866311) (xy 109.782376 -52.901506)
			(xy 109.855746 -52.943866) (xy 109.924758 -52.993009) (xy 109.988786 -53.04849) (xy 110.047251 -53.109805)
			(xy 110.099622 -53.176401) (xy 110.145425 -53.247673) (xy 110.184247 -53.322976) (xy 110.215735 -53.401628)
			(xy 110.239603 -53.482918) (xy 110.255637 -53.566108) (xy 110.26369 -53.650445) (xy 110.264194 -53.692806)
			(xy 110.26369 -53.735167) (xy 110.255637 -53.819504) (xy 110.239603 -53.902694) (xy 110.215735 -53.983984)
			(xy 110.184247 -54.062636) (xy 110.145425 -54.137939) (xy 110.099622 -54.209211) (xy 110.047251 -54.275807)
			(xy 109.988786 -54.337122) (xy 109.924758 -54.392603) (xy 109.855746 -54.441746) (xy 109.782376 -54.484106)
			(xy 109.705311 -54.519301) (xy 109.687801 -54.525361) (xy 110.388142 -54.525361) (xy 110.388142 -54.440639)
			(xy 110.396195 -54.356302) (xy 110.412229 -54.273112) (xy 110.436097 -54.191822) (xy 110.467585 -54.11317)
			(xy 110.506407 -54.037867) (xy 110.55221 -53.966595) (xy 110.604581 -53.899999) (xy 110.663046 -53.838684)
			(xy 110.727074 -53.783203) (xy 110.796086 -53.73406) (xy 110.869456 -53.6917) (xy 110.946521 -53.656505)
			(xy 111.026583 -53.628796) (xy 111.108916 -53.608822) (xy 111.192775 -53.596765) (xy 111.2774 -53.592734)
			(xy 111.362025 -53.596765) (xy 111.445884 -53.608822) (xy 111.528217 -53.628796) (xy 111.608279 -53.656505)
			(xy 111.685344 -53.6917) (xy 111.758714 -53.73406) (xy 111.827726 -53.783203) (xy 111.891754 -53.838684)
			(xy 111.950219 -53.899999) (xy 112.00259 -53.966595) (xy 112.048393 -54.037867) (xy 112.087215 -54.11317)
			(xy 112.118703 -54.191822) (xy 112.142571 -54.273112) (xy 112.158605 -54.356302) (xy 112.166658 -54.440639)
			(xy 112.167162 -54.483) (xy 112.166658 -54.525361) (xy 112.158605 -54.609698) (xy 112.142571 -54.692888)
			(xy 112.118703 -54.774178) (xy 112.087215 -54.85283) (xy 112.048393 -54.928133) (xy 112.00259 -54.999405)
			(xy 111.950219 -55.066001) (xy 111.891754 -55.127316) (xy 111.827726 -55.182797) (xy 111.758714 -55.23194)
			(xy 111.685344 -55.2743) (xy 111.608279 -55.309495) (xy 111.528217 -55.337204) (xy 111.445884 -55.357178)
			(xy 111.362025 -55.369235) (xy 111.2774 -55.373267) (xy 111.192775 -55.369235) (xy 111.108916 -55.357178)
			(xy 111.026583 -55.337204) (xy 110.946521 -55.309495) (xy 110.869456 -55.2743) (xy 110.796086 -55.23194)
			(xy 110.727074 -55.182797) (xy 110.663046 -55.127316) (xy 110.604581 -55.066001) (xy 110.55221 -54.999405)
			(xy 110.506407 -54.928133) (xy 110.467585 -54.85283) (xy 110.436097 -54.774178) (xy 110.412229 -54.692888)
			(xy 110.396195 -54.609698) (xy 110.388142 -54.525361) (xy 109.687801 -54.525361) (xy 109.625249 -54.54701)
			(xy 109.542916 -54.566984) (xy 109.459057 -54.579041) (xy 109.374432 -54.583073) (xy 109.289807 -54.579041)
			(xy 109.205948 -54.566984) (xy 109.123615 -54.54701) (xy 109.043553 -54.519301) (xy 108.966488 -54.484106)
			(xy 108.893118 -54.441746) (xy 108.824106 -54.392603) (xy 108.760078 -54.337122) (xy 108.701613 -54.275807)
			(xy 108.649242 -54.209211) (xy 108.603439 -54.137939) (xy 108.564617 -54.062636) (xy 108.533129 -53.983984)
			(xy 108.509261 -53.902694) (xy 108.493227 -53.819504) (xy 108.485174 -53.735167) (xy 0.509016 -53.735167)
			(xy 0.509016 -56.150961) (xy 111.362994 -56.150961) (xy 111.362994 -56.066239) (xy 111.371047 -55.981902)
			(xy 111.387081 -55.898712) (xy 111.410949 -55.817422) (xy 111.442437 -55.73877) (xy 111.481259 -55.663467)
			(xy 111.527062 -55.592195) (xy 111.579433 -55.525599) (xy 111.637898 -55.464284) (xy 111.701926 -55.408803)
			(xy 111.770938 -55.35966) (xy 111.844308 -55.3173) (xy 111.921373 -55.282105) (xy 112.001435 -55.254396)
			(xy 112.083768 -55.234422) (xy 112.167627 -55.222365) (xy 112.252252 -55.218334) (xy 112.336877 -55.222365)
			(xy 112.420736 -55.234422) (xy 112.503069 -55.254396) (xy 112.583131 -55.282105) (xy 112.660196 -55.3173)
			(xy 112.733566 -55.35966) (xy 112.802578 -55.408803) (xy 112.866606 -55.464284) (xy 112.925071 -55.525599)
			(xy 112.977442 -55.592195) (xy 113.023245 -55.663467) (xy 113.062067 -55.73877) (xy 113.093555 -55.817422)
			(xy 113.117423 -55.898712) (xy 113.133457 -55.981902) (xy 113.14151 -56.066239) (xy 113.142014 -56.1086)
			(xy 113.14151 -56.150961) (xy 113.133457 -56.235298) (xy 113.117423 -56.318488) (xy 113.093555 -56.399778)
			(xy 113.062067 -56.47843) (xy 113.023245 -56.553733) (xy 112.977442 -56.625005) (xy 112.925071 -56.691601)
			(xy 112.866606 -56.752916) (xy 112.802578 -56.808397) (xy 112.733566 -56.85754) (xy 112.660196 -56.8999)
			(xy 112.583131 -56.935095) (xy 112.503069 -56.962804) (xy 112.420736 -56.982778) (xy 112.336877 -56.994835)
			(xy 112.252252 -56.998867) (xy 112.167627 -56.994835) (xy 112.083768 -56.982778) (xy 112.001435 -56.962804)
			(xy 111.921373 -56.935095) (xy 111.844308 -56.8999) (xy 111.770938 -56.85754) (xy 111.701926 -56.808397)
			(xy 111.637898 -56.752916) (xy 111.579433 -56.691601) (xy 111.527062 -56.625005) (xy 111.481259 -56.553733)
			(xy 111.442437 -56.47843) (xy 111.410949 -56.399778) (xy 111.387081 -56.318488) (xy 111.371047 -56.235298)
			(xy 111.362994 -56.150961) (xy 0.509016 -56.150961) (xy 0.509016 -60.099956) (xy 12.484104 -60.099956)
			(xy 12.488134 -59.957621) (xy 12.500209 -59.815741) (xy 12.520292 -59.674773) (xy 12.548319 -59.535166)
			(xy 12.584199 -59.397368) (xy 12.627817 -59.261821) (xy 12.679034 -59.128959) (xy 12.737685 -58.999207)
			(xy 12.803583 -58.872981) (xy 12.876517 -58.750685) (xy 12.956254 -58.632712) (xy 13.042536 -58.519439)
			(xy 13.135089 -58.411228) (xy 13.233616 -58.308427) (xy 13.337801 -58.211365) (xy 13.44731 -58.120353)
			(xy 13.561793 -58.035681) (xy 13.680883 -57.957623) (xy 13.804198 -57.886427) (xy 13.931344 -57.822321)
			(xy 14.061913 -57.765512) (xy 14.195487 -57.71618) (xy 14.331638 -57.674484) (xy 14.469929 -57.640558)
			(xy 14.609919 -57.61451) (xy 14.751158 -57.596424) (xy 14.893194 -57.586357) (xy 15.035572 -57.584342)
			(xy 15.177836 -57.590385) (xy 15.31953 -57.604467) (xy 15.4602 -57.626543) (xy 15.599397 -57.656543)
			(xy 15.736673 -57.694369) (xy 15.871589 -57.739901) (xy 16.003713 -57.792992) (xy 16.132622 -57.853474)
			(xy 16.257903 -57.921152) (xy 16.379154 -57.995809) (xy 16.495987 -58.077207) (xy 16.608028 -58.165084)
			(xy 16.714918 -58.259159) (xy 16.816315 -58.359131) (xy 16.871434 -58.42) (xy 40.838131 -58.42) (xy 40.842106 -58.309941)
			(xy 40.854014 -58.200455) (xy 40.87379 -58.092114) (xy 40.901333 -57.985483) (xy 40.936498 -57.881117)
			(xy 40.979102 -57.77956) (xy 41.028923 -57.681343) (xy 41.085702 -57.586976) (xy 41.149141 -57.496952)
			(xy 41.218912 -57.411741) (xy 41.294649 -57.331786) (xy 41.375958 -57.257505) (xy 41.462415 -57.189285)
			(xy 41.553569 -57.12748) (xy 41.648946 -57.072415) (xy 41.748047 -57.024375) (xy 41.850356 -56.983611)
			(xy 41.95534 -56.950336) (xy 42.062451 -56.924723) (xy 42.171131 -56.906906) (xy 42.280814 -56.896977)
			(xy 42.390927 -56.894989) (xy 42.500897 -56.900951) (xy 42.61015 -56.914833) (xy 42.718116 -56.936563)
			(xy 42.824233 -56.966026) (xy 42.927947 -57.003069) (xy 43.028718 -57.0475) (xy 43.12602 -57.099087)
			(xy 43.219346 -57.157559) (xy 43.308209 -57.222614) (xy 43.392147 -57.293912) (xy 43.470722 -57.37108)
			(xy 43.543523 -57.453717) (xy 43.610171 -57.541391) (xy 43.67032 -57.633647) (xy 43.723654 -57.730002)
			(xy 43.769897 -57.829954) (xy 43.808807 -57.932982) (xy 43.840181 -58.03855) (xy 43.863856 -58.146106)
			(xy 43.879708 -58.25509) (xy 43.887655 -58.364934) (xy 43.888152 -58.42) (xy 60.396131 -58.42) (xy 60.400106 -58.309941)
			(xy 60.412014 -58.200455) (xy 60.43179 -58.092114) (xy 60.459333 -57.985483) (xy 60.494498 -57.881117)
			(xy 60.537102 -57.77956) (xy 60.586923 -57.681343) (xy 60.643702 -57.586976) (xy 60.707141 -57.496952)
			(xy 60.776912 -57.411741) (xy 60.852649 -57.331786) (xy 60.933958 -57.257505) (xy 61.020415 -57.189285)
			(xy 61.111569 -57.12748) (xy 61.206946 -57.072415) (xy 61.306047 -57.024375) (xy 61.408356 -56.983611)
			(xy 61.51334 -56.950336) (xy 61.620451 -56.924723) (xy 61.729131 -56.906906) (xy 61.838814 -56.896977)
			(xy 61.948927 -56.894989) (xy 62.058897 -56.900951) (xy 62.16815 -56.914833) (xy 62.276116 -56.936563)
			(xy 62.382233 -56.966026) (xy 62.485947 -57.003069) (xy 62.586718 -57.0475) (xy 62.68402 -57.099087)
			(xy 62.777346 -57.157559) (xy 62.866209 -57.222614) (xy 62.950147 -57.293912) (xy 63.028722 -57.37108)
			(xy 63.101523 -57.453717) (xy 63.168171 -57.541391) (xy 63.22832 -57.633647) (xy 63.281654 -57.730002)
			(xy 63.327897 -57.829954) (xy 63.366807 -57.932982) (xy 63.398181 -58.03855) (xy 63.421856 -58.146106)
			(xy 63.437708 -58.25509) (xy 63.445655 -58.364934) (xy 63.446152 -58.42) (xy 63.445655 -58.475066)
			(xy 63.437708 -58.58491) (xy 63.421856 -58.693894) (xy 63.398181 -58.80145) (xy 63.366807 -58.907018)
			(xy 63.327897 -59.010046) (xy 63.281654 -59.109998) (xy 63.22832 -59.206353) (xy 63.168171 -59.298609)
			(xy 63.101523 -59.386283) (xy 63.028722 -59.46892) (xy 62.950147 -59.546088) (xy 62.866209 -59.617386)
			(xy 62.777346 -59.682441) (xy 62.68402 -59.740913) (xy 62.586718 -59.7925) (xy 62.485947 -59.836931)
			(xy 62.382233 -59.873974) (xy 62.276116 -59.903437) (xy 62.16815 -59.925167) (xy 62.058897 -59.939049)
			(xy 61.948927 -59.945011) (xy 61.838814 -59.943023) (xy 61.729131 -59.933094) (xy 61.620451 -59.915277)
			(xy 61.51334 -59.889664) (xy 61.408356 -59.856389) (xy 61.306047 -59.815625) (xy 61.206946 -59.767585)
			(xy 61.111569 -59.71252) (xy 61.020415 -59.650715) (xy 60.933958 -59.582495) (xy 60.852649 -59.508214)
			(xy 60.776912 -59.428259) (xy 60.707141 -59.343048) (xy 60.643702 -59.253024) (xy 60.586923 -59.158657)
			(xy 60.537102 -59.06044) (xy 60.494498 -58.958883) (xy 60.459333 -58.854517) (xy 60.43179 -58.747886)
			(xy 60.412014 -58.639545) (xy 60.400106 -58.530059) (xy 60.396131 -58.42) (xy 43.888152 -58.42) (xy 43.887655 -58.475066)
			(xy 43.879708 -58.58491) (xy 43.863856 -58.693894) (xy 43.840181 -58.80145) (xy 43.808807 -58.907018)
			(xy 43.769897 -59.010046) (xy 43.723654 -59.109998) (xy 43.67032 -59.206353) (xy 43.610171 -59.298609)
			(xy 43.543523 -59.386283) (xy 43.470722 -59.46892) (xy 43.392147 -59.546088) (xy 43.308209 -59.617386)
			(xy 43.219346 -59.682441) (xy 43.12602 -59.740913) (xy 43.028718 -59.7925) (xy 42.927947 -59.836931)
			(xy 42.824233 -59.873974) (xy 42.718116 -59.903437) (xy 42.61015 -59.925167) (xy 42.500897 -59.939049)
			(xy 42.390927 -59.945011) (xy 42.280814 -59.943023) (xy 42.171131 -59.933094) (xy 42.062451 -59.915277)
			(xy 41.95534 -59.889664) (xy 41.850356 -59.856389) (xy 41.748047 -59.815625) (xy 41.648946 -59.767585)
			(xy 41.553569 -59.71252) (xy 41.462415 -59.650715) (xy 41.375958 -59.582495) (xy 41.294649 -59.508214)
			(xy 41.218912 -59.428259) (xy 41.149141 -59.343048) (xy 41.085702 -59.253024) (xy 41.028923 -59.158657)
			(xy 40.979102 -59.06044) (xy 40.936498 -58.958883) (xy 40.901333 -58.854517) (xy 40.87379 -58.747886)
			(xy 40.854014 -58.639545) (xy 40.842106 -58.530059) (xy 40.838131 -58.42) (xy 16.871434 -58.42) (xy 16.911893 -58.464679)
			(xy 17.001347 -58.575465) (xy 17.084389 -58.691134) (xy 17.160755 -58.811317) (xy 17.230199 -58.935627)
			(xy 17.292499 -59.063668) (xy 17.347455 -59.195027) (xy 17.394892 -59.329286) (xy 17.434656 -59.466013)
			(xy 17.466622 -59.604771) (xy 17.490687 -59.745115) (xy 17.506773 -59.886596) (xy 17.514828 -60.02876)
			(xy 17.515332 -60.099956) (xy 17.514828 -60.171152) (xy 17.506773 -60.313316) (xy 17.490687 -60.454797)
			(xy 17.466622 -60.595141) (xy 17.434656 -60.733899) (xy 17.394892 -60.870626) (xy 17.347455 -61.004885)
			(xy 17.292499 -61.136244) (xy 17.230199 -61.264285) (xy 17.160755 -61.388595) (xy 17.084389 -61.508778)
			(xy 17.001347 -61.624447) (xy 16.911893 -61.735233) (xy 16.816315 -61.840781) (xy 16.714918 -61.940753)
			(xy 16.608028 -62.034828) (xy 16.495987 -62.122705) (xy 16.379154 -62.204103) (xy 16.257903 -62.27876)
			(xy 16.132622 -62.346438) (xy 16.055974 -62.3824) (xy 111.565944 -62.3824) (xy 111.565944 -62.381892)
			(xy 111.566546 -62.33556) (xy 111.576218 -62.243402) (xy 111.595414 -62.152748) (xy 111.623928 -62.064579)
			(xy 111.642144 -62.021974) (xy 111.645952 -62.012032) (xy 111.645952 -61.990768) (xy 111.642144 -61.980826)
			(xy 111.623902 -61.938162) (xy 111.595357 -61.849871) (xy 111.576163 -61.759086) (xy 111.566529 -61.666796)
			(xy 111.565944 -61.6204) (xy 111.566522 -61.574004) (xy 111.576168 -61.481716) (xy 111.595365 -61.390932)
			(xy 111.623905 -61.302639) (xy 111.642144 -61.259974) (xy 111.645952 -61.250032) (xy 111.645952 -61.228768)
			(xy 111.642144 -61.218826) (xy 111.623902 -61.176162) (xy 111.595357 -61.087871) (xy 111.576163 -60.997086)
			(xy 111.566529 -60.904796) (xy 111.565944 -60.8584) (xy 111.566522 -60.812004) (xy 111.576168 -60.719716)
			(xy 111.595365 -60.628932) (xy 111.623905 -60.540639) (xy 111.642144 -60.497974) (xy 111.645952 -60.488032)
			(xy 111.645952 -60.466768) (xy 111.642144 -60.456826) (xy 111.623902 -60.414162) (xy 111.595357 -60.325871)
			(xy 111.576163 -60.235086) (xy 111.566529 -60.142796) (xy 111.565944 -60.0964) (xy 111.566522 -60.050004)
			(xy 111.576168 -59.957716) (xy 111.595365 -59.866932) (xy 111.623905 -59.778639) (xy 111.642144 -59.735974)
			(xy 111.645952 -59.726032) (xy 111.645952 -59.704768) (xy 111.642144 -59.694826) (xy 111.623919 -59.652224)
			(xy 111.595403 -59.564056) (xy 111.576211 -59.4734) (xy 111.566552 -59.38124) (xy 111.565944 -59.334908)
			(xy 111.565944 -59.3344) (xy 111.566467 -59.293299) (xy 111.574051 -59.211447) (xy 111.589155 -59.130645)
			(xy 111.61165 -59.05158) (xy 111.641344 -58.974929) (xy 111.677983 -58.901344) (xy 111.721256 -58.831453)
			(xy 111.770792 -58.765854) (xy 111.82617 -58.705104) (xy 111.886917 -58.649723) (xy 111.952514 -58.600183)
			(xy 112.022402 -58.556907) (xy 112.095985 -58.520263) (xy 112.172635 -58.490565) (xy 112.251698 -58.468066)
			(xy 112.3325 -58.452958) (xy 112.414351 -58.445369) (xy 112.455452 -58.444892) (xy 112.45596 -58.444892)
			(xy 112.502291 -58.445515) (xy 112.594449 -58.455181) (xy 112.685103 -58.474372) (xy 112.773272 -58.502879)
			(xy 112.815878 -58.521092) (xy 112.82582 -58.524898) (xy 112.847084 -58.524898) (xy 112.857026 -58.521092)
			(xy 112.899695 -58.502863) (xy 112.987985 -58.474315) (xy 113.078768 -58.455117) (xy 113.171056 -58.445479)
			(xy 113.217452 -58.444892) (xy 113.263847 -58.445492) (xy 113.356135 -58.455132) (xy 113.446919 -58.474323)
			(xy 113.535213 -58.502856) (xy 113.577878 -58.521092) (xy 113.58782 -58.524898) (xy 113.609084 -58.524898)
			(xy 113.619026 -58.521092) (xy 113.661695 -58.502863) (xy 113.749985 -58.474315) (xy 113.840768 -58.455117)
			(xy 113.933056 -58.445479) (xy 113.979452 -58.444892) (xy 114.025847 -58.445492) (xy 114.118135 -58.455132)
			(xy 114.208919 -58.474323) (xy 114.297213 -58.502856) (xy 114.339878 -58.521092) (xy 114.34982 -58.524898)
			(xy 114.371084 -58.524898) (xy 114.381026 -58.521092) (xy 114.423695 -58.502863) (xy 114.511985 -58.474315)
			(xy 114.602768 -58.455117) (xy 114.695056 -58.445479) (xy 114.741452 -58.444892) (xy 114.787847 -58.445492)
			(xy 114.880135 -58.455132) (xy 114.970919 -58.474323) (xy 115.059213 -58.502856) (xy 115.101878 -58.521092)
			(xy 115.11182 -58.524898) (xy 115.133084 -58.524898) (xy 115.143026 -58.521092) (xy 115.185635 -58.502886)
			(xy 115.2738 -58.474364) (xy 115.364454 -58.455167) (xy 115.456612 -58.445503) (xy 115.502944 -58.444892)
			(xy 115.503452 -58.444892) (xy 115.544554 -58.445398) (xy 115.626409 -58.452979) (xy 115.707215 -58.46808)
			(xy 115.786282 -58.490573) (xy 115.862937 -58.520265) (xy 115.936525 -58.556904) (xy 116.006418 -58.600177)
			(xy 116.072021 -58.649714) (xy 116.132772 -58.705094) (xy 116.188155 -58.765842) (xy 116.237696 -58.831442)
			(xy 116.280972 -58.901333) (xy 116.317615 -58.974919) (xy 116.347312 -59.051572) (xy 116.369809 -59.130639)
			(xy 116.384915 -59.211444) (xy 116.3925 -59.293298) (xy 116.39296 -59.3344) (xy 116.39296 -59.334908)
			(xy 116.392358 -59.38124) (xy 116.382686 -59.473398) (xy 116.363489 -59.564052) (xy 116.334976 -59.652221)
			(xy 116.31676 -59.694826) (xy 116.312952 -59.704768) (xy 116.312952 -59.726032) (xy 116.31676 -59.735974)
			(xy 116.335002 -59.778637) (xy 116.363547 -59.866929) (xy 116.382741 -59.957714) (xy 116.392375 -60.050004)
			(xy 116.39296 -60.0964) (xy 116.392381 -60.142796) (xy 116.382736 -60.235084) (xy 116.363539 -60.325868)
			(xy 116.334999 -60.414161) (xy 116.31676 -60.456826) (xy 116.312952 -60.466768) (xy 116.312952 -60.488032)
			(xy 116.31676 -60.497974) (xy 116.335002 -60.540637) (xy 116.363547 -60.628929) (xy 116.382741 -60.719714)
			(xy 116.392375 -60.812004) (xy 116.39296 -60.8584) (xy 116.392381 -60.904796) (xy 116.382736 -60.997084)
			(xy 116.363539 -61.087868) (xy 116.334999 -61.176161) (xy 116.31676 -61.218826) (xy 116.312952 -61.228768)
			(xy 116.312952 -61.250032) (xy 116.31676 -61.259974) (xy 116.335002 -61.302637) (xy 116.363547 -61.390929)
			(xy 116.382741 -61.481714) (xy 116.392375 -61.574004) (xy 116.39296 -61.6204) (xy 116.392381 -61.666796)
			(xy 116.382736 -61.759084) (xy 116.363539 -61.849868) (xy 116.334999 -61.938161) (xy 116.31676 -61.980826)
			(xy 116.312952 -61.990768) (xy 116.312952 -62.012032) (xy 116.31676 -62.021974) (xy 116.334985 -62.064576)
			(xy 116.363501 -62.152744) (xy 116.382693 -62.243399) (xy 116.392352 -62.33556) (xy 116.39296 -62.381892)
			(xy 116.39296 -62.3824) (xy 116.392548 -62.423505) (xy 116.384962 -62.505363) (xy 116.369856 -62.586172)
			(xy 116.347357 -62.665243) (xy 116.317659 -62.7419) (xy 116.281014 -62.81549) (xy 116.237735 -62.885385)
			(xy 116.188192 -62.950988) (xy 116.132806 -63.01174) (xy 116.072051 -63.067122) (xy 116.006446 -63.116662)
			(xy 115.936548 -63.159938) (xy 115.862956 -63.196579) (xy 115.786297 -63.226273) (xy 115.707226 -63.248767)
			(xy 115.626415 -63.263869) (xy 115.544557 -63.27145) (xy 115.503452 -63.271908) (xy 115.502944 -63.271908)
			(xy 115.456613 -63.271284) (xy 115.364455 -63.261618) (xy 115.273801 -63.242427) (xy 115.185632 -63.213921)
			(xy 115.143026 -63.195708) (xy 115.133084 -63.191902) (xy 115.11182 -63.191902) (xy 115.101878 -63.195708)
			(xy 115.059209 -63.213936) (xy 114.970919 -63.242484) (xy 114.880136 -63.261682) (xy 114.787847 -63.27132)
			(xy 114.741452 -63.271908) (xy 114.695057 -63.271307) (xy 114.602769 -63.261667) (xy 114.511985 -63.242476)
			(xy 114.423691 -63.213943) (xy 114.381026 -63.195708) (xy 114.371084 -63.191902) (xy 114.34982 -63.191902)
			(xy 114.339878 -63.195708) (xy 114.297209 -63.213936) (xy 114.208919 -63.242484) (xy 114.118136 -63.261682)
			(xy 114.025847 -63.27132) (xy 113.979452 -63.271908) (xy 113.933057 -63.271307) (xy 113.840769 -63.261667)
			(xy 113.749985 -63.242476) (xy 113.661691 -63.213943) (xy 113.619026 -63.195708) (xy 113.609084 -63.191902)
			(xy 113.58782 -63.191902) (xy 113.577878 -63.195708) (xy 113.535209 -63.213936) (xy 113.446919 -63.242484)
			(xy 113.356136 -63.261682) (xy 113.263847 -63.27132) (xy 113.217452 -63.271908) (xy 113.171057 -63.271307)
			(xy 113.078769 -63.261667) (xy 112.987985 -63.242476) (xy 112.899691 -63.213943) (xy 112.857026 -63.195708)
			(xy 112.847084 -63.191902) (xy 112.82582 -63.191902) (xy 112.815878 -63.195708) (xy 112.773268 -63.213913)
			(xy 112.685103 -63.242435) (xy 112.59445 -63.261633) (xy 112.502292 -63.271297) (xy 112.45596 -63.271908)
			(xy 112.455452 -63.271908) (xy 112.414349 -63.271479) (xy 112.332493 -63.26389) (xy 112.251687 -63.248781)
			(xy 112.17262 -63.22628) (xy 112.095965 -63.196581) (xy 112.022379 -63.159935) (xy 111.952487 -63.116657)
			(xy 111.886886 -63.067114) (xy 111.826136 -63.01173) (xy 111.770755 -62.950977) (xy 111.721216 -62.885374)
			(xy 111.677941 -62.815479) (xy 111.6413 -62.741891) (xy 111.611604 -62.665235) (xy 111.589108 -62.586166)
			(xy 111.574003 -62.505359) (xy 111.566419 -62.423503) (xy 111.565944 -62.3824) (xy 16.055974 -62.3824)
			(xy 16.003713 -62.40692) (xy 15.871589 -62.460011) (xy 15.736673 -62.505543) (xy 15.599397 -62.543369)
			(xy 15.4602 -62.573369) (xy 15.31953 -62.595445) (xy 15.177836 -62.609527) (xy 15.035572 -62.61557)
			(xy 14.893194 -62.613555) (xy 14.751158 -62.603488) (xy 14.609919 -62.585402) (xy 14.469929 -62.559354)
			(xy 14.331638 -62.525428) (xy 14.195487 -62.483732) (xy 14.061913 -62.4344) (xy 13.931344 -62.377591)
			(xy 13.804198 -62.313485) (xy 13.680883 -62.242289) (xy 13.561793 -62.164231) (xy 13.44731 -62.079559)
			(xy 13.337801 -61.988547) (xy 13.233616 -61.891485) (xy 13.135089 -61.788684) (xy 13.042536 -61.680473)
			(xy 12.956254 -61.5672) (xy 12.876517 -61.449227) (xy 12.803583 -61.326931) (xy 12.737685 -61.200705)
			(xy 12.679034 -61.070953) (xy 12.627817 -60.938091) (xy 12.584199 -60.802544) (xy 12.548319 -60.664746)
			(xy 12.520292 -60.525139) (xy 12.500209 -60.384171) (xy 12.488134 -60.242291) (xy 12.484104 -60.099956)
			(xy 0.509016 -60.099956) (xy 0.509016 -67.428561) (xy 111.362994 -67.428561) (xy 111.362994 -67.343839)
			(xy 111.371047 -67.259502) (xy 111.387081 -67.176312) (xy 111.410949 -67.095022) (xy 111.442437 -67.01637)
			(xy 111.481259 -66.941067) (xy 111.527062 -66.869795) (xy 111.579433 -66.803199) (xy 111.637898 -66.741884)
			(xy 111.701926 -66.686403) (xy 111.770938 -66.63726) (xy 111.844308 -66.5949) (xy 111.921373 -66.559705)
			(xy 112.001435 -66.531996) (xy 112.083768 -66.512022) (xy 112.167627 -66.499965) (xy 112.252252 -66.495934)
			(xy 112.336877 -66.499965) (xy 112.420736 -66.512022) (xy 112.503069 -66.531996) (xy 112.583131 -66.559705)
			(xy 112.660196 -66.5949) (xy 112.733566 -66.63726) (xy 112.802578 -66.686403) (xy 112.866606 -66.741884)
			(xy 112.925071 -66.803199) (xy 112.977442 -66.869795) (xy 113.023245 -66.941067) (xy 113.062067 -67.01637)
			(xy 113.093555 -67.095022) (xy 113.117423 -67.176312) (xy 113.133457 -67.259502) (xy 113.14151 -67.343839)
			(xy 113.142014 -67.3862) (xy 113.14151 -67.428561) (xy 113.133457 -67.512898) (xy 113.117423 -67.596088)
			(xy 113.093555 -67.677378) (xy 113.062067 -67.75603) (xy 113.023245 -67.831333) (xy 112.977442 -67.902605)
			(xy 112.925071 -67.969201) (xy 112.866606 -68.030516) (xy 112.802578 -68.085997) (xy 112.733566 -68.13514)
			(xy 112.660196 -68.1775) (xy 112.583131 -68.212695) (xy 112.503069 -68.240404) (xy 112.420736 -68.260378)
			(xy 112.336877 -68.272435) (xy 112.252252 -68.276467) (xy 112.167627 -68.272435) (xy 112.083768 -68.260378)
			(xy 112.001435 -68.240404) (xy 111.921373 -68.212695) (xy 111.844308 -68.1775) (xy 111.770938 -68.13514)
			(xy 111.701926 -68.085997) (xy 111.637898 -68.030516) (xy 111.579433 -67.969201) (xy 111.527062 -67.902605)
			(xy 111.481259 -67.831333) (xy 111.442437 -67.75603) (xy 111.410949 -67.677378) (xy 111.387081 -67.596088)
			(xy 111.371047 -67.512898) (xy 111.362994 -67.428561) (xy 0.509016 -67.428561) (xy 0.509016 -71.239888)
			(xy 41.345622 -71.239888) (xy 41.349604 -71.149938) (xy 41.361521 -71.060691) (xy 41.381279 -70.972847)
			(xy 41.408723 -70.887093) (xy 41.443639 -70.8041) (xy 41.485753 -70.724518) (xy 41.534736 -70.648969)
			(xy 41.590204 -70.578045) (xy 41.651724 -70.5123) (xy 41.718813 -70.45225) (xy 41.790947 -70.398365)
			(xy 41.867561 -70.351065) (xy 41.948055 -70.310722) (xy 42.0318 -70.27765) (xy 42.118141 -70.25211)
			(xy 42.2064 -70.2343) (xy 42.295889 -70.22436) (xy 42.385905 -70.222369) (xy 42.475746 -70.22834)
			(xy 42.564707 -70.242229) (xy 42.652092 -70.263925) (xy 42.737218 -70.29326) (xy 42.819418 -70.330003)
			(xy 42.898049 -70.373867) (xy 42.972496 -70.424509) (xy 43.042176 -70.481533) (xy 43.106543 -70.544492)
			(xy 43.165094 -70.612893) (xy 43.217371 -70.686201) (xy 43.262964 -70.763843) (xy 43.301517 -70.84521)
			(xy 43.332728 -70.929666) (xy 43.356352 -71.01655) (xy 43.372205 -71.105182) (xy 43.380162 -71.194869)
			(xy 43.38066 -71.239888) (xy 60.903622 -71.239888) (xy 60.907604 -71.149938) (xy 60.919521 -71.060691)
			(xy 60.939279 -70.972847) (xy 60.966723 -70.887093) (xy 61.001639 -70.8041) (xy 61.043753 -70.724518)
			(xy 61.092736 -70.648969) (xy 61.148204 -70.578045) (xy 61.209724 -70.5123) (xy 61.276813 -70.45225)
			(xy 61.348947 -70.398365) (xy 61.425561 -70.351065) (xy 61.506055 -70.310722) (xy 61.5898 -70.27765)
			(xy 61.676141 -70.25211) (xy 61.7644 -70.2343) (xy 61.853889 -70.22436) (xy 61.943905 -70.222369)
			(xy 62.033746 -70.22834) (xy 62.122707 -70.242229) (xy 62.210092 -70.263925) (xy 62.295218 -70.29326)
			(xy 62.377418 -70.330003) (xy 62.456049 -70.373867) (xy 62.530496 -70.424509) (xy 62.600176 -70.481533)
			(xy 62.664543 -70.544492) (xy 62.723094 -70.612893) (xy 62.775371 -70.686201) (xy 62.820964 -70.763843)
			(xy 62.859517 -70.84521) (xy 62.890728 -70.929666) (xy 62.914352 -71.01655) (xy 62.930205 -71.105182)
			(xy 62.938162 -71.194869) (xy 62.93866 -71.239888) (xy 62.938162 -71.284907) (xy 62.930205 -71.374594)
			(xy 62.914352 -71.463226) (xy 62.890728 -71.55011) (xy 62.859517 -71.634566) (xy 62.820964 -71.715933)
			(xy 62.775371 -71.793575) (xy 62.723094 -71.866883) (xy 62.664543 -71.935284) (xy 62.600176 -71.998243)
			(xy 62.530496 -72.055267) (xy 62.456049 -72.105909) (xy 62.377418 -72.149773) (xy 62.295218 -72.186516)
			(xy 62.210092 -72.215851) (xy 62.122707 -72.237547) (xy 62.033746 -72.251436) (xy 61.943905 -72.257407)
			(xy 61.853889 -72.255416) (xy 61.7644 -72.245476) (xy 61.676141 -72.227666) (xy 61.5898 -72.202126)
			(xy 61.506055 -72.169054) (xy 61.425561 -72.128711) (xy 61.348947 -72.081411) (xy 61.276813 -72.027526)
			(xy 61.209724 -71.967476) (xy 61.148204 -71.901731) (xy 61.092736 -71.830807) (xy 61.043753 -71.755258)
			(xy 61.001639 -71.675676) (xy 60.966723 -71.592683) (xy 60.939279 -71.506929) (xy 60.919521 -71.419085)
			(xy 60.907604 -71.329838) (xy 60.903622 -71.239888) (xy 43.38066 -71.239888) (xy 43.380162 -71.284907)
			(xy 43.372205 -71.374594) (xy 43.356352 -71.463226) (xy 43.332728 -71.55011) (xy 43.301517 -71.634566)
			(xy 43.262964 -71.715933) (xy 43.217371 -71.793575) (xy 43.165094 -71.866883) (xy 43.106543 -71.935284)
			(xy 43.042176 -71.998243) (xy 42.972496 -72.055267) (xy 42.898049 -72.105909) (xy 42.819418 -72.149773)
			(xy 42.737218 -72.186516) (xy 42.652092 -72.215851) (xy 42.564707 -72.237547) (xy 42.475746 -72.251436)
			(xy 42.385905 -72.257407) (xy 42.295889 -72.255416) (xy 42.2064 -72.245476) (xy 42.118141 -72.227666)
			(xy 42.0318 -72.202126) (xy 41.948055 -72.169054) (xy 41.867561 -72.128711) (xy 41.790947 -72.081411)
			(xy 41.718813 -72.027526) (xy 41.651724 -71.967476) (xy 41.590204 -71.901731) (xy 41.534736 -71.830807)
			(xy 41.485753 -71.755258) (xy 41.443639 -71.675676) (xy 41.408723 -71.592683) (xy 41.381279 -71.506929)
			(xy 41.361521 -71.419085) (xy 41.349604 -71.329838) (xy 41.345622 -71.239888) (xy 0.509016 -71.239888)
			(xy 0.509016 -73.66) (xy 111.565944 -73.66) (xy 111.565944 -73.659492) (xy 111.566546 -73.61316)
			(xy 111.576218 -73.521002) (xy 111.595414 -73.430348) (xy 111.623928 -73.342179) (xy 111.642144 -73.299574)
			(xy 111.645952 -73.289632) (xy 111.645952 -73.268368) (xy 111.642144 -73.258426) (xy 111.623902 -73.215762)
			(xy 111.595357 -73.127471) (xy 111.576163 -73.036686) (xy 111.566529 -72.944396) (xy 111.565944 -72.898)
			(xy 111.566522 -72.851604) (xy 111.576168 -72.759316) (xy 111.595365 -72.668532) (xy 111.623905 -72.580239)
			(xy 111.642144 -72.537574) (xy 111.645952 -72.527632) (xy 111.645952 -72.506368) (xy 111.642144 -72.496426)
			(xy 111.623902 -72.453762) (xy 111.595357 -72.365471) (xy 111.576163 -72.274686) (xy 111.566529 -72.182396)
			(xy 111.565944 -72.136) (xy 111.566522 -72.089604) (xy 111.576168 -71.997316) (xy 111.595365 -71.906532)
			(xy 111.623905 -71.818239) (xy 111.642144 -71.775574) (xy 111.645952 -71.765632) (xy 111.645952 -71.744368)
			(xy 111.642144 -71.734426) (xy 111.623902 -71.691762) (xy 111.595357 -71.603471) (xy 111.576163 -71.512686)
			(xy 111.566529 -71.420396) (xy 111.565944 -71.374) (xy 111.566522 -71.327604) (xy 111.576168 -71.235316)
			(xy 111.595365 -71.144532) (xy 111.623905 -71.056239) (xy 111.642144 -71.013574) (xy 111.645952 -71.003632)
			(xy 111.645952 -70.982368) (xy 111.642144 -70.972426) (xy 111.623919 -70.929824) (xy 111.595403 -70.841656)
			(xy 111.576211 -70.751) (xy 111.566552 -70.65884) (xy 111.565944 -70.612508) (xy 111.565944 -70.612)
			(xy 111.566467 -70.570899) (xy 111.574051 -70.489047) (xy 111.589155 -70.408245) (xy 111.61165 -70.32918)
			(xy 111.641344 -70.252529) (xy 111.677983 -70.178944) (xy 111.721256 -70.109053) (xy 111.770792 -70.043454)
			(xy 111.82617 -69.982704) (xy 111.886917 -69.927323) (xy 111.952514 -69.877783) (xy 112.022402 -69.834507)
			(xy 112.095985 -69.797863) (xy 112.172635 -69.768165) (xy 112.251698 -69.745666) (xy 112.3325 -69.730558)
			(xy 112.414351 -69.722969) (xy 112.455452 -69.722492) (xy 112.45596 -69.722492) (xy 112.502291 -69.723115)
			(xy 112.594449 -69.732781) (xy 112.685103 -69.751972) (xy 112.773272 -69.780479) (xy 112.815878 -69.798692)
			(xy 112.82582 -69.802498) (xy 112.847084 -69.802498) (xy 112.857026 -69.798692) (xy 112.899695 -69.780463)
			(xy 112.987985 -69.751915) (xy 113.078768 -69.732717) (xy 113.171056 -69.723079) (xy 113.217452 -69.722492)
			(xy 113.263847 -69.723092) (xy 113.356135 -69.732732) (xy 113.446919 -69.751923) (xy 113.535213 -69.780456)
			(xy 113.577878 -69.798692) (xy 113.58782 -69.802498) (xy 113.609084 -69.802498) (xy 113.619026 -69.798692)
			(xy 113.661695 -69.780463) (xy 113.749985 -69.751915) (xy 113.840768 -69.732717) (xy 113.933056 -69.723079)
			(xy 113.979452 -69.722492) (xy 114.025847 -69.723092) (xy 114.118135 -69.732732) (xy 114.208919 -69.751923)
			(xy 114.297213 -69.780456) (xy 114.339878 -69.798692) (xy 114.34982 -69.802498) (xy 114.371084 -69.802498)
			(xy 114.381026 -69.798692) (xy 114.423695 -69.780463) (xy 114.511985 -69.751915) (xy 114.602768 -69.732717)
			(xy 114.695056 -69.723079) (xy 114.741452 -69.722492) (xy 114.787847 -69.723092) (xy 114.880135 -69.732732)
			(xy 114.970919 -69.751923) (xy 115.059213 -69.780456) (xy 115.101878 -69.798692) (xy 115.11182 -69.802498)
			(xy 115.133084 -69.802498) (xy 115.143026 -69.798692) (xy 115.185635 -69.780486) (xy 115.2738 -69.751964)
			(xy 115.364454 -69.732767) (xy 115.456612 -69.723103) (xy 115.502944 -69.722492) (xy 115.503452 -69.722492)
			(xy 115.544554 -69.722998) (xy 115.626409 -69.730579) (xy 115.707215 -69.74568) (xy 115.786282 -69.768173)
			(xy 115.862937 -69.797865) (xy 115.936525 -69.834504) (xy 116.006418 -69.877777) (xy 116.072021 -69.927314)
			(xy 116.132772 -69.982694) (xy 116.188155 -70.043442) (xy 116.237696 -70.109042) (xy 116.280972 -70.178933)
			(xy 116.317615 -70.252519) (xy 116.347312 -70.329172) (xy 116.369809 -70.408239) (xy 116.384915 -70.489044)
			(xy 116.3925 -70.570898) (xy 116.39296 -70.612) (xy 116.39296 -70.612508) (xy 116.392358 -70.65884)
			(xy 116.382686 -70.750998) (xy 116.363489 -70.841652) (xy 116.334976 -70.929821) (xy 116.31676 -70.972426)
			(xy 116.312952 -70.982368) (xy 116.312952 -71.003632) (xy 116.31676 -71.013574) (xy 116.335002 -71.056237)
			(xy 116.363547 -71.144529) (xy 116.382741 -71.235314) (xy 116.392375 -71.327604) (xy 116.39296 -71.374)
			(xy 116.392381 -71.420396) (xy 116.382736 -71.512684) (xy 116.363539 -71.603468) (xy 116.334999 -71.691761)
			(xy 116.31676 -71.734426) (xy 116.312952 -71.744368) (xy 116.312952 -71.765632) (xy 116.31676 -71.775574)
			(xy 116.335002 -71.818237) (xy 116.363547 -71.906529) (xy 116.382741 -71.997314) (xy 116.392375 -72.089604)
			(xy 116.39296 -72.136) (xy 116.392381 -72.182396) (xy 116.382736 -72.274684) (xy 116.363539 -72.365468)
			(xy 116.334999 -72.453761) (xy 116.31676 -72.496426) (xy 116.312952 -72.506368) (xy 116.312952 -72.527632)
			(xy 116.31676 -72.537574) (xy 116.335002 -72.580237) (xy 116.363547 -72.668529) (xy 116.382741 -72.759314)
			(xy 116.392375 -72.851604) (xy 116.39296 -72.898) (xy 116.392381 -72.944396) (xy 116.382736 -73.036684)
			(xy 116.363539 -73.127468) (xy 116.334999 -73.215761) (xy 116.31676 -73.258426) (xy 116.312952 -73.268368)
			(xy 116.312952 -73.289632) (xy 116.31676 -73.299574) (xy 116.334985 -73.342176) (xy 116.363501 -73.430344)
			(xy 116.382693 -73.520999) (xy 116.392352 -73.61316) (xy 116.39296 -73.659492) (xy 116.39296 -73.66)
			(xy 116.392548 -73.701105) (xy 116.384962 -73.782963) (xy 116.369856 -73.863772) (xy 116.347357 -73.942843)
			(xy 116.317659 -74.0195) (xy 116.281014 -74.09309) (xy 116.237735 -74.162985) (xy 116.188192 -74.228588)
			(xy 116.132806 -74.28934) (xy 116.072051 -74.344722) (xy 116.006446 -74.394262) (xy 115.936548 -74.437538)
			(xy 115.862956 -74.474179) (xy 115.786297 -74.503873) (xy 115.707226 -74.526367) (xy 115.626415 -74.541469)
			(xy 115.544557 -74.54905) (xy 115.503452 -74.549508) (xy 115.502944 -74.549508) (xy 115.456613 -74.548884)
			(xy 115.364455 -74.539218) (xy 115.273801 -74.520027) (xy 115.185632 -74.491521) (xy 115.143026 -74.473308)
			(xy 115.133084 -74.469502) (xy 115.11182 -74.469502) (xy 115.101878 -74.473308) (xy 115.059209 -74.491536)
			(xy 114.970919 -74.520084) (xy 114.880136 -74.539282) (xy 114.787847 -74.54892) (xy 114.741452 -74.549508)
			(xy 114.695057 -74.548907) (xy 114.602769 -74.539267) (xy 114.511985 -74.520076) (xy 114.423691 -74.491543)
			(xy 114.381026 -74.473308) (xy 114.371084 -74.469502) (xy 114.34982 -74.469502) (xy 114.339878 -74.473308)
			(xy 114.297209 -74.491536) (xy 114.208919 -74.520084) (xy 114.118136 -74.539282) (xy 114.025847 -74.54892)
			(xy 113.979452 -74.549508) (xy 113.933057 -74.548907) (xy 113.840769 -74.539267) (xy 113.749985 -74.520076)
			(xy 113.661691 -74.491543) (xy 113.619026 -74.473308) (xy 113.609084 -74.469502) (xy 113.58782 -74.469502)
			(xy 113.577878 -74.473308) (xy 113.535209 -74.491536) (xy 113.446919 -74.520084) (xy 113.356136 -74.539282)
			(xy 113.263847 -74.54892) (xy 113.217452 -74.549508) (xy 113.171057 -74.548907) (xy 113.078769 -74.539267)
			(xy 112.987985 -74.520076) (xy 112.899691 -74.491543) (xy 112.857026 -74.473308) (xy 112.847084 -74.469502)
			(xy 112.82582 -74.469502) (xy 112.815878 -74.473308) (xy 112.773268 -74.491513) (xy 112.685103 -74.520035)
			(xy 112.59445 -74.539233) (xy 112.502292 -74.548897) (xy 112.45596 -74.549508) (xy 112.455452 -74.549508)
			(xy 112.414349 -74.549079) (xy 112.332493 -74.54149) (xy 112.251687 -74.526381) (xy 112.17262 -74.50388)
			(xy 112.095965 -74.474181) (xy 112.022379 -74.437535) (xy 111.952487 -74.394257) (xy 111.886886 -74.344714)
			(xy 111.826136 -74.28933) (xy 111.770755 -74.228577) (xy 111.721216 -74.162974) (xy 111.677941 -74.093079)
			(xy 111.6413 -74.019491) (xy 111.611604 -73.942835) (xy 111.589108 -73.863766) (xy 111.574003 -73.782959)
			(xy 111.566419 -73.701103) (xy 111.565944 -73.66) (xy 0.509016 -73.66) (xy 0.509016 -78.74) (xy 40.838131 -78.74)
			(xy 40.842106 -78.629941) (xy 40.854014 -78.520455) (xy 40.87379 -78.412114) (xy 40.901333 -78.305483)
			(xy 40.936498 -78.201117) (xy 40.979102 -78.09956) (xy 41.028923 -78.001343) (xy 41.085702 -77.906976)
			(xy 41.149141 -77.816952) (xy 41.218912 -77.731741) (xy 41.294649 -77.651786) (xy 41.375958 -77.577505)
			(xy 41.462415 -77.509285) (xy 41.553569 -77.44748) (xy 41.648946 -77.392415) (xy 41.748047 -77.344375)
			(xy 41.850356 -77.303611) (xy 41.95534 -77.270336) (xy 42.062451 -77.244723) (xy 42.171131 -77.226906)
			(xy 42.280814 -77.216977) (xy 42.390927 -77.214989) (xy 42.500897 -77.220951) (xy 42.61015 -77.234833)
			(xy 42.718116 -77.256563) (xy 42.824233 -77.286026) (xy 42.927947 -77.323069) (xy 43.028718 -77.3675)
			(xy 43.12602 -77.419087) (xy 43.219346 -77.477559) (xy 43.308209 -77.542614) (xy 43.392147 -77.613912)
			(xy 43.470722 -77.69108) (xy 43.543523 -77.773717) (xy 43.610171 -77.861391) (xy 43.67032 -77.953647)
			(xy 43.723654 -78.050002) (xy 43.769897 -78.149954) (xy 43.808807 -78.252982) (xy 43.840181 -78.35855)
			(xy 43.863856 -78.466106) (xy 43.879708 -78.57509) (xy 43.887655 -78.684934) (xy 43.888152 -78.74)
			(xy 60.396131 -78.74) (xy 60.400106 -78.629941) (xy 60.412014 -78.520455) (xy 60.43179 -78.412114)
			(xy 60.459333 -78.305483) (xy 60.494498 -78.201117) (xy 60.537102 -78.09956) (xy 60.586923 -78.001343)
			(xy 60.643702 -77.906976) (xy 60.707141 -77.816952) (xy 60.776912 -77.731741) (xy 60.852649 -77.651786)
			(xy 60.933958 -77.577505) (xy 61.020415 -77.509285) (xy 61.111569 -77.44748) (xy 61.206946 -77.392415)
			(xy 61.306047 -77.344375) (xy 61.408356 -77.303611) (xy 61.51334 -77.270336) (xy 61.620451 -77.244723)
			(xy 61.729131 -77.226906) (xy 61.838814 -77.216977) (xy 61.948927 -77.214989) (xy 62.058897 -77.220951)
			(xy 62.16815 -77.234833) (xy 62.276116 -77.256563) (xy 62.382233 -77.286026) (xy 62.485947 -77.323069)
			(xy 62.586718 -77.3675) (xy 62.68402 -77.419087) (xy 62.777346 -77.477559) (xy 62.866209 -77.542614)
			(xy 62.950147 -77.613912) (xy 63.028722 -77.69108) (xy 63.101523 -77.773717) (xy 63.168171 -77.861391)
			(xy 63.22832 -77.953647) (xy 63.281654 -78.050002) (xy 63.327897 -78.149954) (xy 63.366807 -78.252982)
			(xy 63.398181 -78.35855) (xy 63.421856 -78.466106) (xy 63.437708 -78.57509) (xy 63.445655 -78.684934)
			(xy 63.445847 -78.706161) (xy 111.362994 -78.706161) (xy 111.362994 -78.621439) (xy 111.371047 -78.537102)
			(xy 111.387081 -78.453912) (xy 111.410949 -78.372622) (xy 111.442437 -78.29397) (xy 111.481259 -78.218667)
			(xy 111.527062 -78.147395) (xy 111.579433 -78.080799) (xy 111.637898 -78.019484) (xy 111.701926 -77.964003)
			(xy 111.770938 -77.91486) (xy 111.844308 -77.8725) (xy 111.921373 -77.837305) (xy 112.001435 -77.809596)
			(xy 112.083768 -77.789622) (xy 112.167627 -77.777565) (xy 112.252252 -77.773534) (xy 112.336877 -77.777565)
			(xy 112.420736 -77.789622) (xy 112.503069 -77.809596) (xy 112.583131 -77.837305) (xy 112.660196 -77.8725)
			(xy 112.733566 -77.91486) (xy 112.802578 -77.964003) (xy 112.866606 -78.019484) (xy 112.925071 -78.080799)
			(xy 112.977442 -78.147395) (xy 113.023245 -78.218667) (xy 113.062067 -78.29397) (xy 113.093555 -78.372622)
			(xy 113.117423 -78.453912) (xy 113.133457 -78.537102) (xy 113.14151 -78.621439) (xy 113.142014 -78.6638)
			(xy 113.14151 -78.706161) (xy 113.133457 -78.790498) (xy 113.117423 -78.873688) (xy 113.093555 -78.954978)
			(xy 113.062067 -79.03363) (xy 113.023245 -79.108933) (xy 112.977442 -79.180205) (xy 112.925071 -79.246801)
			(xy 112.866606 -79.308116) (xy 112.802578 -79.363597) (xy 112.733566 -79.41274) (xy 112.660196 -79.4551)
			(xy 112.583131 -79.490295) (xy 112.503069 -79.518004) (xy 112.420736 -79.537978) (xy 112.336877 -79.550035)
			(xy 112.252252 -79.554067) (xy 112.167627 -79.550035) (xy 112.083768 -79.537978) (xy 112.001435 -79.518004)
			(xy 111.921373 -79.490295) (xy 111.844308 -79.4551) (xy 111.770938 -79.41274) (xy 111.701926 -79.363597)
			(xy 111.637898 -79.308116) (xy 111.579433 -79.246801) (xy 111.527062 -79.180205) (xy 111.481259 -79.108933)
			(xy 111.442437 -79.03363) (xy 111.410949 -78.954978) (xy 111.387081 -78.873688) (xy 111.371047 -78.790498)
			(xy 111.362994 -78.706161) (xy 63.445847 -78.706161) (xy 63.446152 -78.74) (xy 63.445655 -78.795066)
			(xy 63.437708 -78.90491) (xy 63.421856 -79.013894) (xy 63.398181 -79.12145) (xy 63.366807 -79.227018)
			(xy 63.327897 -79.330046) (xy 63.281654 -79.429998) (xy 63.22832 -79.526353) (xy 63.168171 -79.618609)
			(xy 63.101523 -79.706283) (xy 63.028722 -79.78892) (xy 62.950147 -79.866088) (xy 62.930237 -79.883)
			(xy 122.3264 -79.883) (xy 122.3264 -13.081) (xy 122.326939 -13.047741) (xy 122.335625 -12.981791)
			(xy 122.352847 -12.91754) (xy 122.378311 -12.856089) (xy 122.411582 -12.798488) (xy 122.452088 -12.745724)
			(xy 122.475244 -12.721844) (xy 123.110244 -12.086844) (xy 123.134129 -12.063692) (xy 123.186889 -12.023179)
			(xy 123.244488 -11.989903) (xy 123.305939 -11.964434) (xy 123.37019 -11.947209) (xy 123.43614 -11.938521)
			(xy 123.4694 -11.938) (xy 156.980382 -11.938) (xy 157.013641 -11.938551) (xy 157.07959 -11.947234)
			(xy 157.143841 -11.964454) (xy 157.205292 -11.989916) (xy 157.262894 -12.023184) (xy 157.315658 -12.063689)
			(xy 157.339538 -12.086844) (xy 161.039556 -15.786862) (xy 161.062716 -15.810739) (xy 161.103229 -15.863501)
			(xy 161.136504 -15.921101) (xy 161.161971 -15.982554) (xy 161.179195 -16.046806) (xy 161.18788 -16.112758)
			(xy 161.1884 -16.146018) (xy 161.1884 -22.560114) (xy 205.177635 -22.560114) (xy 205.177635 -22.389758)
			(xy 205.18562 -22.21959) (xy 205.201572 -22.049983) (xy 205.225457 -21.881311) (xy 205.257221 -21.713943)
			(xy 205.296796 -21.548248) (xy 205.344093 -21.38459) (xy 205.39901 -21.223329) (xy 205.461425 -21.064819)
			(xy 205.531201 -20.909409) (xy 205.608184 -20.757441) (xy 205.692206 -20.609247) (xy 205.783082 -20.465155)
			(xy 205.880612 -20.325481) (xy 205.984582 -20.190532) (xy 206.094763 -20.060604) (xy 206.210912 -19.935984)
			(xy 206.332776 -19.816945) (xy 206.460084 -19.703749) (xy 206.592559 -19.596644) (xy 206.729909 -19.495867)
			(xy 206.871831 -19.401638) (xy 207.018013 -19.314165) (xy 207.168136 -19.23364) (xy 207.321867 -19.16024)
			(xy 207.47887 -19.094126) (xy 207.6388 -19.035444) (xy 207.801304 -18.984323) (xy 207.966025 -18.940875)
			(xy 208.132603 -18.905196) (xy 208.300669 -18.877364) (xy 208.469855 -18.85744) (xy 208.639789 -18.845468)
			(xy 208.810098 -18.841475) (xy 208.980407 -18.845468) (xy 209.150341 -18.85744) (xy 209.319527 -18.877364)
			(xy 209.487593 -18.905196) (xy 209.654171 -18.940875) (xy 209.818892 -18.984323) (xy 209.981396 -19.035444)
			(xy 210.141326 -19.094126) (xy 210.298329 -19.16024) (xy 210.45206 -19.23364) (xy 210.602183 -19.314165)
			(xy 210.748365 -19.401638) (xy 210.890287 -19.495867) (xy 211.027637 -19.596644) (xy 211.160112 -19.703749)
			(xy 211.28742 -19.816945) (xy 211.409284 -19.935984) (xy 211.525433 -20.060604) (xy 211.635614 -20.190532)
			(xy 211.739584 -20.325481) (xy 211.837114 -20.465155) (xy 211.92799 -20.609247) (xy 212.012012 -20.757441)
			(xy 212.088995 -20.909409) (xy 212.158771 -21.064819) (xy 212.221186 -21.223329) (xy 212.276103 -21.38459)
			(xy 212.3234 -21.548248) (xy 212.362975 -21.713943) (xy 212.394739 -21.881311) (xy 212.418624 -22.049983)
			(xy 212.434576 -22.21959) (xy 212.442561 -22.389758) (xy 212.44306 -22.474936) (xy 212.442561 -22.560114)
			(xy 235.177575 -22.560114) (xy 235.177575 -22.389758) (xy 235.18556 -22.21959) (xy 235.201512 -22.049983)
			(xy 235.225397 -21.881311) (xy 235.257161 -21.713943) (xy 235.296736 -21.548248) (xy 235.344033 -21.38459)
			(xy 235.39895 -21.223329) (xy 235.461365 -21.064819) (xy 235.531141 -20.909409) (xy 235.608124 -20.757441)
			(xy 235.692146 -20.609247) (xy 235.783022 -20.465155) (xy 235.880552 -20.325481) (xy 235.984522 -20.190532)
			(xy 236.094703 -20.060604) (xy 236.210852 -19.935984) (xy 236.332716 -19.816945) (xy 236.460024 -19.703749)
			(xy 236.592499 -19.596644) (xy 236.729849 -19.495867) (xy 236.871771 -19.401638) (xy 237.017953 -19.314165)
			(xy 237.168076 -19.23364) (xy 237.321807 -19.16024) (xy 237.47881 -19.094126) (xy 237.63874 -19.035444)
			(xy 237.801244 -18.984323) (xy 237.965965 -18.940875) (xy 238.132543 -18.905196) (xy 238.300609 -18.877364)
			(xy 238.469795 -18.85744) (xy 238.639729 -18.845468) (xy 238.810038 -18.841475) (xy 238.980347 -18.845468)
			(xy 239.150281 -18.85744) (xy 239.319467 -18.877364) (xy 239.487533 -18.905196) (xy 239.654111 -18.940875)
			(xy 239.818832 -18.984323) (xy 239.981336 -19.035444) (xy 240.141266 -19.094126) (xy 240.298269 -19.16024)
			(xy 240.452 -19.23364) (xy 240.602123 -19.314165) (xy 240.748305 -19.401638) (xy 240.890227 -19.495867)
			(xy 241.027577 -19.596644) (xy 241.160052 -19.703749) (xy 241.28736 -19.816945) (xy 241.409224 -19.935984)
			(xy 241.525373 -20.060604) (xy 241.635554 -20.190532) (xy 241.739524 -20.325481) (xy 241.837054 -20.465155)
			(xy 241.92793 -20.609247) (xy 242.011952 -20.757441) (xy 242.088935 -20.909409) (xy 242.158711 -21.064819)
			(xy 242.221126 -21.223329) (xy 242.276043 -21.38459) (xy 242.32334 -21.548248) (xy 242.362915 -21.713943)
			(xy 242.394679 -21.881311) (xy 242.418564 -22.049983) (xy 242.434516 -22.21959) (xy 242.442501 -22.389758)
			(xy 242.443 -22.474936) (xy 242.442501 -22.560114) (xy 242.434516 -22.730282) (xy 242.418564 -22.899889)
			(xy 242.394679 -23.068561) (xy 242.362915 -23.235929) (xy 242.32334 -23.401624) (xy 242.276043 -23.565282)
			(xy 242.221126 -23.726543) (xy 242.158711 -23.885053) (xy 242.088935 -24.040463) (xy 242.011952 -24.192431)
			(xy 241.92793 -24.340625) (xy 241.837054 -24.484717) (xy 241.739524 -24.624391) (xy 241.635554 -24.75934)
			(xy 241.525373 -24.889268) (xy 241.409224 -25.013888) (xy 241.28736 -25.132927) (xy 241.160052 -25.246123)
			(xy 241.027577 -25.353228) (xy 240.890227 -25.454005) (xy 240.748305 -25.548234) (xy 240.602123 -25.635707)
			(xy 240.452 -25.716232) (xy 240.298269 -25.789632) (xy 240.141266 -25.855746) (xy 239.981336 -25.914428)
			(xy 239.818832 -25.965549) (xy 239.654111 -26.008997) (xy 239.487533 -26.044676) (xy 239.319467 -26.072508)
			(xy 239.150281 -26.092432) (xy 238.980347 -26.104404) (xy 238.810038 -26.108398) (xy 238.639729 -26.104404)
			(xy 238.469795 -26.092432) (xy 238.300609 -26.072508) (xy 238.132543 -26.044676) (xy 237.965965 -26.008997)
			(xy 237.801244 -25.965549) (xy 237.63874 -25.914428) (xy 237.47881 -25.855746) (xy 237.321807 -25.789632)
			(xy 237.168076 -25.716232) (xy 237.017953 -25.635707) (xy 236.871771 -25.548234) (xy 236.729849 -25.454005)
			(xy 236.592499 -25.353228) (xy 236.460024 -25.246123) (xy 236.332716 -25.132927) (xy 236.210852 -25.013888)
			(xy 236.094703 -24.889268) (xy 235.984522 -24.75934) (xy 235.880552 -24.624391) (xy 235.783022 -24.484717)
			(xy 235.692146 -24.340625) (xy 235.608124 -24.192431) (xy 235.531141 -24.040463) (xy 235.461365 -23.885053)
			(xy 235.39895 -23.726543) (xy 235.344033 -23.565282) (xy 235.296736 -23.401624) (xy 235.257161 -23.235929)
			(xy 235.225397 -23.068561) (xy 235.201512 -22.899889) (xy 235.18556 -22.730282) (xy 235.177575 -22.560114)
			(xy 212.442561 -22.560114) (xy 212.434576 -22.730282) (xy 212.418624 -22.899889) (xy 212.394739 -23.068561)
			(xy 212.362975 -23.235929) (xy 212.3234 -23.401624) (xy 212.276103 -23.565282) (xy 212.221186 -23.726543)
			(xy 212.158771 -23.885053) (xy 212.088995 -24.040463) (xy 212.012012 -24.192431) (xy 211.92799 -24.340625)
			(xy 211.837114 -24.484717) (xy 211.739584 -24.624391) (xy 211.635614 -24.75934) (xy 211.525433 -24.889268)
			(xy 211.409284 -25.013888) (xy 211.28742 -25.132927) (xy 211.160112 -25.246123) (xy 211.027637 -25.353228)
			(xy 210.890287 -25.454005) (xy 210.748365 -25.548234) (xy 210.602183 -25.635707) (xy 210.45206 -25.716232)
			(xy 210.298329 -25.789632) (xy 210.141326 -25.855746) (xy 209.981396 -25.914428) (xy 209.818892 -25.965549)
			(xy 209.654171 -26.008997) (xy 209.487593 -26.044676) (xy 209.319527 -26.072508) (xy 209.150341 -26.092432)
			(xy 208.980407 -26.104404) (xy 208.810098 -26.108398) (xy 208.639789 -26.104404) (xy 208.469855 -26.092432)
			(xy 208.300669 -26.072508) (xy 208.132603 -26.044676) (xy 207.966025 -26.008997) (xy 207.801304 -25.965549)
			(xy 207.6388 -25.914428) (xy 207.47887 -25.855746) (xy 207.321867 -25.789632) (xy 207.168136 -25.716232)
			(xy 207.018013 -25.635707) (xy 206.871831 -25.548234) (xy 206.729909 -25.454005) (xy 206.592559 -25.353228)
			(xy 206.460084 -25.246123) (xy 206.332776 -25.132927) (xy 206.210912 -25.013888) (xy 206.094763 -24.889268)
			(xy 205.984582 -24.75934) (xy 205.880612 -24.624391) (xy 205.783082 -24.484717) (xy 205.692206 -24.340625)
			(xy 205.608184 -24.192431) (xy 205.531201 -24.040463) (xy 205.461425 -23.885053) (xy 205.39901 -23.726543)
			(xy 205.344093 -23.565282) (xy 205.296796 -23.401624) (xy 205.257221 -23.235929) (xy 205.225457 -23.068561)
			(xy 205.201572 -22.899889) (xy 205.18562 -22.730282) (xy 205.177635 -22.560114) (xy 161.1884 -22.560114)
			(xy 161.1884 -26.950924) (xy 161.188786 -26.960998) (xy 161.196532 -26.979597) (xy 161.203386 -26.986992)
			(xy 162.141408 -27.925014) (xy 162.14881 -27.931852) (xy 162.167408 -27.939572) (xy 162.177476 -27.94)
			(xy 209.1944 -27.94) (xy 209.227659 -27.940539) (xy 209.293609 -27.949225) (xy 209.35786 -27.966447)
			(xy 209.419311 -27.991911) (xy 209.476912 -28.025182) (xy 209.529676 -28.065688) (xy 209.553556 -28.088844)
			(xy 211.331556 -29.866844) (xy 211.354708 -29.890729) (xy 211.395221 -29.943489) (xy 211.428497 -30.001088)
			(xy 211.453966 -30.062539) (xy 211.471191 -30.12679) (xy 211.479879 -30.19274) (xy 211.4804 -30.226)
			(xy 211.4804 -46.99) (xy 228.854 -46.99) (xy 228.854 -30.226) (xy 228.854539 -30.192741) (xy 228.863225 -30.126791)
			(xy 228.880447 -30.06254) (xy 228.905911 -30.001089) (xy 228.939182 -29.943488) (xy 228.979688 -29.890724)
			(xy 229.002844 -29.866844) (xy 230.780844 -28.088844) (xy 230.804729 -28.065692) (xy 230.857489 -28.025179)
			(xy 230.915088 -27.991903) (xy 230.976539 -27.966434) (xy 231.04079 -27.949209) (xy 231.10674 -27.940521)
			(xy 231.14 -27.94) (xy 278.156924 -27.94) (xy 278.166998 -27.939614) (xy 278.185597 -27.931868) (xy 278.192992 -27.925014)
			(xy 279.131014 -26.986992) (xy 279.137852 -26.97959) (xy 279.145572 -26.960992) (xy 279.146 -26.950924)
			(xy 279.146 -16.146018) (xy 279.146551 -16.112759) (xy 279.155234 -16.04681) (xy 279.172454 -15.982559)
			(xy 279.197916 -15.921108) (xy 279.231184 -15.863506) (xy 279.271689 -15.810742) (xy 279.294844 -15.786862)
			(xy 282.994862 -12.086844) (xy 283.018739 -12.063684) (xy 283.071501 -12.023171) (xy 283.129101 -11.989896)
			(xy 283.190554 -11.964429) (xy 283.254806 -11.947205) (xy 283.320758 -11.93852) (xy 283.354018 -11.938)
			(xy 323.977 -11.938) (xy 324.010259 -11.938539) (xy 324.076209 -11.947225) (xy 324.14046 -11.964447)
			(xy 324.201911 -11.989911) (xy 324.259512 -12.023182) (xy 324.312276 -12.063688) (xy 324.336156 -12.086844)
			(xy 324.971156 -12.721844) (xy 324.994308 -12.745729) (xy 325.034821 -12.798489) (xy 325.068097 -12.856088)
			(xy 325.093566 -12.917539) (xy 325.110791 -12.98179) (xy 325.119479 -13.04774) (xy 325.12 -13.081)
			(xy 325.12 -17.288961) (xy 334.478626 -17.288961) (xy 334.478626 -17.204239) (xy 334.486679 -17.119902)
			(xy 334.502713 -17.036712) (xy 334.526581 -16.955422) (xy 334.558069 -16.87677) (xy 334.596891 -16.801467)
			(xy 334.642694 -16.730195) (xy 334.695065 -16.663599) (xy 334.75353 -16.602284) (xy 334.817558 -16.546803)
			(xy 334.88657 -16.49766) (xy 334.95994 -16.4553) (xy 335.037005 -16.420105) (xy 335.117067 -16.392396)
			(xy 335.1994 -16.372422) (xy 335.283259 -16.360365) (xy 335.367884 -16.356334) (xy 335.452509 -16.360365)
			(xy 335.536368 -16.372422) (xy 335.618701 -16.392396) (xy 335.698763 -16.420105) (xy 335.775828 -16.4553)
			(xy 335.849198 -16.49766) (xy 335.91821 -16.546803) (xy 335.982238 -16.602284) (xy 336.040703 -16.663599)
			(xy 336.093074 -16.730195) (xy 336.138877 -16.801467) (xy 336.177699 -16.87677) (xy 336.209187 -16.955422)
			(xy 336.233055 -17.036712) (xy 336.249089 -17.119902) (xy 336.257142 -17.204239) (xy 336.257646 -17.2466)
			(xy 336.257142 -17.288961) (xy 336.249089 -17.373298) (xy 336.233055 -17.456488) (xy 336.209187 -17.537778)
			(xy 336.177699 -17.61643) (xy 336.138877 -17.691733) (xy 336.093074 -17.763005) (xy 336.040703 -17.829601)
			(xy 335.982238 -17.890916) (xy 335.91821 -17.946397) (xy 335.849198 -17.99554) (xy 335.775828 -18.0379)
			(xy 335.698763 -18.073095) (xy 335.618701 -18.100804) (xy 335.536368 -18.120778) (xy 335.452509 -18.132835)
			(xy 335.367884 -18.136867) (xy 335.283259 -18.132835) (xy 335.1994 -18.120778) (xy 335.117067 -18.100804)
			(xy 335.037005 -18.073095) (xy 334.95994 -18.0379) (xy 334.88657 -17.99554) (xy 334.817558 -17.946397)
			(xy 334.75353 -17.890916) (xy 334.695065 -17.829601) (xy 334.642694 -17.763005) (xy 334.596891 -17.691733)
			(xy 334.558069 -17.61643) (xy 334.526581 -17.537778) (xy 334.502713 -17.456488) (xy 334.486679 -17.373298)
			(xy 334.478626 -17.288961) (xy 325.12 -17.288961) (xy 325.12 -23.0886) (xy 331.266292 -23.0886) (xy 331.266292 -23.088092)
			(xy 331.266898 -23.04176) (xy 331.276569 -22.949602) (xy 331.295765 -22.858948) (xy 331.324277 -22.770779)
			(xy 331.342492 -22.728174) (xy 331.346298 -22.718232) (xy 331.346298 -22.696968) (xy 331.342492 -22.687026)
			(xy 331.324247 -22.644364) (xy 331.295703 -22.556071) (xy 331.27651 -22.465286) (xy 331.266877 -22.372996)
			(xy 331.266292 -22.3266) (xy 331.266875 -22.280204) (xy 331.27652 -22.187916) (xy 331.295716 -22.097132)
			(xy 331.324254 -22.008839) (xy 331.342492 -21.966174) (xy 331.346298 -21.956232) (xy 331.346298 -21.934968)
			(xy 331.342492 -21.925026) (xy 331.324247 -21.882364) (xy 331.295703 -21.794071) (xy 331.27651 -21.703286)
			(xy 331.266877 -21.610996) (xy 331.266292 -21.5646) (xy 331.266875 -21.518204) (xy 331.27652 -21.425916)
			(xy 331.295716 -21.335132) (xy 331.324254 -21.246839) (xy 331.342492 -21.204174) (xy 331.346298 -21.194232)
			(xy 331.346298 -21.172968) (xy 331.342492 -21.163026) (xy 331.324247 -21.120364) (xy 331.295703 -21.032071)
			(xy 331.27651 -20.941286) (xy 331.266877 -20.848996) (xy 331.266292 -20.8026) (xy 331.266875 -20.756204)
			(xy 331.27652 -20.663916) (xy 331.295716 -20.573132) (xy 331.324254 -20.484839) (xy 331.342492 -20.442174)
			(xy 331.346298 -20.432232) (xy 331.346298 -20.410968) (xy 331.342492 -20.401026) (xy 331.32427 -20.358423)
			(xy 331.295752 -20.270256) (xy 331.27656 -20.1796) (xy 331.2669 -20.08744) (xy 331.266292 -20.041108)
			(xy 331.266292 -20.0406) (xy 331.266767 -19.999498) (xy 331.274352 -19.917643) (xy 331.289457 -19.836838)
			(xy 331.311953 -19.757771) (xy 331.341649 -19.681117) (xy 331.378291 -19.60753) (xy 331.421566 -19.537638)
			(xy 331.471106 -19.472037) (xy 331.526487 -19.411287) (xy 331.587237 -19.355906) (xy 331.652838 -19.306366)
			(xy 331.72273 -19.263091) (xy 331.796317 -19.226449) (xy 331.872971 -19.196753) (xy 331.952038 -19.174257)
			(xy 332.032843 -19.159152) (xy 332.114698 -19.151567) (xy 332.1558 -19.151092) (xy 332.156308 -19.151092)
			(xy 332.20264 -19.151698) (xy 332.294798 -19.161369) (xy 332.385452 -19.180565) (xy 332.473621 -19.209077)
			(xy 332.516226 -19.227292) (xy 332.526168 -19.231098) (xy 332.547432 -19.231098) (xy 332.557374 -19.227292)
			(xy 332.600036 -19.209047) (xy 332.688329 -19.180503) (xy 332.779114 -19.16131) (xy 332.871404 -19.151677)
			(xy 332.9178 -19.151092) (xy 332.964196 -19.151675) (xy 333.056484 -19.16132) (xy 333.147268 -19.180516)
			(xy 333.235561 -19.209054) (xy 333.278226 -19.227292) (xy 333.288168 -19.231098) (xy 333.309432 -19.231098)
			(xy 333.319374 -19.227292) (xy 333.362036 -19.209047) (xy 333.450329 -19.180503) (xy 333.541114 -19.16131)
			(xy 333.633404 -19.151677) (xy 333.6798 -19.151092) (xy 333.726196 -19.151675) (xy 333.818484 -19.16132)
			(xy 333.909268 -19.180516) (xy 333.997561 -19.209054) (xy 334.040226 -19.227292) (xy 334.050168 -19.231098)
			(xy 334.071432 -19.231098) (xy 334.081374 -19.227292) (xy 334.124036 -19.209047) (xy 334.212329 -19.180503)
			(xy 334.303114 -19.16131) (xy 334.395404 -19.151677) (xy 334.4418 -19.151092) (xy 334.488196 -19.151675)
			(xy 334.580484 -19.16132) (xy 334.671268 -19.180516) (xy 334.759561 -19.209054) (xy 334.802226 -19.227292)
			(xy 334.812168 -19.231098) (xy 334.833432 -19.231098) (xy 334.843374 -19.227292) (xy 334.885977 -19.20907)
			(xy 334.974144 -19.180552) (xy 335.0648 -19.16136) (xy 335.15696 -19.1517) (xy 335.203292 -19.151092)
			(xy 335.2038 -19.151092) (xy 335.244902 -19.151567) (xy 335.326757 -19.159152) (xy 335.407562 -19.174257)
			(xy 335.486629 -19.196753) (xy 335.563283 -19.226449) (xy 335.63687 -19.263091) (xy 335.706762 -19.306366)
			(xy 335.772363 -19.355906) (xy 335.833113 -19.411287) (xy 335.888494 -19.472037) (xy 335.938034 -19.537638)
			(xy 335.981309 -19.60753) (xy 336.017951 -19.681117) (xy 336.047647 -19.757771) (xy 336.070143 -19.836838)
			(xy 336.085248 -19.917643) (xy 336.092833 -19.999498) (xy 336.09288 -20.00357) (xy 386.295635 -20.00357)
			(xy 386.295635 -19.87443) (xy 386.303585 -19.745535) (xy 386.319455 -19.617375) (xy 386.343184 -19.490434)
			(xy 386.374683 -19.365195) (xy 386.413832 -19.242132) (xy 386.460483 -19.121713) (xy 386.514458 -19.004394)
			(xy 386.575553 -18.89062) (xy 386.643536 -18.780823) (xy 386.71815 -18.67542) (xy 386.799111 -18.57481)
			(xy 386.886111 -18.479375) (xy 386.978822 -18.389476) (xy 387.076892 -18.305455) (xy 387.179947 -18.227631)
			(xy 387.287598 -18.156299) (xy 387.399437 -18.091729) (xy 387.515038 -18.034167) (xy 387.633963 -17.98383)
			(xy 387.755762 -17.94091) (xy 387.879972 -17.905569) (xy 388.006121 -17.877942) (xy 388.133733 -17.858133)
			(xy 388.262322 -17.846217) (xy 388.3914 -17.842241) (xy 388.520478 -17.846217) (xy 388.649067 -17.858133)
			(xy 388.776679 -17.877942) (xy 388.902828 -17.905569) (xy 389.027038 -17.94091) (xy 389.148837 -17.98383)
			(xy 389.267762 -18.034167) (xy 389.383363 -18.091729) (xy 389.495202 -18.156299) (xy 389.602853 -18.227631)
			(xy 389.705908 -18.305455) (xy 389.803978 -18.389476) (xy 389.896689 -18.479375) (xy 389.983689 -18.57481)
			(xy 390.06465 -18.67542) (xy 390.139264 -18.780823) (xy 390.207247 -18.89062) (xy 390.268342 -19.004394)
			(xy 390.322317 -19.121713) (xy 390.368968 -19.242132) (xy 390.408117 -19.365195) (xy 390.439616 -19.490434)
			(xy 390.463345 -19.617375) (xy 390.479215 -19.745535) (xy 390.487165 -19.87443) (xy 390.487662 -19.939)
			(xy 390.487165 -20.00357) (xy 390.479215 -20.132465) (xy 390.463345 -20.260625) (xy 390.439616 -20.387566)
			(xy 390.408117 -20.512805) (xy 390.368968 -20.635868) (xy 390.322317 -20.756287) (xy 390.268342 -20.873606)
			(xy 390.207247 -20.98738) (xy 390.139264 -21.097177) (xy 390.06465 -21.20258) (xy 389.983689 -21.30319)
			(xy 389.896689 -21.398625) (xy 389.803978 -21.488524) (xy 389.705908 -21.572545) (xy 389.602853 -21.650369)
			(xy 389.495202 -21.721701) (xy 389.383363 -21.786271) (xy 389.267762 -21.843833) (xy 389.148837 -21.89417)
			(xy 389.027038 -21.93709) (xy 388.902828 -21.972431) (xy 388.776679 -22.000058) (xy 388.649067 -22.019867)
			(xy 388.520478 -22.031783) (xy 388.3914 -22.03576) (xy 388.262322 -22.031783) (xy 388.133733 -22.019867)
			(xy 388.006121 -22.000058) (xy 387.879972 -21.972431) (xy 387.755762 -21.93709) (xy 387.633963 -21.89417)
			(xy 387.515038 -21.843833) (xy 387.399437 -21.786271) (xy 387.287598 -21.721701) (xy 387.179947 -21.650369)
			(xy 387.076892 -21.572545) (xy 386.978822 -21.488524) (xy 386.886111 -21.398625) (xy 386.799111 -21.30319)
			(xy 386.71815 -21.20258) (xy 386.643536 -21.097177) (xy 386.575553 -20.98738) (xy 386.514458 -20.873606)
			(xy 386.460483 -20.756287) (xy 386.413832 -20.635868) (xy 386.374683 -20.512805) (xy 386.343184 -20.387566)
			(xy 386.319455 -20.260625) (xy 386.303585 -20.132465) (xy 386.295635 -20.00357) (xy 336.09288 -20.00357)
			(xy 336.093308 -20.0406) (xy 336.093308 -20.041108) (xy 336.092702 -20.08744) (xy 336.083031 -20.179598)
			(xy 336.063835 -20.270252) (xy 336.035323 -20.358421) (xy 336.017108 -20.401026) (xy 336.013302 -20.410968)
			(xy 336.013302 -20.432232) (xy 336.017108 -20.442174) (xy 336.035353 -20.484836) (xy 336.063897 -20.573129)
			(xy 336.08309 -20.663914) (xy 336.092723 -20.756204) (xy 336.093308 -20.8026) (xy 336.092725 -20.848996)
			(xy 336.08308 -20.941284) (xy 336.063884 -21.032068) (xy 336.035346 -21.120361) (xy 336.017108 -21.163026)
			(xy 336.013302 -21.172968) (xy 336.013302 -21.194232) (xy 336.017108 -21.204174) (xy 336.035353 -21.246836)
			(xy 336.063897 -21.335129) (xy 336.08309 -21.425914) (xy 336.092723 -21.518204) (xy 336.093308 -21.5646)
			(xy 336.092725 -21.610996) (xy 336.08308 -21.703284) (xy 336.063884 -21.794068) (xy 336.035346 -21.882361)
			(xy 336.017108 -21.925026) (xy 336.013302 -21.934968) (xy 336.013302 -21.956232) (xy 336.017108 -21.966174)
			(xy 336.035353 -22.008836) (xy 336.063897 -22.097129) (xy 336.08309 -22.187914) (xy 336.092723 -22.280204)
			(xy 336.093308 -22.3266) (xy 336.092725 -22.372996) (xy 336.08308 -22.465284) (xy 336.063884 -22.556068)
			(xy 336.035346 -22.644361) (xy 336.017108 -22.687026) (xy 336.013302 -22.696968) (xy 336.013302 -22.718232)
			(xy 336.017108 -22.728174) (xy 336.03533 -22.770777) (xy 336.063848 -22.858944) (xy 336.08304 -22.9496)
			(xy 336.0927 -23.04176) (xy 336.093308 -23.088092) (xy 336.093308 -23.0886) (xy 336.092833 -23.129702)
			(xy 336.085248 -23.211557) (xy 336.070143 -23.292362) (xy 336.047647 -23.371429) (xy 336.017951 -23.448083)
			(xy 335.981309 -23.52167) (xy 335.938034 -23.591562) (xy 335.888494 -23.657163) (xy 335.833113 -23.717913)
			(xy 335.772363 -23.773294) (xy 335.706762 -23.822834) (xy 335.63687 -23.866109) (xy 335.563283 -23.902751)
			(xy 335.486629 -23.932447) (xy 335.407562 -23.954943) (xy 335.326757 -23.970048) (xy 335.244902 -23.977633)
			(xy 335.2038 -23.978108) (xy 335.203292 -23.978108) (xy 335.15696 -23.977502) (xy 335.064802 -23.967831)
			(xy 334.974148 -23.948635) (xy 334.885979 -23.920123) (xy 334.843374 -23.901908) (xy 334.833432 -23.898102)
			(xy 334.812168 -23.898102) (xy 334.802226 -23.901908) (xy 334.759564 -23.920153) (xy 334.671271 -23.948697)
			(xy 334.580486 -23.96789) (xy 334.488196 -23.977523) (xy 334.4418 -23.978108) (xy 334.395404 -23.977525)
			(xy 334.303116 -23.96788) (xy 334.212332 -23.948684) (xy 334.124039 -23.920146) (xy 334.081374 -23.901908)
			(xy 334.071432 -23.898102) (xy 334.050168 -23.898102) (xy 334.040226 -23.901908) (xy 333.997564 -23.920153)
			(xy 333.909271 -23.948697) (xy 333.818486 -23.96789) (xy 333.726196 -23.977523) (xy 333.6798 -23.978108)
			(xy 333.633404 -23.977525) (xy 333.541116 -23.96788) (xy 333.450332 -23.948684) (xy 333.362039 -23.920146)
			(xy 333.319374 -23.901908) (xy 333.309432 -23.898102) (xy 333.288168 -23.898102) (xy 333.278226 -23.901908)
			(xy 333.235564 -23.920153) (xy 333.147271 -23.948697) (xy 333.056486 -23.96789) (xy 332.964196 -23.977523)
			(xy 332.9178 -23.978108) (xy 332.871404 -23.977525) (xy 332.779116 -23.96788) (xy 332.688332 -23.948684)
			(xy 332.600039 -23.920146) (xy 332.557374 -23.901908) (xy 332.547432 -23.898102) (xy 332.526168 -23.898102)
			(xy 332.516226 -23.901908) (xy 332.473623 -23.92013) (xy 332.385456 -23.948648) (xy 332.2948 -23.96784)
			(xy 332.20264 -23.9775) (xy 332.156308 -23.978108) (xy 332.1558 -23.978108) (xy 332.114698 -23.977633)
			(xy 332.032843 -23.970048) (xy 331.952038 -23.954943) (xy 331.872971 -23.932447) (xy 331.796317 -23.902751)
			(xy 331.72273 -23.866109) (xy 331.652838 -23.822834) (xy 331.587237 -23.773294) (xy 331.526487 -23.717913)
			(xy 331.471106 -23.657163) (xy 331.421566 -23.591562) (xy 331.378291 -23.52167) (xy 331.341649 -23.448083)
			(xy 331.311953 -23.371429) (xy 331.289457 -23.292362) (xy 331.274352 -23.211557) (xy 331.266767 -23.129702)
			(xy 331.266292 -23.0886) (xy 325.12 -23.0886) (xy 325.12 -28.566561) (xy 334.478626 -28.566561) (xy 334.478626 -28.481839)
			(xy 334.486679 -28.397502) (xy 334.502713 -28.314312) (xy 334.526581 -28.233022) (xy 334.558069 -28.15437)
			(xy 334.596891 -28.079067) (xy 334.642694 -28.007795) (xy 334.695065 -27.941199) (xy 334.75353 -27.879884)
			(xy 334.817558 -27.824403) (xy 334.88657 -27.77526) (xy 334.95994 -27.7329) (xy 335.037005 -27.697705)
			(xy 335.117067 -27.669996) (xy 335.1994 -27.650022) (xy 335.283259 -27.637965) (xy 335.367884 -27.633934)
			(xy 335.452509 -27.637965) (xy 335.536368 -27.650022) (xy 335.618701 -27.669996) (xy 335.698763 -27.697705)
			(xy 335.775828 -27.7329) (xy 335.849198 -27.77526) (xy 335.91821 -27.824403) (xy 335.982238 -27.879884)
			(xy 336.040703 -27.941199) (xy 336.093074 -28.007795) (xy 336.138877 -28.079067) (xy 336.177699 -28.15437)
			(xy 336.209187 -28.233022) (xy 336.233055 -28.314312) (xy 336.249089 -28.397502) (xy 336.257142 -28.481839)
			(xy 336.257646 -28.5242) (xy 336.257142 -28.566561) (xy 336.249089 -28.650898) (xy 336.233055 -28.734088)
			(xy 336.209187 -28.815378) (xy 336.177699 -28.89403) (xy 336.138877 -28.969333) (xy 336.093074 -29.040605)
			(xy 336.040703 -29.107201) (xy 335.982238 -29.168516) (xy 335.91821 -29.223997) (xy 335.849198 -29.27314)
			(xy 335.775828 -29.3155) (xy 335.698763 -29.350695) (xy 335.618701 -29.378404) (xy 335.536368 -29.398378)
			(xy 335.452509 -29.410435) (xy 335.367884 -29.414467) (xy 335.283259 -29.410435) (xy 335.1994 -29.398378)
			(xy 335.117067 -29.378404) (xy 335.037005 -29.350695) (xy 334.95994 -29.3155) (xy 334.88657 -29.27314)
			(xy 334.817558 -29.223997) (xy 334.75353 -29.168516) (xy 334.695065 -29.107201) (xy 334.642694 -29.040605)
			(xy 334.596891 -28.969333) (xy 334.558069 -28.89403) (xy 334.526581 -28.815378) (xy 334.502713 -28.734088)
			(xy 334.486679 -28.650898) (xy 334.478626 -28.566561) (xy 325.12 -28.566561) (xy 325.12 -34.3662)
			(xy 331.266292 -34.3662) (xy 331.266292 -34.365692) (xy 331.266898 -34.31936) (xy 331.276569 -34.227202)
			(xy 331.295765 -34.136548) (xy 331.324277 -34.048379) (xy 331.342492 -34.005774) (xy 331.346298 -33.995832)
			(xy 331.346298 -33.974568) (xy 331.342492 -33.964626) (xy 331.324247 -33.921964) (xy 331.295703 -33.833671)
			(xy 331.27651 -33.742886) (xy 331.266877 -33.650596) (xy 331.266292 -33.6042) (xy 331.266875 -33.557804)
			(xy 331.27652 -33.465516) (xy 331.295716 -33.374732) (xy 331.324254 -33.286439) (xy 331.342492 -33.243774)
			(xy 331.346298 -33.233832) (xy 331.346298 -33.212568) (xy 331.342492 -33.202626) (xy 331.324247 -33.159964)
			(xy 331.295703 -33.071671) (xy 331.27651 -32.980886) (xy 331.266877 -32.888596) (xy 331.266292 -32.8422)
			(xy 331.266875 -32.795804) (xy 331.27652 -32.703516) (xy 331.295716 -32.612732) (xy 331.324254 -32.524439)
			(xy 331.342492 -32.481774) (xy 331.346298 -32.471832) (xy 331.346298 -32.450568) (xy 331.342492 -32.440626)
			(xy 331.324247 -32.397964) (xy 331.295703 -32.309671) (xy 331.27651 -32.218886) (xy 331.266877 -32.126596)
			(xy 331.266292 -32.0802) (xy 331.266875 -32.033804) (xy 331.27652 -31.941516) (xy 331.295716 -31.850732)
			(xy 331.324254 -31.762439) (xy 331.342492 -31.719774) (xy 331.346298 -31.709832) (xy 331.346298 -31.688568)
			(xy 331.342492 -31.678626) (xy 331.32427 -31.636023) (xy 331.295752 -31.547856) (xy 331.27656 -31.4572)
			(xy 331.2669 -31.36504) (xy 331.266292 -31.318708) (xy 331.266292 -31.3182) (xy 331.266767 -31.277098)
			(xy 331.274352 -31.195243) (xy 331.289457 -31.114438) (xy 331.311953 -31.035371) (xy 331.341649 -30.958717)
			(xy 331.378291 -30.88513) (xy 331.421566 -30.815238) (xy 331.471106 -30.749637) (xy 331.526487 -30.688887)
			(xy 331.587237 -30.633506) (xy 331.652838 -30.583966) (xy 331.72273 -30.540691) (xy 331.796317 -30.504049)
			(xy 331.872971 -30.474353) (xy 331.952038 -30.451857) (xy 332.032843 -30.436752) (xy 332.114698 -30.429167)
			(xy 332.1558 -30.428692) (xy 332.156308 -30.428692) (xy 332.20264 -30.429298) (xy 332.294798 -30.438969)
			(xy 332.385452 -30.458165) (xy 332.473621 -30.486677) (xy 332.516226 -30.504892) (xy 332.526168 -30.508698)
			(xy 332.547432 -30.508698) (xy 332.557374 -30.504892) (xy 332.600036 -30.486647) (xy 332.688329 -30.458103)
			(xy 332.779114 -30.43891) (xy 332.871404 -30.429277) (xy 332.9178 -30.428692) (xy 332.964196 -30.429275)
			(xy 333.056484 -30.43892) (xy 333.147268 -30.458116) (xy 333.235561 -30.486654) (xy 333.278226 -30.504892)
			(xy 333.288168 -30.508698) (xy 333.309432 -30.508698) (xy 333.319374 -30.504892) (xy 333.362036 -30.486647)
			(xy 333.450329 -30.458103) (xy 333.541114 -30.43891) (xy 333.633404 -30.429277) (xy 333.6798 -30.428692)
			(xy 333.726196 -30.429275) (xy 333.818484 -30.43892) (xy 333.909268 -30.458116) (xy 333.997561 -30.486654)
			(xy 334.040226 -30.504892) (xy 334.050168 -30.508698) (xy 334.071432 -30.508698) (xy 334.081374 -30.504892)
			(xy 334.124036 -30.486647) (xy 334.212329 -30.458103) (xy 334.303114 -30.43891) (xy 334.395404 -30.429277)
			(xy 334.4418 -30.428692) (xy 334.488196 -30.429275) (xy 334.580484 -30.43892) (xy 334.671268 -30.458116)
			(xy 334.759561 -30.486654) (xy 334.802226 -30.504892) (xy 334.812168 -30.508698) (xy 334.833432 -30.508698)
			(xy 334.843374 -30.504892) (xy 334.885977 -30.48667) (xy 334.974144 -30.458152) (xy 335.0648 -30.43896)
			(xy 335.15696 -30.4293) (xy 335.203292 -30.428692) (xy 335.2038 -30.428692) (xy 335.244902 -30.429167)
			(xy 335.326757 -30.436752) (xy 335.407562 -30.451857) (xy 335.486629 -30.474353) (xy 335.563283 -30.504049)
			(xy 335.63687 -30.540691) (xy 335.706762 -30.583966) (xy 335.772363 -30.633506) (xy 335.833113 -30.688887)
			(xy 335.888494 -30.749637) (xy 335.938034 -30.815238) (xy 335.981309 -30.88513) (xy 336.017951 -30.958717)
			(xy 336.047647 -31.035371) (xy 336.070143 -31.114438) (xy 336.085248 -31.195243) (xy 336.092833 -31.277098)
			(xy 336.093308 -31.3182) (xy 336.093308 -31.318708) (xy 336.092702 -31.36504) (xy 336.083031 -31.457198)
			(xy 336.063835 -31.547852) (xy 336.035323 -31.636021) (xy 336.017108 -31.678626) (xy 336.013302 -31.688568)
			(xy 336.013302 -31.709832) (xy 336.017108 -31.719774) (xy 336.035353 -31.762436) (xy 336.063897 -31.850729)
			(xy 336.08309 -31.941514) (xy 336.092723 -32.033804) (xy 336.093308 -32.0802) (xy 336.092725 -32.126596)
			(xy 336.08308 -32.218884) (xy 336.063884 -32.309668) (xy 336.035346 -32.397961) (xy 336.017108 -32.440626)
			(xy 336.013302 -32.450568) (xy 336.013302 -32.471832) (xy 336.017108 -32.481774) (xy 336.035353 -32.524436)
			(xy 336.063897 -32.612729) (xy 336.08309 -32.703514) (xy 336.092723 -32.795804) (xy 336.093308 -32.8422)
			(xy 336.092725 -32.888596) (xy 336.08308 -32.980884) (xy 336.063884 -33.071668) (xy 336.035346 -33.159961)
			(xy 336.017108 -33.202626) (xy 336.013302 -33.212568) (xy 336.013302 -33.233832) (xy 336.017108 -33.243774)
			(xy 336.035353 -33.286436) (xy 336.063897 -33.374729) (xy 336.08309 -33.465514) (xy 336.092723 -33.557804)
			(xy 336.093308 -33.6042) (xy 336.092725 -33.650596) (xy 336.08308 -33.742884) (xy 336.063884 -33.833668)
			(xy 336.035346 -33.921961) (xy 336.017108 -33.964626) (xy 336.013302 -33.974568) (xy 336.013302 -33.995832)
			(xy 336.017108 -34.005774) (xy 336.03533 -34.048377) (xy 336.063848 -34.136544) (xy 336.08304 -34.2272)
			(xy 336.0927 -34.31936) (xy 336.093308 -34.365692) (xy 336.093308 -34.3662) (xy 336.092833 -34.407302)
			(xy 336.085248 -34.489157) (xy 336.070143 -34.569962) (xy 336.047647 -34.649029) (xy 336.017951 -34.725683)
			(xy 335.981309 -34.79927) (xy 335.938034 -34.869162) (xy 335.888494 -34.934763) (xy 335.833113 -34.995513)
			(xy 335.772363 -35.050894) (xy 335.706762 -35.100434) (xy 335.63687 -35.143709) (xy 335.563283 -35.180351)
			(xy 335.486629 -35.210047) (xy 335.407562 -35.232543) (xy 335.326757 -35.247648) (xy 335.244902 -35.255233)
			(xy 335.2038 -35.255708) (xy 335.203292 -35.255708) (xy 335.15696 -35.255102) (xy 335.064802 -35.245431)
			(xy 334.974148 -35.226235) (xy 334.885979 -35.197723) (xy 334.843374 -35.179508) (xy 334.833432 -35.175702)
			(xy 334.812168 -35.175702) (xy 334.802226 -35.179508) (xy 334.759564 -35.197753) (xy 334.671271 -35.226297)
			(xy 334.580486 -35.24549) (xy 334.488196 -35.255123) (xy 334.4418 -35.255708) (xy 334.395404 -35.255125)
			(xy 334.303116 -35.24548) (xy 334.212332 -35.226284) (xy 334.124039 -35.197746) (xy 334.081374 -35.179508)
			(xy 334.071432 -35.175702) (xy 334.050168 -35.175702) (xy 334.040226 -35.179508) (xy 333.997564 -35.197753)
			(xy 333.909271 -35.226297) (xy 333.818486 -35.24549) (xy 333.726196 -35.255123) (xy 333.6798 -35.255708)
			(xy 333.633404 -35.255125) (xy 333.541116 -35.24548) (xy 333.450332 -35.226284) (xy 333.362039 -35.197746)
			(xy 333.319374 -35.179508) (xy 333.309432 -35.175702) (xy 333.288168 -35.175702) (xy 333.278226 -35.179508)
			(xy 333.235564 -35.197753) (xy 333.147271 -35.226297) (xy 333.056486 -35.24549) (xy 332.964196 -35.255123)
			(xy 332.9178 -35.255708) (xy 332.871404 -35.255125) (xy 332.779116 -35.24548) (xy 332.688332 -35.226284)
			(xy 332.600039 -35.197746) (xy 332.557374 -35.179508) (xy 332.547432 -35.175702) (xy 332.526168 -35.175702)
			(xy 332.516226 -35.179508) (xy 332.473623 -35.19773) (xy 332.385456 -35.226248) (xy 332.2948 -35.24544)
			(xy 332.20264 -35.2551) (xy 332.156308 -35.255708) (xy 332.1558 -35.255708) (xy 332.114698 -35.255233)
			(xy 332.032843 -35.247648) (xy 331.952038 -35.232543) (xy 331.872971 -35.210047) (xy 331.796317 -35.180351)
			(xy 331.72273 -35.143709) (xy 331.652838 -35.100434) (xy 331.587237 -35.050894) (xy 331.526487 -34.995513)
			(xy 331.471106 -34.934763) (xy 331.421566 -34.869162) (xy 331.378291 -34.79927) (xy 331.341649 -34.725683)
			(xy 331.311953 -34.649029) (xy 331.289457 -34.569962) (xy 331.274352 -34.489157) (xy 331.266767 -34.407302)
			(xy 331.266292 -34.3662) (xy 325.12 -34.3662) (xy 325.12 -37.289429) (xy 337.982302 -37.289429) (xy 337.982302 -37.204707)
			(xy 337.990355 -37.12037) (xy 338.006389 -37.03718) (xy 338.030257 -36.95589) (xy 338.061745 -36.877238)
			(xy 338.100567 -36.801935) (xy 338.14637 -36.730663) (xy 338.198741 -36.664067) (xy 338.257206 -36.602752)
			(xy 338.321234 -36.547271) (xy 338.390246 -36.498128) (xy 338.463616 -36.455768) (xy 338.540681 -36.420573)
			(xy 338.620743 -36.392864) (xy 338.703076 -36.37289) (xy 338.786935 -36.360833) (xy 338.87156 -36.356802)
			(xy 338.956185 -36.360833) (xy 339.040044 -36.37289) (xy 339.122377 -36.392864) (xy 339.202439 -36.420573)
			(xy 339.279504 -36.455768) (xy 339.352874 -36.498128) (xy 339.421886 -36.547271) (xy 339.485914 -36.602752)
			(xy 339.544379 -36.664067) (xy 339.59675 -36.730663) (xy 339.642553 -36.801935) (xy 339.681375 -36.877238)
			(xy 339.712863 -36.95589) (xy 339.736731 -37.03718) (xy 339.752765 -37.12037) (xy 339.760818 -37.204707)
			(xy 339.761322 -37.247068) (xy 339.760818 -37.289429) (xy 339.752765 -37.373766) (xy 339.736731 -37.456956)
			(xy 339.712863 -37.538246) (xy 339.681375 -37.616898) (xy 339.642553 -37.692201) (xy 339.59675 -37.763473)
			(xy 339.544379 -37.830069) (xy 339.485914 -37.891384) (xy 339.421886 -37.946865) (xy 339.352874 -37.996008)
			(xy 339.279504 -38.038368) (xy 339.202439 -38.073563) (xy 339.122377 -38.101272) (xy 339.040044 -38.121246)
			(xy 338.956185 -38.133303) (xy 338.87156 -38.137335) (xy 338.786935 -38.133303) (xy 338.703076 -38.121246)
			(xy 338.620743 -38.101272) (xy 338.540681 -38.073563) (xy 338.463616 -38.038368) (xy 338.390246 -37.996008)
			(xy 338.321234 -37.946865) (xy 338.257206 -37.891384) (xy 338.198741 -37.830069) (xy 338.14637 -37.763473)
			(xy 338.100567 -37.692201) (xy 338.061745 -37.616898) (xy 338.030257 -37.538246) (xy 338.006389 -37.456956)
			(xy 337.990355 -37.373766) (xy 337.982302 -37.289429) (xy 325.12 -37.289429) (xy 325.12 -39.787831)
			(xy 334.477997 -39.787831) (xy 334.483261 -39.704146) (xy 334.496377 -39.621328) (xy 334.517229 -39.540112)
			(xy 334.545631 -39.461218) (xy 334.581332 -39.385348) (xy 334.624014 -39.313173) (xy 334.673299 -39.245336)
			(xy 334.728749 -39.182438) (xy 334.789873 -39.125038) (xy 334.856127 -39.073645) (xy 334.926923 -39.028714)
			(xy 335.001634 -38.990646) (xy 335.079595 -38.959777) (xy 335.160116 -38.936382) (xy 335.242481 -38.920669)
			(xy 335.325959 -38.912776) (xy 335.367884 -38.912292) (xy 335.368392 -38.912292) (xy 335.404819 -38.912666)
			(xy 335.477428 -38.918641) (xy 335.513426 -38.92423) (xy 335.528472 -38.926165) (xy 335.558521 -38.922119)
			(xy 335.586063 -38.909441) (xy 335.608678 -38.889246) (xy 335.624379 -38.863308) (xy 335.631785 -38.833906)
			(xy 335.630246 -38.803626) (xy 335.619897 -38.775127) (xy 335.611216 -38.762686) (xy 335.586864 -38.729613)
			(xy 335.543671 -38.659752) (xy 335.507099 -38.586206) (xy 335.477461 -38.509604) (xy 335.455009 -38.430596)
			(xy 335.439934 -38.349855) (xy 335.432365 -38.268068) (xy 335.431892 -38.227) (xy 335.432376 -38.185075)
			(xy 335.440267 -38.101596) (xy 335.455979 -38.019231) (xy 335.479372 -37.938709) (xy 335.51024 -37.860747)
			(xy 335.548307 -37.786036) (xy 335.593237 -37.715238) (xy 335.644629 -37.648983) (xy 335.702029 -37.587859)
			(xy 335.764926 -37.532407) (xy 335.832763 -37.483121) (xy 335.904937 -37.440438) (xy 335.980807 -37.404736)
			(xy 336.0597 -37.376332) (xy 336.140917 -37.355479) (xy 336.223735 -37.342362) (xy 336.30742 -37.337097)
			(xy 336.39123 -37.339731) (xy 336.474419 -37.35024) (xy 336.55625 -37.368532) (xy 336.635997 -37.394443)
			(xy 336.712951 -37.427744) (xy 336.78643 -37.46814) (xy 336.855782 -37.515271) (xy 336.92039 -37.568719)
			(xy 336.979681 -37.62801) (xy 337.033129 -37.692618) (xy 337.08026 -37.76197) (xy 337.120656 -37.835449)
			(xy 337.153957 -37.912403) (xy 337.179868 -37.99215) (xy 337.19816 -38.073981) (xy 337.208669 -38.15717)
			(xy 337.211303 -38.24098) (xy 337.206038 -38.324665) (xy 337.192921 -38.407483) (xy 337.172068 -38.4887)
			(xy 337.143664 -38.567593) (xy 337.107962 -38.643463) (xy 337.065279 -38.715637) (xy 337.015993 -38.783474)
			(xy 336.960541 -38.846371) (xy 336.899417 -38.903771) (xy 336.833162 -38.955163) (xy 336.762364 -39.000093)
			(xy 336.687653 -39.03816) (xy 336.609691 -39.069028) (xy 336.529169 -39.092421) (xy 336.446804 -39.108133)
			(xy 336.363325 -39.116024) (xy 336.3214 -39.116508) (xy 336.320892 -39.116508) (xy 336.284465 -39.116136)
			(xy 336.211856 -39.110159) (xy 336.175858 -39.10457) (xy 336.160814 -39.102622) (xy 336.130765 -39.106672)
			(xy 336.103223 -39.119352) (xy 336.080609 -39.139549) (xy 336.064909 -39.165489) (xy 336.057502 -39.194891)
			(xy 336.05904 -39.225172) (xy 336.069388 -39.253672) (xy 336.078068 -39.266114) (xy 336.102418 -39.299188)
			(xy 336.145612 -39.36905) (xy 336.182184 -39.442594) (xy 336.211822 -39.519197) (xy 336.234274 -39.598205)
			(xy 336.249349 -39.678945) (xy 336.256919 -39.760732) (xy 336.257392 -39.8018) (xy 336.256924 -39.843725)
			(xy 336.249033 -39.927203) (xy 336.233322 -40.009569) (xy 336.209928 -40.090089) (xy 336.179061 -40.168052)
			(xy 336.140994 -40.242763) (xy 336.096065 -40.31356) (xy 336.044672 -40.379815) (xy 335.987273 -40.440939)
			(xy 335.924376 -40.496391) (xy 335.85654 -40.545677) (xy 335.784367 -40.588361) (xy 335.708497 -40.624063)
			(xy 335.629604 -40.652466) (xy 335.548388 -40.67332) (xy 335.46557 -40.686437) (xy 335.381885 -40.691703)
			(xy 335.298076 -40.689069) (xy 335.214887 -40.678561) (xy 335.133056 -40.66027) (xy 335.053309 -40.634359)
			(xy 334.976355 -40.601059) (xy 334.902876 -40.560664) (xy 334.833525 -40.513534) (xy 334.768916 -40.460086)
			(xy 334.709625 -40.400796) (xy 334.656176 -40.336188) (xy 334.609044 -40.266838) (xy 334.568648 -40.19336)
			(xy 334.535346 -40.116406) (xy 334.509434 -40.03666) (xy 334.491142 -39.954829) (xy 334.480632 -39.87164)
			(xy 334.477997 -39.787831) (xy 325.12 -39.787831) (xy 325.12 -45.6438) (xy 331.266292 -45.6438) (xy 331.266292 -45.643292)
			(xy 331.266898 -45.59696) (xy 331.276569 -45.504802) (xy 331.295765 -45.414148) (xy 331.324277 -45.325979)
			(xy 331.342492 -45.283374) (xy 331.346298 -45.273432) (xy 331.346298 -45.252168) (xy 331.342492 -45.242226)
			(xy 331.324247 -45.199564) (xy 331.295703 -45.111271) (xy 331.27651 -45.020486) (xy 331.266877 -44.928196)
			(xy 331.266292 -44.8818) (xy 331.266875 -44.835404) (xy 331.27652 -44.743116) (xy 331.295716 -44.652332)
			(xy 331.324254 -44.564039) (xy 331.342492 -44.521374) (xy 331.346298 -44.511432) (xy 331.346298 -44.490168)
			(xy 331.342492 -44.480226) (xy 331.324247 -44.437564) (xy 331.295703 -44.349271) (xy 331.27651 -44.258486)
			(xy 331.266877 -44.166196) (xy 331.266292 -44.1198) (xy 331.266875 -44.073404) (xy 331.27652 -43.981116)
			(xy 331.295716 -43.890332) (xy 331.324254 -43.802039) (xy 331.342492 -43.759374) (xy 331.346298 -43.749432)
			(xy 331.346298 -43.728168) (xy 331.342492 -43.718226) (xy 331.324247 -43.675564) (xy 331.295703 -43.587271)
			(xy 331.27651 -43.496486) (xy 331.266877 -43.404196) (xy 331.266292 -43.3578) (xy 331.266875 -43.311404)
			(xy 331.27652 -43.219116) (xy 331.295716 -43.128332) (xy 331.324254 -43.040039) (xy 331.342492 -42.997374)
			(xy 331.346298 -42.987432) (xy 331.346298 -42.966168) (xy 331.342492 -42.956226) (xy 331.32427 -42.913623)
			(xy 331.295752 -42.825456) (xy 331.27656 -42.7348) (xy 331.2669 -42.64264) (xy 331.266292 -42.596308)
			(xy 331.266292 -42.5958) (xy 331.266767 -42.554698) (xy 331.274352 -42.472843) (xy 331.289457 -42.392038)
			(xy 331.311953 -42.312971) (xy 331.341649 -42.236317) (xy 331.378291 -42.16273) (xy 331.421566 -42.092838)
			(xy 331.471106 -42.027237) (xy 331.526487 -41.966487) (xy 331.587237 -41.911106) (xy 331.652838 -41.861566)
			(xy 331.72273 -41.818291) (xy 331.796317 -41.781649) (xy 331.872971 -41.751953) (xy 331.952038 -41.729457)
			(xy 332.032843 -41.714352) (xy 332.114698 -41.706767) (xy 332.1558 -41.706292) (xy 332.156308 -41.706292)
			(xy 332.20264 -41.706898) (xy 332.294798 -41.716569) (xy 332.385452 -41.735765) (xy 332.473621 -41.764277)
			(xy 332.516226 -41.782492) (xy 332.526168 -41.786298) (xy 332.547432 -41.786298) (xy 332.557374 -41.782492)
			(xy 332.600036 -41.764247) (xy 332.688329 -41.735703) (xy 332.779114 -41.71651) (xy 332.871404 -41.706877)
			(xy 332.9178 -41.706292) (xy 332.964196 -41.706875) (xy 333.056484 -41.71652) (xy 333.147268 -41.735716)
			(xy 333.235561 -41.764254) (xy 333.278226 -41.782492) (xy 333.288168 -41.786298) (xy 333.309432 -41.786298)
			(xy 333.319374 -41.782492) (xy 333.362036 -41.764247) (xy 333.450329 -41.735703) (xy 333.541114 -41.71651)
			(xy 333.633404 -41.706877) (xy 333.6798 -41.706292) (xy 333.726196 -41.706875) (xy 333.818484 -41.71652)
			(xy 333.909268 -41.735716) (xy 333.997561 -41.764254) (xy 334.040226 -41.782492) (xy 334.050168 -41.786298)
			(xy 334.071432 -41.786298) (xy 334.081374 -41.782492) (xy 334.124036 -41.764247) (xy 334.212329 -41.735703)
			(xy 334.303114 -41.71651) (xy 334.395404 -41.706877) (xy 334.4418 -41.706292) (xy 334.488196 -41.706875)
			(xy 334.580484 -41.71652) (xy 334.671268 -41.735716) (xy 334.759561 -41.764254) (xy 334.802226 -41.782492)
			(xy 334.812168 -41.786298) (xy 334.833432 -41.786298) (xy 334.843374 -41.782492) (xy 334.885977 -41.76427)
			(xy 334.974144 -41.735752) (xy 335.0648 -41.71656) (xy 335.15696 -41.7069) (xy 335.203292 -41.706292)
			(xy 335.2038 -41.706292) (xy 335.244902 -41.706767) (xy 335.326757 -41.714352) (xy 335.407562 -41.729457)
			(xy 335.486629 -41.751953) (xy 335.563283 -41.781649) (xy 335.63687 -41.818291) (xy 335.706762 -41.861566)
			(xy 335.772363 -41.911106) (xy 335.833113 -41.966487) (xy 335.888494 -42.027237) (xy 335.938034 -42.092838)
			(xy 335.981309 -42.16273) (xy 336.017951 -42.236317) (xy 336.047647 -42.312971) (xy 336.070143 -42.392038)
			(xy 336.085248 -42.472843) (xy 336.092833 -42.554698) (xy 336.093308 -42.5958) (xy 336.093308 -42.596308)
			(xy 336.092702 -42.64264) (xy 336.083031 -42.734798) (xy 336.063835 -42.825452) (xy 336.035323 -42.913621)
			(xy 336.017108 -42.956226) (xy 336.013302 -42.966168) (xy 336.013302 -42.987432) (xy 336.017108 -42.997374)
			(xy 336.035353 -43.040036) (xy 336.063897 -43.128329) (xy 336.08309 -43.219114) (xy 336.092723 -43.311404)
			(xy 336.093308 -43.3578) (xy 336.092725 -43.404196) (xy 336.08308 -43.496484) (xy 336.063884 -43.587268)
			(xy 336.035346 -43.675561) (xy 336.017108 -43.718226) (xy 336.013302 -43.728168) (xy 336.013302 -43.749432)
			(xy 336.017108 -43.759374) (xy 336.035353 -43.802036) (xy 336.063897 -43.890329) (xy 336.08309 -43.981114)
			(xy 336.092723 -44.073404) (xy 336.093308 -44.1198) (xy 336.092725 -44.166196) (xy 336.08308 -44.258484)
			(xy 336.063884 -44.349268) (xy 336.035346 -44.437561) (xy 336.017108 -44.480226) (xy 336.013302 -44.490168)
			(xy 336.013302 -44.511432) (xy 336.017108 -44.521374) (xy 336.03533 -44.563977) (xy 336.063848 -44.652144)
			(xy 336.08304 -44.7428) (xy 336.0927 -44.83496) (xy 336.093308 -44.881292) (xy 336.093308 -44.8818)
			(xy 336.092833 -44.922902) (xy 336.085248 -45.004757) (xy 336.070143 -45.085562) (xy 336.047647 -45.164629)
			(xy 336.017951 -45.241283) (xy 335.981309 -45.31487) (xy 335.938034 -45.384762) (xy 335.888494 -45.450363)
			(xy 335.833113 -45.511113) (xy 335.772363 -45.566494) (xy 335.706762 -45.616034) (xy 335.63687 -45.659309)
			(xy 335.563283 -45.695951) (xy 335.486629 -45.725647) (xy 335.407562 -45.748143) (xy 335.326757 -45.763248)
			(xy 335.244902 -45.770833) (xy 335.2038 -45.771308) (xy 335.203292 -45.771308) (xy 335.15696 -45.770702)
			(xy 335.064802 -45.761031) (xy 334.974148 -45.741835) (xy 334.885979 -45.713323) (xy 334.843374 -45.695108)
			(xy 334.833432 -45.691302) (xy 334.812168 -45.691302) (xy 334.802226 -45.695108) (xy 334.769307 -45.709337)
			(xy 334.701622 -45.733057) (xy 334.632242 -45.751237) (xy 334.596994 -45.757846) (xy 334.58687 -45.760144)
			(xy 334.569549 -45.771549) (xy 334.558144 -45.78887) (xy 334.555846 -45.798994) (xy 334.548139 -45.839659)
			(xy 334.526175 -45.919465) (xy 334.496893 -45.996885) (xy 334.460547 -46.071251) (xy 334.417451 -46.14192)
			(xy 334.367977 -46.20828) (xy 334.312554 -46.269759) (xy 334.251659 -46.325823) (xy 334.185821 -46.375989)
			(xy 334.115608 -46.419824) (xy 334.041627 -46.456947) (xy 333.964517 -46.487038) (xy 333.884946 -46.509837)
			(xy 333.803601 -46.525147) (xy 333.721186 -46.532835) (xy 333.6798 -46.533308) (xy 333.679292 -46.533308)
			(xy 333.63296 -46.532702) (xy 333.540802 -46.523031) (xy 333.450148 -46.503835) (xy 333.361979 -46.475323)
			(xy 333.319374 -46.457108) (xy 333.309432 -46.453302) (xy 333.288168 -46.453302) (xy 333.278226 -46.457108)
			(xy 333.235564 -46.475353) (xy 333.147271 -46.503897) (xy 333.056486 -46.52309) (xy 332.964196 -46.532723)
			(xy 332.9178 -46.533308) (xy 332.871404 -46.532725) (xy 332.779116 -46.52308) (xy 332.688332 -46.503884)
			(xy 332.600039 -46.475346) (xy 332.557374 -46.457108) (xy 332.547432 -46.453302) (xy 332.526168 -46.453302)
			(xy 332.516226 -46.457108) (xy 332.473623 -46.47533) (xy 332.385456 -46.503848) (xy 332.2948 -46.52304)
			(xy 332.20264 -46.5327) (xy 332.156308 -46.533308) (xy 332.1558 -46.533308) (xy 332.114698 -46.532833)
			(xy 332.032843 -46.525248) (xy 331.952038 -46.510143) (xy 331.872971 -46.487647) (xy 331.796317 -46.457951)
			(xy 331.72273 -46.421309) (xy 331.652838 -46.378034) (xy 331.587237 -46.328494) (xy 331.526487 -46.273113)
			(xy 331.471106 -46.212363) (xy 331.421566 -46.146762) (xy 331.378291 -46.07687) (xy 331.341649 -46.003283)
			(xy 331.311953 -45.926629) (xy 331.289457 -45.847562) (xy 331.274352 -45.766757) (xy 331.266767 -45.684902)
			(xy 331.266292 -45.6438) (xy 325.12 -45.6438) (xy 325.12 -48.465937) (xy 337.609176 -48.465937) (xy 337.609176 -48.381215)
			(xy 337.617229 -48.296878) (xy 337.633263 -48.213688) (xy 337.657131 -48.132398) (xy 337.688619 -48.053746)
			(xy 337.727441 -47.978443) (xy 337.773244 -47.907171) (xy 337.825615 -47.840575) (xy 337.88408 -47.77926)
			(xy 337.948108 -47.723779) (xy 338.01712 -47.674636) (xy 338.09049 -47.632276) (xy 338.167555 -47.597081)
			(xy 338.247617 -47.569372) (xy 338.32995 -47.549398) (xy 338.413809 -47.537341) (xy 338.498434 -47.53331)
			(xy 338.583059 -47.537341) (xy 338.666918 -47.549398) (xy 338.749251 -47.569372) (xy 338.829313 -47.597081)
			(xy 338.906378 -47.632276) (xy 338.979748 -47.674636) (xy 339.04876 -47.723779) (xy 339.112788 -47.77926)
			(xy 339.171253 -47.840575) (xy 339.223624 -47.907171) (xy 339.269427 -47.978443) (xy 339.308249 -48.053746)
			(xy 339.339737 -48.132398) (xy 339.363605 -48.213688) (xy 339.379639 -48.296878) (xy 339.387692 -48.381215)
			(xy 339.388196 -48.423576) (xy 339.387692 -48.465937) (xy 339.379639 -48.550274) (xy 339.363605 -48.633464)
			(xy 339.339737 -48.714754) (xy 339.308249 -48.793406) (xy 339.269427 -48.868709) (xy 339.223624 -48.939981)
			(xy 339.171253 -49.006577) (xy 339.112788 -49.067892) (xy 339.04876 -49.123373) (xy 338.979748 -49.172516)
			(xy 338.906378 -49.214876) (xy 338.829313 -49.250071) (xy 338.749251 -49.27778) (xy 338.666918 -49.297754)
			(xy 338.583059 -49.309811) (xy 338.498434 -49.313843) (xy 338.413809 -49.309811) (xy 338.32995 -49.297754)
			(xy 338.247617 -49.27778) (xy 338.167555 -49.250071) (xy 338.09049 -49.214876) (xy 338.01712 -49.172516)
			(xy 337.948108 -49.123373) (xy 337.88408 -49.067892) (xy 337.825615 -49.006577) (xy 337.773244 -48.939981)
			(xy 337.727441 -48.868709) (xy 337.688619 -48.793406) (xy 337.657131 -48.714754) (xy 337.633263 -48.633464)
			(xy 337.617229 -48.550274) (xy 337.609176 -48.465937) (xy 325.12 -48.465937) (xy 325.12 -51.065431)
			(xy 334.477997 -51.065431) (xy 334.483261 -50.981746) (xy 334.496377 -50.898928) (xy 334.517229 -50.817712)
			(xy 334.545631 -50.738818) (xy 334.581332 -50.662948) (xy 334.624014 -50.590773) (xy 334.673299 -50.522936)
			(xy 334.728749 -50.460038) (xy 334.789873 -50.402638) (xy 334.856127 -50.351245) (xy 334.926923 -50.306314)
			(xy 335.001634 -50.268246) (xy 335.079595 -50.237377) (xy 335.160116 -50.213982) (xy 335.242481 -50.198269)
			(xy 335.325959 -50.190376) (xy 335.367884 -50.189892) (xy 335.368392 -50.189892) (xy 335.404819 -50.190266)
			(xy 335.477428 -50.196241) (xy 335.513426 -50.20183) (xy 335.528472 -50.203765) (xy 335.558521 -50.199719)
			(xy 335.586063 -50.187041) (xy 335.608678 -50.166846) (xy 335.624379 -50.140908) (xy 335.631785 -50.111506)
			(xy 335.630246 -50.081226) (xy 335.619897 -50.052727) (xy 335.611216 -50.040286) (xy 335.586864 -50.007213)
			(xy 335.543671 -49.937352) (xy 335.507099 -49.863806) (xy 335.477461 -49.787204) (xy 335.455009 -49.708196)
			(xy 335.439934 -49.627455) (xy 335.432365 -49.545668) (xy 335.431892 -49.5046) (xy 335.432376 -49.462675)
			(xy 335.440267 -49.379196) (xy 335.455979 -49.296831) (xy 335.479372 -49.216309) (xy 335.51024 -49.138347)
			(xy 335.548307 -49.063636) (xy 335.593237 -48.992838) (xy 335.644629 -48.926583) (xy 335.702029 -48.865459)
			(xy 335.764926 -48.810007) (xy 335.832763 -48.760721) (xy 335.904937 -48.718038) (xy 335.980807 -48.682336)
			(xy 336.0597 -48.653932) (xy 336.140917 -48.633079) (xy 336.223735 -48.619962) (xy 336.30742 -48.614697)
			(xy 336.39123 -48.617331) (xy 336.474419 -48.62784) (xy 336.55625 -48.646132) (xy 336.635997 -48.672043)
			(xy 336.712951 -48.705344) (xy 336.78643 -48.74574) (xy 336.855782 -48.792871) (xy 336.92039 -48.846319)
			(xy 336.979681 -48.90561) (xy 337.033129 -48.970218) (xy 337.08026 -49.03957) (xy 337.120656 -49.113049)
			(xy 337.153957 -49.190003) (xy 337.179868 -49.26975) (xy 337.19816 -49.351581) (xy 337.208669 -49.43477)
			(xy 337.211303 -49.51858) (xy 337.206038 -49.602265) (xy 337.192921 -49.685083) (xy 337.172068 -49.7663)
			(xy 337.143664 -49.845193) (xy 337.107962 -49.921063) (xy 337.065279 -49.993237) (xy 337.015993 -50.061074)
			(xy 336.960541 -50.123971) (xy 336.899417 -50.181371) (xy 336.833162 -50.232763) (xy 336.762364 -50.277693)
			(xy 336.687653 -50.31576) (xy 336.609691 -50.346628) (xy 336.529169 -50.370021) (xy 336.446804 -50.385733)
			(xy 336.363325 -50.393624) (xy 336.3214 -50.394108) (xy 336.320892 -50.394108) (xy 336.284465 -50.393736)
			(xy 336.211856 -50.387759) (xy 336.175858 -50.38217) (xy 336.160814 -50.380222) (xy 336.130765 -50.384272)
			(xy 336.103223 -50.396952) (xy 336.080609 -50.417149) (xy 336.064909 -50.443089) (xy 336.057502 -50.472491)
			(xy 336.05904 -50.502772) (xy 336.069388 -50.531272) (xy 336.078068 -50.543714) (xy 336.102418 -50.576788)
			(xy 336.145612 -50.64665) (xy 336.182184 -50.720194) (xy 336.211822 -50.796797) (xy 336.234274 -50.875805)
			(xy 336.242505 -50.919888) (xy 377.061232 -50.919888) (xy 377.065214 -50.829938) (xy 377.077131 -50.740691)
			(xy 377.096889 -50.652847) (xy 377.124333 -50.567093) (xy 377.159249 -50.4841) (xy 377.201363 -50.404518)
			(xy 377.250346 -50.328969) (xy 377.305814 -50.258045) (xy 377.367334 -50.1923) (xy 377.434423 -50.13225)
			(xy 377.506557 -50.078365) (xy 377.583171 -50.031065) (xy 377.663665 -49.990722) (xy 377.74741 -49.95765)
			(xy 377.833751 -49.93211) (xy 377.92201 -49.9143) (xy 378.011499 -49.90436) (xy 378.101515 -49.902369)
			(xy 378.191356 -49.90834) (xy 378.280317 -49.922229) (xy 378.367702 -49.943925) (xy 378.452828 -49.97326)
			(xy 378.535028 -50.010003) (xy 378.613659 -50.053867) (xy 378.688106 -50.104509) (xy 378.757786 -50.161533)
			(xy 378.822153 -50.224492) (xy 378.880704 -50.292893) (xy 378.932981 -50.366201) (xy 378.978574 -50.443843)
			(xy 379.017127 -50.52521) (xy 379.048338 -50.609666) (xy 379.071962 -50.69655) (xy 379.087815 -50.785182)
			(xy 379.095772 -50.874869) (xy 379.09627 -50.919888) (xy 396.619232 -50.919888) (xy 396.623214 -50.829938)
			(xy 396.635131 -50.740691) (xy 396.654889 -50.652847) (xy 396.682333 -50.567093) (xy 396.717249 -50.4841)
			(xy 396.759363 -50.404518) (xy 396.808346 -50.328969) (xy 396.863814 -50.258045) (xy 396.925334 -50.1923)
			(xy 396.992423 -50.13225) (xy 397.064557 -50.078365) (xy 397.141171 -50.031065) (xy 397.221665 -49.990722)
			(xy 397.30541 -49.95765) (xy 397.391751 -49.93211) (xy 397.48001 -49.9143) (xy 397.569499 -49.90436)
			(xy 397.659515 -49.902369) (xy 397.749356 -49.90834) (xy 397.838317 -49.922229) (xy 397.925702 -49.943925)
			(xy 398.010828 -49.97326) (xy 398.093028 -50.010003) (xy 398.171659 -50.053867) (xy 398.246106 -50.104509)
			(xy 398.315786 -50.161533) (xy 398.380153 -50.224492) (xy 398.438704 -50.292893) (xy 398.490981 -50.366201)
			(xy 398.536574 -50.443843) (xy 398.575127 -50.52521) (xy 398.606338 -50.609666) (xy 398.629962 -50.69655)
			(xy 398.645815 -50.785182) (xy 398.653772 -50.874869) (xy 398.65427 -50.919888) (xy 398.653772 -50.964907)
			(xy 398.645815 -51.054594) (xy 398.629962 -51.143226) (xy 398.606338 -51.23011) (xy 398.575127 -51.314566)
			(xy 398.536574 -51.395933) (xy 398.490981 -51.473575) (xy 398.438704 -51.546883) (xy 398.380153 -51.615284)
			(xy 398.315786 -51.678243) (xy 398.246106 -51.735267) (xy 398.171659 -51.785909) (xy 398.093028 -51.829773)
			(xy 398.010828 -51.866516) (xy 397.925702 -51.895851) (xy 397.838317 -51.917547) (xy 397.749356 -51.931436)
			(xy 397.659515 -51.937407) (xy 397.569499 -51.935416) (xy 397.48001 -51.925476) (xy 397.391751 -51.907666)
			(xy 397.30541 -51.882126) (xy 397.221665 -51.849054) (xy 397.141171 -51.808711) (xy 397.064557 -51.761411)
			(xy 396.992423 -51.707526) (xy 396.925334 -51.647476) (xy 396.863814 -51.581731) (xy 396.808346 -51.510807)
			(xy 396.759363 -51.435258) (xy 396.717249 -51.355676) (xy 396.682333 -51.272683) (xy 396.654889 -51.186929)
			(xy 396.635131 -51.099085) (xy 396.623214 -51.009838) (xy 396.619232 -50.919888) (xy 379.09627 -50.919888)
			(xy 379.095772 -50.964907) (xy 379.087815 -51.054594) (xy 379.071962 -51.143226) (xy 379.048338 -51.23011)
			(xy 379.017127 -51.314566) (xy 378.978574 -51.395933) (xy 378.932981 -51.473575) (xy 378.880704 -51.546883)
			(xy 378.822153 -51.615284) (xy 378.757786 -51.678243) (xy 378.688106 -51.735267) (xy 378.613659 -51.785909)
			(xy 378.535028 -51.829773) (xy 378.452828 -51.866516) (xy 378.367702 -51.895851) (xy 378.280317 -51.917547)
			(xy 378.191356 -51.931436) (xy 378.101515 -51.937407) (xy 378.011499 -51.935416) (xy 377.92201 -51.925476)
			(xy 377.833751 -51.907666) (xy 377.74741 -51.882126) (xy 377.663665 -51.849054) (xy 377.583171 -51.808711)
			(xy 377.506557 -51.761411) (xy 377.434423 -51.707526) (xy 377.367334 -51.647476) (xy 377.305814 -51.581731)
			(xy 377.250346 -51.510807) (xy 377.201363 -51.435258) (xy 377.159249 -51.355676) (xy 377.124333 -51.272683)
			(xy 377.096889 -51.186929) (xy 377.077131 -51.099085) (xy 377.065214 -51.009838) (xy 377.061232 -50.919888)
			(xy 336.242505 -50.919888) (xy 336.249349 -50.956545) (xy 336.256919 -51.038332) (xy 336.257392 -51.0794)
			(xy 336.256924 -51.121325) (xy 336.249033 -51.204803) (xy 336.233322 -51.287169) (xy 336.209928 -51.367689)
			(xy 336.179061 -51.445652) (xy 336.140994 -51.520363) (xy 336.096065 -51.59116) (xy 336.044672 -51.657415)
			(xy 335.987273 -51.718539) (xy 335.924376 -51.773991) (xy 335.85654 -51.823277) (xy 335.784367 -51.865961)
			(xy 335.708497 -51.901663) (xy 335.629604 -51.930066) (xy 335.548388 -51.95092) (xy 335.46557 -51.964037)
			(xy 335.381885 -51.969303) (xy 335.298076 -51.966669) (xy 335.214887 -51.956161) (xy 335.133056 -51.93787)
			(xy 335.053309 -51.911959) (xy 334.976355 -51.878659) (xy 334.902876 -51.838264) (xy 334.833525 -51.791134)
			(xy 334.768916 -51.737686) (xy 334.709625 -51.678396) (xy 334.656176 -51.613788) (xy 334.609044 -51.544438)
			(xy 334.568648 -51.47096) (xy 334.535346 -51.394006) (xy 334.509434 -51.31426) (xy 334.491142 -51.232429)
			(xy 334.480632 -51.14924) (xy 334.477997 -51.065431) (xy 325.12 -51.065431) (xy 325.12 -56.9214)
			(xy 331.266292 -56.9214) (xy 331.266292 -56.920892) (xy 331.266898 -56.87456) (xy 331.276569 -56.782402)
			(xy 331.295765 -56.691748) (xy 331.324277 -56.603579) (xy 331.342492 -56.560974) (xy 331.346298 -56.551032)
			(xy 331.346298 -56.529768) (xy 331.342492 -56.519826) (xy 331.324247 -56.477164) (xy 331.295703 -56.388871)
			(xy 331.27651 -56.298086) (xy 331.266877 -56.205796) (xy 331.266292 -56.1594) (xy 331.266875 -56.113004)
			(xy 331.27652 -56.020716) (xy 331.295716 -55.929932) (xy 331.324254 -55.841639) (xy 331.342492 -55.798974)
			(xy 331.346298 -55.789032) (xy 331.346298 -55.767768) (xy 331.342492 -55.757826) (xy 331.324247 -55.715164)
			(xy 331.295703 -55.626871) (xy 331.27651 -55.536086) (xy 331.266877 -55.443796) (xy 331.266292 -55.3974)
			(xy 331.266875 -55.351004) (xy 331.27652 -55.258716) (xy 331.295716 -55.167932) (xy 331.324254 -55.079639)
			(xy 331.342492 -55.036974) (xy 331.346298 -55.027032) (xy 331.346298 -55.005768) (xy 331.342492 -54.995826)
			(xy 331.324247 -54.953164) (xy 331.295703 -54.864871) (xy 331.27651 -54.774086) (xy 331.266877 -54.681796)
			(xy 331.266292 -54.6354) (xy 331.266875 -54.589004) (xy 331.27652 -54.496716) (xy 331.295716 -54.405932)
			(xy 331.324254 -54.317639) (xy 331.342492 -54.274974) (xy 331.346298 -54.265032) (xy 331.346298 -54.243768)
			(xy 331.342492 -54.233826) (xy 331.32427 -54.191223) (xy 331.295752 -54.103056) (xy 331.27656 -54.0124)
			(xy 331.2669 -53.92024) (xy 331.266292 -53.873908) (xy 331.266292 -53.8734) (xy 331.266767 -53.832298)
			(xy 331.274352 -53.750443) (xy 331.289457 -53.669638) (xy 331.311953 -53.590571) (xy 331.341649 -53.513917)
			(xy 331.378291 -53.44033) (xy 331.421566 -53.370438) (xy 331.471106 -53.304837) (xy 331.526487 -53.244087)
			(xy 331.587237 -53.188706) (xy 331.652838 -53.139166) (xy 331.72273 -53.095891) (xy 331.796317 -53.059249)
			(xy 331.872971 -53.029553) (xy 331.952038 -53.007057) (xy 332.032843 -52.991952) (xy 332.114698 -52.984367)
			(xy 332.1558 -52.983892) (xy 332.156308 -52.983892) (xy 332.20264 -52.984498) (xy 332.294798 -52.994169)
			(xy 332.385452 -53.013365) (xy 332.473621 -53.041877) (xy 332.516226 -53.060092) (xy 332.526168 -53.063898)
			(xy 332.547432 -53.063898) (xy 332.557374 -53.060092) (xy 332.600036 -53.041847) (xy 332.688329 -53.013303)
			(xy 332.779114 -52.99411) (xy 332.871404 -52.984477) (xy 332.9178 -52.983892) (xy 332.964196 -52.984475)
			(xy 333.056484 -52.99412) (xy 333.147268 -53.013316) (xy 333.235561 -53.041854) (xy 333.278226 -53.060092)
			(xy 333.288168 -53.063898) (xy 333.309432 -53.063898) (xy 333.319374 -53.060092) (xy 333.362036 -53.041847)
			(xy 333.450329 -53.013303) (xy 333.541114 -52.99411) (xy 333.633404 -52.984477) (xy 333.6798 -52.983892)
			(xy 333.726196 -52.984475) (xy 333.818484 -52.99412) (xy 333.909268 -53.013316) (xy 333.997561 -53.041854)
			(xy 334.040226 -53.060092) (xy 334.050168 -53.063898) (xy 334.071432 -53.063898) (xy 334.081374 -53.060092)
			(xy 334.124036 -53.041847) (xy 334.212329 -53.013303) (xy 334.303114 -52.99411) (xy 334.395404 -52.984477)
			(xy 334.4418 -52.983892) (xy 334.488196 -52.984475) (xy 334.580484 -52.99412) (xy 334.671268 -53.013316)
			(xy 334.759561 -53.041854) (xy 334.802226 -53.060092) (xy 334.812168 -53.063898) (xy 334.833432 -53.063898)
			(xy 334.843374 -53.060092) (xy 334.885977 -53.04187) (xy 334.974144 -53.013352) (xy 335.0648 -52.99416)
			(xy 335.15696 -52.9845) (xy 335.203292 -52.983892) (xy 335.2038 -52.983892) (xy 335.244902 -52.984367)
			(xy 335.326757 -52.991952) (xy 335.407562 -53.007057) (xy 335.486629 -53.029553) (xy 335.563283 -53.059249)
			(xy 335.63687 -53.095891) (xy 335.706762 -53.139166) (xy 335.772363 -53.188706) (xy 335.833113 -53.244087)
			(xy 335.888494 -53.304837) (xy 335.938034 -53.370438) (xy 335.981309 -53.44033) (xy 336.017951 -53.513917)
			(xy 336.047647 -53.590571) (xy 336.070143 -53.669638) (xy 336.085248 -53.750443) (xy 336.092833 -53.832298)
			(xy 336.093308 -53.8734) (xy 336.093308 -53.873908) (xy 336.092702 -53.92024) (xy 336.083031 -54.012398)
			(xy 336.063835 -54.103052) (xy 336.035323 -54.191221) (xy 336.017108 -54.233826) (xy 336.013302 -54.243768)
			(xy 336.013302 -54.265032) (xy 336.017108 -54.274974) (xy 336.035353 -54.317636) (xy 336.063897 -54.405929)
			(xy 336.08309 -54.496714) (xy 336.092723 -54.589004) (xy 336.093308 -54.6354) (xy 336.092725 -54.681796)
			(xy 336.08308 -54.774084) (xy 336.063884 -54.864868) (xy 336.035346 -54.953161) (xy 336.017108 -54.995826)
			(xy 336.013302 -55.005768) (xy 336.013302 -55.027032) (xy 336.017108 -55.036974) (xy 336.035353 -55.079636)
			(xy 336.063897 -55.167929) (xy 336.08309 -55.258714) (xy 336.092723 -55.351004) (xy 336.093308 -55.3974)
			(xy 336.092725 -55.443796) (xy 336.08308 -55.536084) (xy 336.063884 -55.626868) (xy 336.035346 -55.715161)
			(xy 336.017108 -55.757826) (xy 336.013302 -55.767768) (xy 336.013302 -55.789032) (xy 336.017108 -55.798974)
			(xy 336.035353 -55.841636) (xy 336.063897 -55.929929) (xy 336.076593 -55.989982) (xy 468.668363 -55.989982)
			(xy 468.672353 -55.876999) (xy 468.684302 -55.764578) (xy 468.704152 -55.653281) (xy 468.731804 -55.543661)
			(xy 468.767118 -55.436264) (xy 468.809921 -55.331626) (xy 468.859998 -55.230268) (xy 468.9171 -55.132695)
			(xy 468.980942 -55.039393) (xy 469.051207 -54.950827) (xy 469.127544 -54.867437) (xy 469.209573 -54.78964)
			(xy 469.296886 -54.717823) (xy 469.389047 -54.652344) (xy 469.485597 -54.593529) (xy 469.586055 -54.541671)
			(xy 469.689922 -54.497029) (xy 469.796678 -54.459824) (xy 469.905793 -54.430242) (xy 470.016723 -54.408431)
			(xy 470.128915 -54.3945) (xy 470.24181 -54.388516) (xy 470.354846 -54.390512) (xy 470.46746 -54.400475)
			(xy 470.579091 -54.418358) (xy 470.689182 -54.44407) (xy 470.797185 -54.477484) (xy 470.902562 -54.518433)
			(xy 471.004788 -54.566714) (xy 471.103353 -54.622085) (xy 471.197768 -54.68427) (xy 471.28756 -54.752961)
			(xy 471.372284 -54.827815) (xy 471.451517 -54.908458) (xy 471.524863 -54.99449) (xy 471.591959 -55.085481)
			(xy 471.652468 -55.180978) (xy 471.706091 -55.280505) (xy 471.75256 -55.383568) (xy 471.791643 -55.489651)
			(xy 471.823146 -55.598227) (xy 471.846911 -55.708754) (xy 471.862821 -55.820683) (xy 471.870795 -55.933455)
			(xy 471.871294 -55.989982) (xy 471.870795 -56.046509) (xy 471.862821 -56.159281) (xy 471.846911 -56.27121)
			(xy 471.823146 -56.381737) (xy 471.791643 -56.490313) (xy 471.75256 -56.596396) (xy 471.706091 -56.699459)
			(xy 471.652468 -56.798986) (xy 471.591959 -56.894483) (xy 471.524863 -56.985474) (xy 471.451517 -57.071506)
			(xy 471.372284 -57.152149) (xy 471.28756 -57.227003) (xy 471.197768 -57.295694) (xy 471.103353 -57.357879)
			(xy 471.004788 -57.41325) (xy 470.902562 -57.461531) (xy 470.797185 -57.50248) (xy 470.689182 -57.535894)
			(xy 470.579091 -57.561606) (xy 470.46746 -57.579489) (xy 470.354846 -57.589452) (xy 470.24181 -57.591448)
			(xy 470.128915 -57.585464) (xy 470.016723 -57.571533) (xy 469.905793 -57.549722) (xy 469.796678 -57.52014)
			(xy 469.689922 -57.482935) (xy 469.586055 -57.438293) (xy 469.485597 -57.386435) (xy 469.389047 -57.32762)
			(xy 469.296886 -57.262141) (xy 469.209573 -57.190324) (xy 469.127544 -57.112527) (xy 469.051207 -57.029137)
			(xy 468.980942 -56.940571) (xy 468.9171 -56.847269) (xy 468.859998 -56.749696) (xy 468.809921 -56.648338)
			(xy 468.767118 -56.5437) (xy 468.731804 -56.436303) (xy 468.704152 -56.326683) (xy 468.684302 -56.215386)
			(xy 468.672353 -56.102965) (xy 468.668363 -55.989982) (xy 336.076593 -55.989982) (xy 336.08309 -56.020714)
			(xy 336.092723 -56.113004) (xy 336.093308 -56.1594) (xy 336.092725 -56.205796) (xy 336.08308 -56.298084)
			(xy 336.063884 -56.388868) (xy 336.035346 -56.477161) (xy 336.017108 -56.519826) (xy 336.013302 -56.529768)
			(xy 336.013302 -56.551032) (xy 336.017108 -56.560974) (xy 336.03533 -56.603577) (xy 336.063848 -56.691744)
			(xy 336.08304 -56.7824) (xy 336.0927 -56.87456) (xy 336.093308 -56.920892) (xy 336.093308 -56.9214)
			(xy 336.092833 -56.962502) (xy 336.085248 -57.044357) (xy 336.070143 -57.125162) (xy 336.047647 -57.204229)
			(xy 336.017951 -57.280883) (xy 335.981309 -57.35447) (xy 335.938034 -57.424362) (xy 335.888494 -57.489963)
			(xy 335.833113 -57.550713) (xy 335.772363 -57.606094) (xy 335.706762 -57.655634) (xy 335.63687 -57.698909)
			(xy 335.563283 -57.735551) (xy 335.486629 -57.765247) (xy 335.407562 -57.787743) (xy 335.326757 -57.802848)
			(xy 335.244902 -57.810433) (xy 335.2038 -57.810908) (xy 335.203292 -57.810908) (xy 335.15696 -57.810302)
			(xy 335.064802 -57.800631) (xy 334.974148 -57.781435) (xy 334.885979 -57.752923) (xy 334.843374 -57.734708)
			(xy 334.833432 -57.730902) (xy 334.812168 -57.730902) (xy 334.802226 -57.734708) (xy 334.759564 -57.752953)
			(xy 334.671271 -57.781497) (xy 334.580486 -57.80069) (xy 334.488196 -57.810323) (xy 334.4418 -57.810908)
			(xy 334.395404 -57.810325) (xy 334.303116 -57.80068) (xy 334.212332 -57.781484) (xy 334.124039 -57.752946)
			(xy 334.081374 -57.734708) (xy 334.071432 -57.730902) (xy 334.050168 -57.730902) (xy 334.040226 -57.734708)
			(xy 333.997564 -57.752953) (xy 333.909271 -57.781497) (xy 333.818486 -57.80069) (xy 333.726196 -57.810323)
			(xy 333.6798 -57.810908) (xy 333.633404 -57.810325) (xy 333.541116 -57.80068) (xy 333.450332 -57.781484)
			(xy 333.362039 -57.752946) (xy 333.319374 -57.734708) (xy 333.309432 -57.730902) (xy 333.288168 -57.730902)
			(xy 333.278226 -57.734708) (xy 333.235564 -57.752953) (xy 333.147271 -57.781497) (xy 333.056486 -57.80069)
			(xy 332.964196 -57.810323) (xy 332.9178 -57.810908) (xy 332.871404 -57.810325) (xy 332.779116 -57.80068)
			(xy 332.688332 -57.781484) (xy 332.600039 -57.752946) (xy 332.557374 -57.734708) (xy 332.547432 -57.730902)
			(xy 332.526168 -57.730902) (xy 332.516226 -57.734708) (xy 332.473623 -57.75293) (xy 332.385456 -57.781448)
			(xy 332.2948 -57.80064) (xy 332.20264 -57.8103) (xy 332.156308 -57.810908) (xy 332.1558 -57.810908)
			(xy 332.114698 -57.810433) (xy 332.032843 -57.802848) (xy 331.952038 -57.787743) (xy 331.872971 -57.765247)
			(xy 331.796317 -57.735551) (xy 331.72273 -57.698909) (xy 331.652838 -57.655634) (xy 331.587237 -57.606094)
			(xy 331.526487 -57.550713) (xy 331.471106 -57.489963) (xy 331.421566 -57.424362) (xy 331.378291 -57.35447)
			(xy 331.341649 -57.280883) (xy 331.311953 -57.204229) (xy 331.289457 -57.125162) (xy 331.274352 -57.044357)
			(xy 331.266767 -56.962502) (xy 331.266292 -56.9214) (xy 325.12 -56.9214) (xy 325.12 -58.42) (xy 376.553741 -58.42)
			(xy 376.557716 -58.309941) (xy 376.569624 -58.200455) (xy 376.5894 -58.092114) (xy 376.616943 -57.985483)
			(xy 376.652108 -57.881117) (xy 376.694712 -57.77956) (xy 376.744533 -57.681343) (xy 376.801312 -57.586976)
			(xy 376.864751 -57.496952) (xy 376.934522 -57.411741) (xy 377.010259 -57.331786) (xy 377.091568 -57.257505)
			(xy 377.178025 -57.189285) (xy 377.269179 -57.12748) (xy 377.364556 -57.072415) (xy 377.463657 -57.024375)
			(xy 377.565966 -56.983611) (xy 377.67095 -56.950336) (xy 377.778061 -56.924723) (xy 377.886741 -56.906906)
			(xy 377.996424 -56.896977) (xy 378.106537 -56.894989) (xy 378.216507 -56.900951) (xy 378.32576 -56.914833)
			(xy 378.433726 -56.936563) (xy 378.539843 -56.966026) (xy 378.643557 -57.003069) (xy 378.744328 -57.0475)
			(xy 378.84163 -57.099087) (xy 378.934956 -57.157559) (xy 379.023819 -57.222614) (xy 379.107757 -57.293912)
			(xy 379.186332 -57.37108) (xy 379.259133 -57.453717) (xy 379.325781 -57.541391) (xy 379.38593 -57.633647)
			(xy 379.439264 -57.730002) (xy 379.485507 -57.829954) (xy 379.524417 -57.932982) (xy 379.555791 -58.03855)
			(xy 379.579466 -58.146106) (xy 379.595318 -58.25509) (xy 379.603265 -58.364934) (xy 379.603762 -58.42)
			(xy 396.111741 -58.42) (xy 396.115716 -58.309941) (xy 396.127624 -58.200455) (xy 396.1474 -58.092114)
			(xy 396.174943 -57.985483) (xy 396.210108 -57.881117) (xy 396.252712 -57.77956) (xy 396.302533 -57.681343)
			(xy 396.359312 -57.586976) (xy 396.422751 -57.496952) (xy 396.492522 -57.411741) (xy 396.568259 -57.331786)
			(xy 396.649568 -57.257505) (xy 396.736025 -57.189285) (xy 396.827179 -57.12748) (xy 396.922556 -57.072415)
			(xy 397.021657 -57.024375) (xy 397.123966 -56.983611) (xy 397.22895 -56.950336) (xy 397.336061 -56.924723)
			(xy 397.444741 -56.906906) (xy 397.554424 -56.896977) (xy 397.664537 -56.894989) (xy 397.774507 -56.900951)
			(xy 397.88376 -56.914833) (xy 397.991726 -56.936563) (xy 398.097843 -56.966026) (xy 398.201557 -57.003069)
			(xy 398.302328 -57.0475) (xy 398.39963 -57.099087) (xy 398.492956 -57.157559) (xy 398.581819 -57.222614)
			(xy 398.665757 -57.293912) (xy 398.744332 -57.37108) (xy 398.817133 -57.453717) (xy 398.883781 -57.541391)
			(xy 398.94393 -57.633647) (xy 398.997264 -57.730002) (xy 399.043507 -57.829954) (xy 399.082417 -57.932982)
			(xy 399.113791 -58.03855) (xy 399.137466 -58.146106) (xy 399.153318 -58.25509) (xy 399.161265 -58.364934)
			(xy 399.161762 -58.42) (xy 399.161265 -58.475066) (xy 399.153318 -58.58491) (xy 399.137466 -58.693894)
			(xy 399.113791 -58.80145) (xy 399.082417 -58.907018) (xy 399.043507 -59.010046) (xy 398.997264 -59.109998)
			(xy 398.94393 -59.206353) (xy 398.883781 -59.298609) (xy 398.817133 -59.386283) (xy 398.744332 -59.46892)
			(xy 398.665757 -59.546088) (xy 398.581819 -59.617386) (xy 398.492956 -59.682441) (xy 398.39963 -59.740913)
			(xy 398.302328 -59.7925) (xy 398.201557 -59.836931) (xy 398.097843 -59.873974) (xy 397.991726 -59.903437)
			(xy 397.88376 -59.925167) (xy 397.774507 -59.939049) (xy 397.664537 -59.945011) (xy 397.554424 -59.943023)
			(xy 397.444741 -59.933094) (xy 397.336061 -59.915277) (xy 397.22895 -59.889664) (xy 397.123966 -59.856389)
			(xy 397.021657 -59.815625) (xy 396.922556 -59.767585) (xy 396.827179 -59.71252) (xy 396.736025 -59.650715)
			(xy 396.649568 -59.582495) (xy 396.568259 -59.508214) (xy 396.492522 -59.428259) (xy 396.422751 -59.343048)
			(xy 396.359312 -59.253024) (xy 396.302533 -59.158657) (xy 396.252712 -59.06044) (xy 396.210108 -58.958883)
			(xy 396.174943 -58.854517) (xy 396.1474 -58.747886) (xy 396.127624 -58.639545) (xy 396.115716 -58.530059)
			(xy 396.111741 -58.42) (xy 379.603762 -58.42) (xy 379.603265 -58.475066) (xy 379.595318 -58.58491)
			(xy 379.579466 -58.693894) (xy 379.555791 -58.80145) (xy 379.524417 -58.907018) (xy 379.485507 -59.010046)
			(xy 379.439264 -59.109998) (xy 379.38593 -59.206353) (xy 379.325781 -59.298609) (xy 379.259133 -59.386283)
			(xy 379.186332 -59.46892) (xy 379.107757 -59.546088) (xy 379.023819 -59.617386) (xy 378.934956 -59.682441)
			(xy 378.84163 -59.740913) (xy 378.744328 -59.7925) (xy 378.643557 -59.836931) (xy 378.539843 -59.873974)
			(xy 378.433726 -59.903437) (xy 378.32576 -59.925167) (xy 378.216507 -59.939049) (xy 378.106537 -59.945011)
			(xy 377.996424 -59.943023) (xy 377.886741 -59.933094) (xy 377.778061 -59.915277) (xy 377.67095 -59.889664)
			(xy 377.565966 -59.856389) (xy 377.463657 -59.815625) (xy 377.364556 -59.767585) (xy 377.269179 -59.71252)
			(xy 377.178025 -59.650715) (xy 377.091568 -59.582495) (xy 377.010259 -59.508214) (xy 376.934522 -59.428259)
			(xy 376.864751 -59.343048) (xy 376.801312 -59.253024) (xy 376.744533 -59.158657) (xy 376.694712 -59.06044)
			(xy 376.652108 -58.958883) (xy 376.616943 -58.854517) (xy 376.5894 -58.747886) (xy 376.569624 -58.639545)
			(xy 376.557716 -58.530059) (xy 376.553741 -58.42) (xy 325.12 -58.42) (xy 325.12 -60.099956) (xy 422.484046 -60.099956)
			(xy 422.488076 -59.957621) (xy 422.500151 -59.815741) (xy 422.520234 -59.674773) (xy 422.548261 -59.535166)
			(xy 422.584141 -59.397368) (xy 422.627759 -59.261821) (xy 422.678976 -59.128959) (xy 422.737627 -58.999207)
			(xy 422.803525 -58.872981) (xy 422.876459 -58.750685) (xy 422.956196 -58.632712) (xy 423.042478 -58.519439)
			(xy 423.135031 -58.411228) (xy 423.233558 -58.308427) (xy 423.337743 -58.211365) (xy 423.447252 -58.120353)
			(xy 423.561735 -58.035681) (xy 423.680825 -57.957623) (xy 423.80414 -57.886427) (xy 423.931286 -57.822321)
			(xy 424.061855 -57.765512) (xy 424.195429 -57.71618) (xy 424.33158 -57.674484) (xy 424.469871 -57.640558)
			(xy 424.609861 -57.61451) (xy 424.7511 -57.596424) (xy 424.893136 -57.586357) (xy 425.035514 -57.584342)
			(xy 425.177778 -57.590385) (xy 425.319472 -57.604467) (xy 425.460142 -57.626543) (xy 425.599339 -57.656543)
			(xy 425.736615 -57.694369) (xy 425.871531 -57.739901) (xy 426.003655 -57.792992) (xy 426.132564 -57.853474)
			(xy 426.257845 -57.921152) (xy 426.379096 -57.995809) (xy 426.495929 -58.077207) (xy 426.60797 -58.165084)
			(xy 426.71486 -58.259159) (xy 426.816257 -58.359131) (xy 426.911835 -58.464679) (xy 427.001289 -58.575465)
			(xy 427.084331 -58.691134) (xy 427.160697 -58.811317) (xy 427.230141 -58.935627) (xy 427.292441 -59.063668)
			(xy 427.347397 -59.195027) (xy 427.394834 -59.329286) (xy 427.434598 -59.466013) (xy 427.466564 -59.604771)
			(xy 427.490629 -59.745115) (xy 427.506715 -59.886596) (xy 427.51477 -60.02876) (xy 427.515274 -60.099956)
			(xy 427.51477 -60.171152) (xy 427.506715 -60.313316) (xy 427.490629 -60.454797) (xy 427.466564 -60.595141)
			(xy 427.434598 -60.733899) (xy 427.394834 -60.870626) (xy 427.347397 -61.004885) (xy 427.292441 -61.136244)
			(xy 427.230141 -61.264285) (xy 427.160697 -61.388595) (xy 427.084331 -61.508778) (xy 427.001289 -61.624447)
			(xy 426.911835 -61.735233) (xy 426.816257 -61.840781) (xy 426.71486 -61.940753) (xy 426.60797 -62.034828)
			(xy 426.495929 -62.122705) (xy 426.379096 -62.204103) (xy 426.257845 -62.27876) (xy 426.132564 -62.346438)
			(xy 426.003655 -62.40692) (xy 425.871531 -62.460011) (xy 425.736615 -62.505543) (xy 425.599339 -62.543369)
			(xy 425.460142 -62.573369) (xy 425.319472 -62.595445) (xy 425.177778 -62.609527) (xy 425.035514 -62.61557)
			(xy 424.893136 -62.613555) (xy 424.7511 -62.603488) (xy 424.609861 -62.585402) (xy 424.469871 -62.559354)
			(xy 424.33158 -62.525428) (xy 424.195429 -62.483732) (xy 424.061855 -62.4344) (xy 423.931286 -62.377591)
			(xy 423.80414 -62.313485) (xy 423.680825 -62.242289) (xy 423.561735 -62.164231) (xy 423.447252 -62.079559)
			(xy 423.337743 -61.988547) (xy 423.233558 -61.891485) (xy 423.135031 -61.788684) (xy 423.042478 -61.680473)
			(xy 422.956196 -61.5672) (xy 422.876459 -61.449227) (xy 422.803525 -61.326931) (xy 422.737627 -61.200705)
			(xy 422.678976 -61.070953) (xy 422.627759 -60.938091) (xy 422.584141 -60.802544) (xy 422.548261 -60.664746)
			(xy 422.520234 -60.525139) (xy 422.500151 -60.384171) (xy 422.488076 -60.242291) (xy 422.484046 -60.099956)
			(xy 325.12 -60.099956) (xy 325.12 -62.399361) (xy 334.478626 -62.399361) (xy 334.478626 -62.314639)
			(xy 334.486679 -62.230302) (xy 334.502713 -62.147112) (xy 334.526581 -62.065822) (xy 334.558069 -61.98717)
			(xy 334.596891 -61.911867) (xy 334.642694 -61.840595) (xy 334.695065 -61.773999) (xy 334.75353 -61.712684)
			(xy 334.817558 -61.657203) (xy 334.88657 -61.60806) (xy 334.95994 -61.5657) (xy 335.037005 -61.530505)
			(xy 335.117067 -61.502796) (xy 335.1994 -61.482822) (xy 335.283259 -61.470765) (xy 335.367884 -61.466734)
			(xy 335.452509 -61.470765) (xy 335.536368 -61.482822) (xy 335.618701 -61.502796) (xy 335.698763 -61.530505)
			(xy 335.775828 -61.5657) (xy 335.849198 -61.60806) (xy 335.91821 -61.657203) (xy 335.982238 -61.712684)
			(xy 336.040703 -61.773999) (xy 336.093074 -61.840595) (xy 336.138877 -61.911867) (xy 336.177699 -61.98717)
			(xy 336.209187 -62.065822) (xy 336.233055 -62.147112) (xy 336.249089 -62.230302) (xy 336.257142 -62.314639)
			(xy 336.257646 -62.357) (xy 336.257142 -62.399361) (xy 336.249089 -62.483698) (xy 336.233055 -62.566888)
			(xy 336.209187 -62.648178) (xy 336.177699 -62.72683) (xy 336.138877 -62.802133) (xy 336.093074 -62.873405)
			(xy 336.040703 -62.940001) (xy 335.982238 -63.001316) (xy 335.91821 -63.056797) (xy 335.849198 -63.10594)
			(xy 335.775828 -63.1483) (xy 335.698763 -63.183495) (xy 335.618701 -63.211204) (xy 335.536368 -63.231178)
			(xy 335.452509 -63.243235) (xy 335.367884 -63.247267) (xy 335.283259 -63.243235) (xy 335.1994 -63.231178)
			(xy 335.117067 -63.211204) (xy 335.037005 -63.183495) (xy 334.95994 -63.1483) (xy 334.88657 -63.10594)
			(xy 334.817558 -63.056797) (xy 334.75353 -63.001316) (xy 334.695065 -62.940001) (xy 334.642694 -62.873405)
			(xy 334.596891 -62.802133) (xy 334.558069 -62.72683) (xy 334.526581 -62.648178) (xy 334.502713 -62.566888)
			(xy 334.486679 -62.483698) (xy 334.478626 -62.399361) (xy 325.12 -62.399361) (xy 325.12 -68.199)
			(xy 331.266292 -68.199) (xy 331.266292 -68.198492) (xy 331.266898 -68.15216) (xy 331.276569 -68.060002)
			(xy 331.295765 -67.969348) (xy 331.324277 -67.881179) (xy 331.342492 -67.838574) (xy 331.346298 -67.828632)
			(xy 331.346298 -67.807368) (xy 331.342492 -67.797426) (xy 331.324247 -67.754764) (xy 331.295703 -67.666471)
			(xy 331.27651 -67.575686) (xy 331.266877 -67.483396) (xy 331.266292 -67.437) (xy 331.266875 -67.390604)
			(xy 331.27652 -67.298316) (xy 331.295716 -67.207532) (xy 331.324254 -67.119239) (xy 331.342492 -67.076574)
			(xy 331.346298 -67.066632) (xy 331.346298 -67.045368) (xy 331.342492 -67.035426) (xy 331.324247 -66.992764)
			(xy 331.295703 -66.904471) (xy 331.27651 -66.813686) (xy 331.266877 -66.721396) (xy 331.266292 -66.675)
			(xy 331.266875 -66.628604) (xy 331.27652 -66.536316) (xy 331.295716 -66.445532) (xy 331.324254 -66.357239)
			(xy 331.342492 -66.314574) (xy 331.346298 -66.304632) (xy 331.346298 -66.283368) (xy 331.342492 -66.273426)
			(xy 331.324247 -66.230764) (xy 331.295703 -66.142471) (xy 331.27651 -66.051686) (xy 331.266877 -65.959396)
			(xy 331.266292 -65.913) (xy 331.266875 -65.866604) (xy 331.27652 -65.774316) (xy 331.295716 -65.683532)
			(xy 331.324254 -65.595239) (xy 331.342492 -65.552574) (xy 331.346298 -65.542632) (xy 331.346298 -65.521368)
			(xy 331.342492 -65.511426) (xy 331.32427 -65.468823) (xy 331.295752 -65.380656) (xy 331.27656 -65.29)
			(xy 331.2669 -65.19784) (xy 331.266292 -65.151508) (xy 331.266292 -65.151) (xy 331.266767 -65.109898)
			(xy 331.274352 -65.028043) (xy 331.289457 -64.947238) (xy 331.311953 -64.868171) (xy 331.341649 -64.791517)
			(xy 331.378291 -64.71793) (xy 331.421566 -64.648038) (xy 331.471106 -64.582437) (xy 331.526487 -64.521687)
			(xy 331.587237 -64.466306) (xy 331.652838 -64.416766) (xy 331.72273 -64.373491) (xy 331.796317 -64.336849)
			(xy 331.872971 -64.307153) (xy 331.952038 -64.284657) (xy 332.032843 -64.269552) (xy 332.114698 -64.261967)
			(xy 332.1558 -64.261492) (xy 332.156308 -64.261492) (xy 332.20264 -64.262098) (xy 332.294798 -64.271769)
			(xy 332.385452 -64.290965) (xy 332.473621 -64.319477) (xy 332.516226 -64.337692) (xy 332.526168 -64.341498)
			(xy 332.547432 -64.341498) (xy 332.557374 -64.337692) (xy 332.600036 -64.319447) (xy 332.688329 -64.290903)
			(xy 332.779114 -64.27171) (xy 332.871404 -64.262077) (xy 332.9178 -64.261492) (xy 332.964196 -64.262075)
			(xy 333.056484 -64.27172) (xy 333.147268 -64.290916) (xy 333.235561 -64.319454) (xy 333.278226 -64.337692)
			(xy 333.288168 -64.341498) (xy 333.309432 -64.341498) (xy 333.319374 -64.337692) (xy 333.362036 -64.319447)
			(xy 333.450329 -64.290903) (xy 333.541114 -64.27171) (xy 333.633404 -64.262077) (xy 333.6798 -64.261492)
			(xy 333.726196 -64.262075) (xy 333.818484 -64.27172) (xy 333.909268 -64.290916) (xy 333.997561 -64.319454)
			(xy 334.040226 -64.337692) (xy 334.050168 -64.341498) (xy 334.071432 -64.341498) (xy 334.081374 -64.337692)
			(xy 334.124036 -64.319447) (xy 334.212329 -64.290903) (xy 334.303114 -64.27171) (xy 334.395404 -64.262077)
			(xy 334.4418 -64.261492) (xy 334.488196 -64.262075) (xy 334.580484 -64.27172) (xy 334.671268 -64.290916)
			(xy 334.759561 -64.319454) (xy 334.802226 -64.337692) (xy 334.812168 -64.341498) (xy 334.833432 -64.341498)
			(xy 334.843374 -64.337692) (xy 334.885977 -64.31947) (xy 334.974144 -64.290952) (xy 335.0648 -64.27176)
			(xy 335.15696 -64.2621) (xy 335.203292 -64.261492) (xy 335.2038 -64.261492) (xy 335.244902 -64.261967)
			(xy 335.326757 -64.269552) (xy 335.407562 -64.284657) (xy 335.486629 -64.307153) (xy 335.563283 -64.336849)
			(xy 335.63687 -64.373491) (xy 335.706762 -64.416766) (xy 335.772363 -64.466306) (xy 335.833113 -64.521687)
			(xy 335.888494 -64.582437) (xy 335.938034 -64.648038) (xy 335.981309 -64.71793) (xy 336.017951 -64.791517)
			(xy 336.047647 -64.868171) (xy 336.070143 -64.947238) (xy 336.085248 -65.028043) (xy 336.092833 -65.109898)
			(xy 336.093308 -65.151) (xy 336.093308 -65.151508) (xy 336.092702 -65.19784) (xy 336.083031 -65.289998)
			(xy 336.063835 -65.380652) (xy 336.035323 -65.468821) (xy 336.017108 -65.511426) (xy 336.013302 -65.521368)
			(xy 336.013302 -65.542632) (xy 336.017108 -65.552574) (xy 336.035353 -65.595236) (xy 336.063897 -65.683529)
			(xy 336.08309 -65.774314) (xy 336.092723 -65.866604) (xy 336.093308 -65.913) (xy 336.092725 -65.959396)
			(xy 336.08308 -66.051684) (xy 336.063884 -66.142468) (xy 336.035346 -66.230761) (xy 336.017108 -66.273426)
			(xy 336.013302 -66.283368) (xy 336.013302 -66.304632) (xy 336.017108 -66.314574) (xy 336.035353 -66.357236)
			(xy 336.063897 -66.445529) (xy 336.08309 -66.536314) (xy 336.092723 -66.628604) (xy 336.093308 -66.675)
			(xy 336.092725 -66.721396) (xy 336.08308 -66.813684) (xy 336.063884 -66.904468) (xy 336.035346 -66.992761)
			(xy 336.017108 -67.035426) (xy 336.013302 -67.045368) (xy 336.013302 -67.066632) (xy 336.017108 -67.076574)
			(xy 336.035353 -67.119236) (xy 336.063897 -67.207529) (xy 336.08309 -67.298314) (xy 336.092723 -67.390604)
			(xy 336.093308 -67.437) (xy 336.092725 -67.483396) (xy 336.08308 -67.575684) (xy 336.063884 -67.666468)
			(xy 336.035346 -67.754761) (xy 336.017108 -67.797426) (xy 336.013302 -67.807368) (xy 336.013302 -67.828632)
			(xy 336.017108 -67.838574) (xy 336.03533 -67.881177) (xy 336.063848 -67.969344) (xy 336.08304 -68.06)
			(xy 336.0927 -68.15216) (xy 336.093308 -68.198492) (xy 336.093308 -68.199) (xy 336.092833 -68.240102)
			(xy 336.085248 -68.321957) (xy 336.070143 -68.402762) (xy 336.047647 -68.481829) (xy 336.017951 -68.558483)
			(xy 335.981309 -68.63207) (xy 335.938034 -68.701962) (xy 335.888494 -68.767563) (xy 335.833113 -68.828313)
			(xy 335.772363 -68.883694) (xy 335.706762 -68.933234) (xy 335.63687 -68.976509) (xy 335.563283 -69.013151)
			(xy 335.486629 -69.042847) (xy 335.407562 -69.065343) (xy 335.326757 -69.080448) (xy 335.244902 -69.088033)
			(xy 335.2038 -69.088508) (xy 335.203292 -69.088508) (xy 335.15696 -69.087902) (xy 335.064802 -69.078231)
			(xy 334.974148 -69.059035) (xy 334.885979 -69.030523) (xy 334.843374 -69.012308) (xy 334.833432 -69.008502)
			(xy 334.812168 -69.008502) (xy 334.802226 -69.012308) (xy 334.759564 -69.030553) (xy 334.671271 -69.059097)
			(xy 334.580486 -69.07829) (xy 334.488196 -69.087923) (xy 334.4418 -69.088508) (xy 334.395404 -69.087925)
			(xy 334.303116 -69.07828) (xy 334.212332 -69.059084) (xy 334.124039 -69.030546) (xy 334.081374 -69.012308)
			(xy 334.071432 -69.008502) (xy 334.050168 -69.008502) (xy 334.040226 -69.012308) (xy 333.997564 -69.030553)
			(xy 333.909271 -69.059097) (xy 333.818486 -69.07829) (xy 333.726196 -69.087923) (xy 333.6798 -69.088508)
			(xy 333.633404 -69.087925) (xy 333.541116 -69.07828) (xy 333.450332 -69.059084) (xy 333.362039 -69.030546)
			(xy 333.319374 -69.012308) (xy 333.309432 -69.008502) (xy 333.288168 -69.008502) (xy 333.278226 -69.012308)
			(xy 333.235564 -69.030553) (xy 333.147271 -69.059097) (xy 333.056486 -69.07829) (xy 332.964196 -69.087923)
			(xy 332.9178 -69.088508) (xy 332.871404 -69.087925) (xy 332.779116 -69.07828) (xy 332.688332 -69.059084)
			(xy 332.600039 -69.030546) (xy 332.557374 -69.012308) (xy 332.547432 -69.008502) (xy 332.526168 -69.008502)
			(xy 332.516226 -69.012308) (xy 332.473623 -69.03053) (xy 332.385456 -69.059048) (xy 332.2948 -69.07824)
			(xy 332.20264 -69.0879) (xy 332.156308 -69.088508) (xy 332.1558 -69.088508) (xy 332.114698 -69.088033)
			(xy 332.032843 -69.080448) (xy 331.952038 -69.065343) (xy 331.872971 -69.042847) (xy 331.796317 -69.013151)
			(xy 331.72273 -68.976509) (xy 331.652838 -68.933234) (xy 331.587237 -68.883694) (xy 331.526487 -68.828313)
			(xy 331.471106 -68.767563) (xy 331.421566 -68.701962) (xy 331.378291 -68.63207) (xy 331.341649 -68.558483)
			(xy 331.311953 -68.481829) (xy 331.289457 -68.402762) (xy 331.274352 -68.321957) (xy 331.266767 -68.240102)
			(xy 331.266292 -68.199) (xy 325.12 -68.199) (xy 325.12 -71.239888) (xy 377.061232 -71.239888) (xy 377.065214 -71.149938)
			(xy 377.077131 -71.060691) (xy 377.096889 -70.972847) (xy 377.124333 -70.887093) (xy 377.159249 -70.8041)
			(xy 377.201363 -70.724518) (xy 377.250346 -70.648969) (xy 377.305814 -70.578045) (xy 377.367334 -70.5123)
			(xy 377.434423 -70.45225) (xy 377.506557 -70.398365) (xy 377.583171 -70.351065) (xy 377.663665 -70.310722)
			(xy 377.74741 -70.27765) (xy 377.833751 -70.25211) (xy 377.92201 -70.2343) (xy 378.011499 -70.22436)
			(xy 378.101515 -70.222369) (xy 378.191356 -70.22834) (xy 378.280317 -70.242229) (xy 378.367702 -70.263925)
			(xy 378.452828 -70.29326) (xy 378.535028 -70.330003) (xy 378.613659 -70.373867) (xy 378.688106 -70.424509)
			(xy 378.757786 -70.481533) (xy 378.822153 -70.544492) (xy 378.880704 -70.612893) (xy 378.932981 -70.686201)
			(xy 378.978574 -70.763843) (xy 379.017127 -70.84521) (xy 379.048338 -70.929666) (xy 379.071962 -71.01655)
			(xy 379.087815 -71.105182) (xy 379.095772 -71.194869) (xy 379.09627 -71.239888) (xy 396.619232 -71.239888)
			(xy 396.623214 -71.149938) (xy 396.635131 -71.060691) (xy 396.654889 -70.972847) (xy 396.682333 -70.887093)
			(xy 396.717249 -70.8041) (xy 396.759363 -70.724518) (xy 396.808346 -70.648969) (xy 396.863814 -70.578045)
			(xy 396.925334 -70.5123) (xy 396.992423 -70.45225) (xy 397.064557 -70.398365) (xy 397.141171 -70.351065)
			(xy 397.221665 -70.310722) (xy 397.30541 -70.27765) (xy 397.391751 -70.25211) (xy 397.48001 -70.2343)
			(xy 397.569499 -70.22436) (xy 397.659515 -70.222369) (xy 397.749356 -70.22834) (xy 397.838317 -70.242229)
			(xy 397.925702 -70.263925) (xy 398.010828 -70.29326) (xy 398.093028 -70.330003) (xy 398.171659 -70.373867)
			(xy 398.246106 -70.424509) (xy 398.315786 -70.481533) (xy 398.380153 -70.544492) (xy 398.438704 -70.612893)
			(xy 398.490981 -70.686201) (xy 398.536574 -70.763843) (xy 398.575127 -70.84521) (xy 398.606338 -70.929666)
			(xy 398.629962 -71.01655) (xy 398.645815 -71.105182) (xy 398.653772 -71.194869) (xy 398.65427 -71.239888)
			(xy 398.653772 -71.284907) (xy 398.645815 -71.374594) (xy 398.629962 -71.463226) (xy 398.606338 -71.55011)
			(xy 398.575127 -71.634566) (xy 398.536574 -71.715933) (xy 398.490981 -71.793575) (xy 398.438704 -71.866883)
			(xy 398.380153 -71.935284) (xy 398.315786 -71.998243) (xy 398.246106 -72.055267) (xy 398.171659 -72.105909)
			(xy 398.093028 -72.149773) (xy 398.010828 -72.186516) (xy 397.925702 -72.215851) (xy 397.838317 -72.237547)
			(xy 397.749356 -72.251436) (xy 397.659515 -72.257407) (xy 397.569499 -72.255416) (xy 397.48001 -72.245476)
			(xy 397.391751 -72.227666) (xy 397.30541 -72.202126) (xy 397.221665 -72.169054) (xy 397.141171 -72.128711)
			(xy 397.064557 -72.081411) (xy 396.992423 -72.027526) (xy 396.925334 -71.967476) (xy 396.863814 -71.901731)
			(xy 396.808346 -71.830807) (xy 396.759363 -71.755258) (xy 396.717249 -71.675676) (xy 396.682333 -71.592683)
			(xy 396.654889 -71.506929) (xy 396.635131 -71.419085) (xy 396.623214 -71.329838) (xy 396.619232 -71.239888)
			(xy 379.09627 -71.239888) (xy 379.095772 -71.284907) (xy 379.087815 -71.374594) (xy 379.071962 -71.463226)
			(xy 379.048338 -71.55011) (xy 379.017127 -71.634566) (xy 378.978574 -71.715933) (xy 378.932981 -71.793575)
			(xy 378.880704 -71.866883) (xy 378.822153 -71.935284) (xy 378.757786 -71.998243) (xy 378.688106 -72.055267)
			(xy 378.613659 -72.105909) (xy 378.535028 -72.149773) (xy 378.452828 -72.186516) (xy 378.367702 -72.215851)
			(xy 378.280317 -72.237547) (xy 378.191356 -72.251436) (xy 378.101515 -72.257407) (xy 378.011499 -72.255416)
			(xy 377.92201 -72.245476) (xy 377.833751 -72.227666) (xy 377.74741 -72.202126) (xy 377.663665 -72.169054)
			(xy 377.583171 -72.128711) (xy 377.506557 -72.081411) (xy 377.434423 -72.027526) (xy 377.367334 -71.967476)
			(xy 377.305814 -71.901731) (xy 377.250346 -71.830807) (xy 377.201363 -71.755258) (xy 377.159249 -71.675676)
			(xy 377.124333 -71.592683) (xy 377.096889 -71.506929) (xy 377.077131 -71.419085) (xy 377.065214 -71.329838)
			(xy 377.061232 -71.239888) (xy 325.12 -71.239888) (xy 325.12 -73.676961) (xy 334.478626 -73.676961)
			(xy 334.478626 -73.592239) (xy 334.486679 -73.507902) (xy 334.502713 -73.424712) (xy 334.526581 -73.343422)
			(xy 334.558069 -73.26477) (xy 334.596891 -73.189467) (xy 334.642694 -73.118195) (xy 334.695065 -73.051599)
			(xy 334.75353 -72.990284) (xy 334.817558 -72.934803) (xy 334.88657 -72.88566) (xy 334.95994 -72.8433)
			(xy 335.037005 -72.808105) (xy 335.117067 -72.780396) (xy 335.1994 -72.760422) (xy 335.283259 -72.748365)
			(xy 335.367884 -72.744334) (xy 335.452509 -72.748365) (xy 335.536368 -72.760422) (xy 335.618701 -72.780396)
			(xy 335.698763 -72.808105) (xy 335.775828 -72.8433) (xy 335.849198 -72.88566) (xy 335.91821 -72.934803)
			(xy 335.982238 -72.990284) (xy 336.040703 -73.051599) (xy 336.093074 -73.118195) (xy 336.138877 -73.189467)
			(xy 336.177699 -73.26477) (xy 336.209187 -73.343422) (xy 336.233055 -73.424712) (xy 336.249089 -73.507902)
			(xy 336.257142 -73.592239) (xy 336.257646 -73.6346) (xy 336.257142 -73.676961) (xy 336.249089 -73.761298)
			(xy 336.233055 -73.844488) (xy 336.209187 -73.925778) (xy 336.177699 -74.00443) (xy 336.138877 -74.079733)
			(xy 336.093074 -74.151005) (xy 336.040703 -74.217601) (xy 335.982238 -74.278916) (xy 335.91821 -74.334397)
			(xy 335.849198 -74.38354) (xy 335.775828 -74.4259) (xy 335.698763 -74.461095) (xy 335.618701 -74.488804)
			(xy 335.536368 -74.508778) (xy 335.452509 -74.520835) (xy 335.367884 -74.524867) (xy 335.283259 -74.520835)
			(xy 335.1994 -74.508778) (xy 335.117067 -74.488804) (xy 335.037005 -74.461095) (xy 334.95994 -74.4259)
			(xy 334.88657 -74.38354) (xy 334.817558 -74.334397) (xy 334.75353 -74.278916) (xy 334.695065 -74.217601)
			(xy 334.642694 -74.151005) (xy 334.596891 -74.079733) (xy 334.558069 -74.00443) (xy 334.526581 -73.925778)
			(xy 334.502713 -73.844488) (xy 334.486679 -73.761298) (xy 334.478626 -73.676961) (xy 325.12 -73.676961)
			(xy 325.12 -79.4766) (xy 331.266292 -79.4766) (xy 331.266292 -79.476092) (xy 331.266898 -79.42976)
			(xy 331.276569 -79.337602) (xy 331.295765 -79.246948) (xy 331.324277 -79.158779) (xy 331.342492 -79.116174)
			(xy 331.346298 -79.106232) (xy 331.346298 -79.084968) (xy 331.342492 -79.075026) (xy 331.324247 -79.032364)
			(xy 331.295703 -78.944071) (xy 331.27651 -78.853286) (xy 331.266877 -78.760996) (xy 331.266292 -78.7146)
			(xy 331.266875 -78.668204) (xy 331.27652 -78.575916) (xy 331.295716 -78.485132) (xy 331.324254 -78.396839)
			(xy 331.342492 -78.354174) (xy 331.346298 -78.344232) (xy 331.346298 -78.322968) (xy 331.342492 -78.313026)
			(xy 331.324247 -78.270364) (xy 331.295703 -78.182071) (xy 331.27651 -78.091286) (xy 331.266877 -77.998996)
			(xy 331.266292 -77.9526) (xy 331.266875 -77.906204) (xy 331.27652 -77.813916) (xy 331.295716 -77.723132)
			(xy 331.324254 -77.634839) (xy 331.342492 -77.592174) (xy 331.346298 -77.582232) (xy 331.346298 -77.560968)
			(xy 331.342492 -77.551026) (xy 331.324247 -77.508364) (xy 331.295703 -77.420071) (xy 331.27651 -77.329286)
			(xy 331.266877 -77.236996) (xy 331.266292 -77.1906) (xy 331.266875 -77.144204) (xy 331.27652 -77.051916)
			(xy 331.295716 -76.961132) (xy 331.324254 -76.872839) (xy 331.342492 -76.830174) (xy 331.346298 -76.820232)
			(xy 331.346298 -76.798968) (xy 331.342492 -76.789026) (xy 331.32427 -76.746423) (xy 331.295752 -76.658256)
			(xy 331.27656 -76.5676) (xy 331.2669 -76.47544) (xy 331.266292 -76.429108) (xy 331.266292 -76.4286)
			(xy 331.266767 -76.387498) (xy 331.274352 -76.305643) (xy 331.289457 -76.224838) (xy 331.311953 -76.145771)
			(xy 331.341649 -76.069117) (xy 331.378291 -75.99553) (xy 331.421566 -75.925638) (xy 331.471106 -75.860037)
			(xy 331.526487 -75.799287) (xy 331.587237 -75.743906) (xy 331.652838 -75.694366) (xy 331.72273 -75.651091)
			(xy 331.796317 -75.614449) (xy 331.872971 -75.584753) (xy 331.952038 -75.562257) (xy 332.032843 -75.547152)
			(xy 332.114698 -75.539567) (xy 332.1558 -75.539092) (xy 332.156308 -75.539092) (xy 332.20264 -75.539698)
			(xy 332.294798 -75.549369) (xy 332.385452 -75.568565) (xy 332.473621 -75.597077) (xy 332.516226 -75.615292)
			(xy 332.526168 -75.619098) (xy 332.547432 -75.619098) (xy 332.557374 -75.615292) (xy 332.600036 -75.597047)
			(xy 332.688329 -75.568503) (xy 332.779114 -75.54931) (xy 332.871404 -75.539677) (xy 332.9178 -75.539092)
			(xy 332.964196 -75.539675) (xy 333.056484 -75.54932) (xy 333.147268 -75.568516) (xy 333.235561 -75.597054)
			(xy 333.278226 -75.615292) (xy 333.288168 -75.619098) (xy 333.309432 -75.619098) (xy 333.319374 -75.615292)
			(xy 333.362036 -75.597047) (xy 333.450329 -75.568503) (xy 333.541114 -75.54931) (xy 333.633404 -75.539677)
			(xy 333.6798 -75.539092) (xy 333.726196 -75.539675) (xy 333.818484 -75.54932) (xy 333.909268 -75.568516)
			(xy 333.997561 -75.597054) (xy 334.040226 -75.615292) (xy 334.050168 -75.619098) (xy 334.071432 -75.619098)
			(xy 334.081374 -75.615292) (xy 334.124036 -75.597047) (xy 334.212329 -75.568503) (xy 334.303114 -75.54931)
			(xy 334.395404 -75.539677) (xy 334.4418 -75.539092) (xy 334.488196 -75.539675) (xy 334.580484 -75.54932)
			(xy 334.671268 -75.568516) (xy 334.759561 -75.597054) (xy 334.802226 -75.615292) (xy 334.812168 -75.619098)
			(xy 334.833432 -75.619098) (xy 334.843374 -75.615292) (xy 334.885977 -75.59707) (xy 334.974144 -75.568552)
			(xy 335.0648 -75.54936) (xy 335.15696 -75.5397) (xy 335.203292 -75.539092) (xy 335.2038 -75.539092)
			(xy 335.244902 -75.539567) (xy 335.326757 -75.547152) (xy 335.407562 -75.562257) (xy 335.486629 -75.584753)
			(xy 335.563283 -75.614449) (xy 335.63687 -75.651091) (xy 335.706762 -75.694366) (xy 335.772363 -75.743906)
			(xy 335.833113 -75.799287) (xy 335.888494 -75.860037) (xy 335.938034 -75.925638) (xy 335.981309 -75.99553)
			(xy 336.017951 -76.069117) (xy 336.047647 -76.145771) (xy 336.070143 -76.224838) (xy 336.085248 -76.305643)
			(xy 336.085697 -76.31049) (xy 467.50986 -76.31049) (xy 467.50986 -76.309982) (xy 467.510348 -76.255884)
			(xy 467.518633 -76.148004) (xy 467.53516 -76.041077) (xy 467.559833 -75.935731) (xy 467.592506 -75.832585)
			(xy 467.632987 -75.732246) (xy 467.681038 -75.635305) (xy 467.736376 -75.54233) (xy 467.798677 -75.45387)
			(xy 467.867573 -75.370444) (xy 467.942659 -75.292543) (xy 468.023495 -75.220625) (xy 468.109603 -75.155112)
			(xy 468.154766 -75.125326) (xy 468.165688 -75.118214) (xy 468.178134 -75.095608) (xy 468.178134 -74.984356)
			(xy 468.165688 -74.96175) (xy 468.154766 -74.954638) (xy 468.109587 -74.924876) (xy 468.023479 -74.85936)
			(xy 467.942644 -74.787439) (xy 467.867558 -74.709536) (xy 467.798662 -74.626108) (xy 467.736361 -74.537647)
			(xy 467.681021 -74.444672) (xy 467.632969 -74.347729) (xy 467.592485 -74.24739) (xy 467.559809 -74.144244)
			(xy 467.535133 -74.038897) (xy 467.518601 -73.93197) (xy 467.510312 -73.824089) (xy 467.510312 -73.715891)
			(xy 467.518604 -73.608011) (xy 467.535137 -73.501083) (xy 467.559815 -73.395737) (xy 467.592492 -73.292591)
			(xy 467.632977 -73.192253) (xy 467.681031 -73.095311) (xy 467.736372 -73.002337) (xy 467.798674 -72.913876)
			(xy 467.867571 -72.830449) (xy 467.942659 -72.752547) (xy 468.023494 -72.680628) (xy 468.109603 -72.615113)
			(xy 468.154766 -72.585326) (xy 468.165688 -72.578214) (xy 468.178134 -72.555608) (xy 468.178134 -72.444356)
			(xy 468.165688 -72.42175) (xy 468.154766 -72.414638) (xy 468.109587 -72.384876) (xy 468.023479 -72.31936)
			(xy 467.942644 -72.247439) (xy 467.867558 -72.169536) (xy 467.798662 -72.086108) (xy 467.736361 -71.997647)
			(xy 467.681021 -71.904672) (xy 467.632969 -71.807729) (xy 467.592485 -71.70739) (xy 467.559809 -71.604244)
			(xy 467.535133 -71.498897) (xy 467.518601 -71.39197) (xy 467.510312 -71.284089) (xy 467.510312 -71.175891)
			(xy 467.518604 -71.068011) (xy 467.535137 -70.961083) (xy 467.559815 -70.855737) (xy 467.592492 -70.752591)
			(xy 467.632977 -70.652253) (xy 467.681031 -70.555311) (xy 467.736372 -70.462337) (xy 467.798674 -70.373876)
			(xy 467.867571 -70.290449) (xy 467.942659 -70.212547) (xy 468.023494 -70.140628) (xy 468.109603 -70.075113)
			(xy 468.154766 -70.045326) (xy 468.165688 -70.038214) (xy 468.178134 -70.015608) (xy 468.178134 -69.904356)
			(xy 468.165688 -69.88175) (xy 468.154766 -69.874638) (xy 468.109595 -69.844866) (xy 468.023492 -69.779347)
			(xy 467.942663 -69.707424) (xy 467.867582 -69.629519) (xy 467.798691 -69.54609) (xy 467.736395 -69.457628)
			(xy 467.681059 -69.364653) (xy 467.633011 -69.267711) (xy 467.592531 -69.167373) (xy 467.559858 -69.064228)
			(xy 467.535184 -68.958884) (xy 467.518654 -68.851958) (xy 467.510366 -68.74408) (xy 467.50986 -68.689982)
			(xy 467.510314 -68.63723) (xy 467.518198 -68.532021) (xy 467.533923 -68.427695) (xy 467.557398 -68.324836)
			(xy 467.588494 -68.224019) (xy 467.627036 -68.125806) (xy 467.672809 -68.030749) (xy 467.725557 -67.939377)
			(xy 467.784984 -67.852202) (xy 467.85076 -67.769712) (xy 467.922515 -67.692367) (xy 467.99985 -67.6206)
			(xy 468.08233 -67.554812) (xy 468.169496 -67.495371) (xy 468.26086 -67.442609) (xy 468.35591 -67.396822)
			(xy 468.454117 -67.358265) (xy 468.554929 -67.327154) (xy 468.657785 -67.303662) (xy 468.762108 -67.287922)
			(xy 468.867316 -67.280022) (xy 468.920068 -67.27952) (xy 468.971968 -67.279989) (xy 469.075487 -67.287612)
			(xy 469.178165 -67.302827) (xy 469.279447 -67.325552) (xy 469.378783 -67.355664) (xy 469.475635 -67.392998)
			(xy 469.56948 -67.437354) (xy 469.659809 -67.488491) (xy 469.746133 -67.546132) (xy 469.827985 -67.609965)
			(xy 469.904921 -67.679645) (xy 469.976524 -67.754793) (xy 470.042407 -67.835004) (xy 470.102214 -67.919842)
			(xy 470.15562 -68.008849) (xy 470.1794 -68.054982) (xy 470.18575 -68.067936) (xy 470.210134 -68.082922)
			(xy 470.330022 -68.082922) (xy 470.354406 -68.067936) (xy 470.360756 -68.054982) (xy 470.38451 -68.008836)
			(xy 470.437926 -67.919837) (xy 470.497742 -67.835006) (xy 470.563632 -67.754803) (xy 470.635241 -67.679661)
			(xy 470.71218 -67.609987) (xy 470.794033 -67.546158) (xy 470.880358 -67.48852) (xy 470.970687 -67.437385)
			(xy 471.064531 -67.393029) (xy 471.161382 -67.355693) (xy 471.260716 -67.325578) (xy 471.361995 -67.302848)
			(xy 471.464671 -67.287626) (xy 471.568189 -67.279993) (xy 471.620088 -67.27952) (xy 471.67283 -67.279996)
			(xy 471.77802 -67.287878) (xy 471.882327 -67.303597) (xy 471.985167 -67.327066) (xy 472.085967 -67.358155)
			(xy 472.184161 -67.396688) (xy 472.279202 -67.442451) (xy 472.370557 -67.495188) (xy 472.457717 -67.554604)
			(xy 472.540193 -67.620366) (xy 472.617524 -67.692108) (xy 472.689278 -67.769427) (xy 472.755055 -67.851892)
			(xy 472.814485 -67.939041) (xy 472.867238 -68.030388) (xy 472.913017 -68.125421) (xy 472.951567 -68.223609)
			(xy 472.982672 -68.324403) (xy 473.006159 -68.427239) (xy 473.021896 -68.531543) (xy 473.029795 -68.636732)
			(xy 473.030296 -68.689474) (xy 473.030296 -68.689982) (xy 473.029754 -68.744079) (xy 473.021472 -68.851956)
			(xy 473.004948 -68.958882) (xy 472.980279 -69.064227) (xy 472.94761 -69.167371) (xy 472.907133 -69.267709)
			(xy 472.859087 -69.36465) (xy 472.803753 -69.457625) (xy 472.741457 -69.546085) (xy 472.672566 -69.629512)
			(xy 472.597485 -69.707415) (xy 472.516654 -69.779335) (xy 472.43055 -69.84485) (xy 472.38539 -69.874638)
			(xy 472.374468 -69.88175) (xy 472.362022 -69.904356) (xy 472.362022 -70.015608) (xy 472.374468 -70.038214)
			(xy 472.38539 -70.045326) (xy 472.430534 -70.075139) (xy 472.516638 -70.140654) (xy 472.597469 -70.212573)
			(xy 472.672552 -70.290475) (xy 472.741445 -70.373901) (xy 472.803743 -70.462359) (xy 472.859081 -70.555332)
			(xy 472.907132 -70.652271) (xy 472.947614 -70.752607) (xy 472.980289 -70.855749) (xy 473.004965 -70.961092)
			(xy 473.021497 -71.068016) (xy 473.029788 -71.175893) (xy 473.029789 -71.284088) (xy 473.021499 -71.391964)
			(xy 473.004969 -71.498888) (xy 472.980294 -71.604232) (xy 472.94762 -71.707375) (xy 472.90714 -71.807711)
			(xy 472.85909 -71.904651) (xy 472.803754 -71.997624) (xy 472.741457 -72.086084) (xy 472.672565 -72.16951)
			(xy 472.597483 -72.247413) (xy 472.516653 -72.319334) (xy 472.43055 -72.38485) (xy 472.38539 -72.414638)
			(xy 472.374468 -72.42175) (xy 472.362022 -72.444356) (xy 472.362022 -72.555608) (xy 472.374468 -72.578214)
			(xy 472.38539 -72.585326) (xy 472.430534 -72.615139) (xy 472.516638 -72.680654) (xy 472.597469 -72.752573)
			(xy 472.672552 -72.830475) (xy 472.741445 -72.913901) (xy 472.803743 -73.002359) (xy 472.859081 -73.095332)
			(xy 472.907132 -73.192271) (xy 472.947614 -73.292607) (xy 472.980289 -73.395749) (xy 473.004965 -73.501092)
			(xy 473.021497 -73.608016) (xy 473.029788 -73.715893) (xy 473.029789 -73.824088) (xy 473.021499 -73.931964)
			(xy 473.004969 -74.038888) (xy 472.980294 -74.144232) (xy 472.94762 -74.247375) (xy 472.90714 -74.347711)
			(xy 472.85909 -74.444651) (xy 472.803754 -74.537624) (xy 472.741457 -74.626084) (xy 472.672565 -74.70951)
			(xy 472.597483 -74.787413) (xy 472.516653 -74.859334) (xy 472.43055 -74.92485) (xy 472.38539 -74.954638)
			(xy 472.374468 -74.96175) (xy 472.362022 -74.984356) (xy 472.362022 -75.095608) (xy 472.374468 -75.118214)
			(xy 472.38539 -75.125326) (xy 472.430558 -75.155102) (xy 472.516659 -75.220622) (xy 472.597487 -75.292546)
			(xy 472.672567 -75.370452) (xy 472.741457 -75.45388) (xy 472.803753 -75.542342) (xy 472.859088 -75.635317)
			(xy 472.907137 -75.732257) (xy 472.947617 -75.832595) (xy 472.980291 -75.935738) (xy 473.004966 -76.041082)
			(xy 473.021498 -76.148007) (xy 473.029789 -76.255884) (xy 473.030296 -76.309982) (xy 473.029752 -76.362732)
			(xy 473.02187 -76.467938) (xy 473.006149 -76.57226) (xy 472.982677 -76.675117) (xy 472.951585 -76.775931)
			(xy 472.913048 -76.874141) (xy 472.867279 -76.969197) (xy 472.814536 -77.060567) (xy 472.755113 -77.147741)
			(xy 472.689342 -77.230231) (xy 472.617592 -77.307575) (xy 472.540263 -77.379343) (xy 472.457787 -77.445131)
			(xy 472.370626 -77.504573) (xy 472.279268 -77.557336) (xy 472.184222 -77.603125) (xy 472.08602 -77.641684)
			(xy 471.985212 -77.672798) (xy 471.882361 -77.696292) (xy 471.778042 -77.712036) (xy 471.672838 -77.71994)
			(xy 471.620088 -77.720444) (xy 471.568188 -77.719978) (xy 471.46467 -77.712352) (xy 471.361992 -77.697134)
			(xy 471.260712 -77.674407) (xy 471.161377 -77.644294) (xy 471.064525 -77.606959) (xy 470.970681 -77.562602)
			(xy 470.880352 -77.511465) (xy 470.794028 -77.453824) (xy 470.712177 -77.389992) (xy 470.635241 -77.320313)
			(xy 470.563637 -77.245166) (xy 470.497753 -77.164956) (xy 470.437945 -77.08012) (xy 470.384537 -76.991115)
			(xy 470.360756 -76.944982) (xy 470.354406 -76.932028) (xy 470.330022 -76.917042) (xy 470.210134 -76.917042)
			(xy 470.18575 -76.932028) (xy 470.1794 -76.944982) (xy 470.155586 -76.991097) (xy 470.102175 -77.080095)
			(xy 470.042364 -77.164927) (xy 469.976479 -77.245131) (xy 469.904875 -77.320274) (xy 469.827941 -77.389949)
			(xy 469.746092 -77.45378) (xy 469.659771 -77.51142) (xy 469.569447 -77.562557) (xy 469.475607 -77.606916)
			(xy 469.37876 -77.644255) (xy 469.279429 -77.674373) (xy 469.178154 -77.697106) (xy 469.075481 -77.712332)
			(xy 468.971966 -77.719969) (xy 468.920068 -77.720444) (xy 468.867327 -77.719946) (xy 468.762139 -77.712062)
			(xy 468.657834 -77.696341) (xy 468.554996 -77.67287) (xy 468.454199 -77.64178) (xy 468.356007 -77.603246)
			(xy 468.260968 -77.557483) (xy 468.169615 -77.504746) (xy 468.082457 -77.445331) (xy 467.999982 -77.37957)
			(xy 467.922652 -77.30783) (xy 467.850898 -77.230513) (xy 467.785122 -77.148051) (xy 467.725691 -77.060904)
			(xy 467.672938 -76.96956) (xy 467.627157 -76.87453) (xy 467.588605 -76.776344) (xy 467.557497 -76.675553)
			(xy 467.534007 -76.572719) (xy 467.518267 -76.468417) (xy 467.510364 -76.363231) (xy 467.50986 -76.31049)
			(xy 336.085697 -76.31049) (xy 336.092833 -76.387498) (xy 336.093308 -76.4286) (xy 336.093308 -76.429108)
			(xy 336.092702 -76.47544) (xy 336.083031 -76.567598) (xy 336.063835 -76.658252) (xy 336.035323 -76.746421)
			(xy 336.017108 -76.789026) (xy 336.013302 -76.798968) (xy 336.013302 -76.820232) (xy 336.017108 -76.830174)
			(xy 336.03533 -76.872777) (xy 336.063848 -76.960944) (xy 336.08304 -77.0516) (xy 336.0927 -77.14376)
			(xy 336.093308 -77.190092) (xy 336.093308 -77.1906) (xy 336.09286 -77.231986) (xy 336.085163 -77.314401)
			(xy 336.069847 -77.395744) (xy 336.047042 -77.475313) (xy 336.016946 -77.552421) (xy 335.97982 -77.6264)
			(xy 335.935983 -77.696612) (xy 335.885816 -77.76245) (xy 335.829751 -77.823344) (xy 335.768274 -77.878768)
			(xy 335.701914 -77.928243) (xy 335.631247 -77.971342) (xy 335.556883 -78.007691) (xy 335.479465 -78.036978)
			(xy 335.399661 -78.058948) (xy 335.358994 -78.066646) (xy 335.34887 -78.068944) (xy 335.331549 -78.080349)
			(xy 335.320144 -78.09767) (xy 335.317846 -78.107794) (xy 335.310093 -78.14883) (xy 335.287881 -78.229342)
			(xy 335.258222 -78.307417) (xy 335.221376 -78.382369) (xy 335.177667 -78.453538) (xy 335.127482 -78.520298)
			(xy 335.07126 -78.58206) (xy 335.009498 -78.638282) (xy 334.942738 -78.688467) (xy 334.871569 -78.732176)
			(xy 334.855653 -78.74) (xy 376.553741 -78.74) (xy 376.557716 -78.629941) (xy 376.569624 -78.520455)
			(xy 376.5894 -78.412114) (xy 376.616943 -78.305483) (xy 376.652108 -78.201117) (xy 376.694712 -78.09956)
			(xy 376.744533 -78.001343) (xy 376.801312 -77.906976) (xy 376.864751 -77.816952) (xy 376.934522 -77.731741)
			(xy 377.010259 -77.651786) (xy 377.091568 -77.577505) (xy 377.178025 -77.509285) (xy 377.269179 -77.44748)
			(xy 377.364556 -77.392415) (xy 377.463657 -77.344375) (xy 377.565966 -77.303611) (xy 377.67095 -77.270336)
			(xy 377.778061 -77.244723) (xy 377.886741 -77.226906) (xy 377.996424 -77.216977) (xy 378.106537 -77.214989)
			(xy 378.216507 -77.220951) (xy 378.32576 -77.234833) (xy 378.433726 -77.256563) (xy 378.539843 -77.286026)
			(xy 378.643557 -77.323069) (xy 378.744328 -77.3675) (xy 378.84163 -77.419087) (xy 378.934956 -77.477559)
			(xy 379.023819 -77.542614) (xy 379.107757 -77.613912) (xy 379.186332 -77.69108) (xy 379.259133 -77.773717)
			(xy 379.325781 -77.861391) (xy 379.38593 -77.953647) (xy 379.439264 -78.050002) (xy 379.485507 -78.149954)
			(xy 379.524417 -78.252982) (xy 379.555791 -78.35855) (xy 379.579466 -78.466106) (xy 379.595318 -78.57509)
			(xy 379.603265 -78.684934) (xy 379.603762 -78.74) (xy 396.111741 -78.74) (xy 396.115716 -78.629941)
			(xy 396.127624 -78.520455) (xy 396.1474 -78.412114) (xy 396.174943 -78.305483) (xy 396.210108 -78.201117)
			(xy 396.252712 -78.09956) (xy 396.302533 -78.001343) (xy 396.359312 -77.906976) (xy 396.422751 -77.816952)
			(xy 396.492522 -77.731741) (xy 396.568259 -77.651786) (xy 396.649568 -77.577505) (xy 396.736025 -77.509285)
			(xy 396.827179 -77.44748) (xy 396.922556 -77.392415) (xy 397.021657 -77.344375) (xy 397.123966 -77.303611)
			(xy 397.22895 -77.270336) (xy 397.336061 -77.244723) (xy 397.444741 -77.226906) (xy 397.554424 -77.216977)
			(xy 397.664537 -77.214989) (xy 397.774507 -77.220951) (xy 397.88376 -77.234833) (xy 397.991726 -77.256563)
			(xy 398.097843 -77.286026) (xy 398.201557 -77.323069) (xy 398.302328 -77.3675) (xy 398.39963 -77.419087)
			(xy 398.492956 -77.477559) (xy 398.581819 -77.542614) (xy 398.665757 -77.613912) (xy 398.744332 -77.69108)
			(xy 398.817133 -77.773717) (xy 398.883781 -77.861391) (xy 398.94393 -77.953647) (xy 398.997264 -78.050002)
			(xy 399.043507 -78.149954) (xy 399.082417 -78.252982) (xy 399.113791 -78.35855) (xy 399.137466 -78.466106)
			(xy 399.153318 -78.57509) (xy 399.161265 -78.684934) (xy 399.161762 -78.74) (xy 399.161265 -78.795066)
			(xy 399.153318 -78.90491) (xy 399.137466 -79.013894) (xy 399.113791 -79.12145) (xy 399.082417 -79.227018)
			(xy 399.043507 -79.330046) (xy 398.997264 -79.429998) (xy 398.94393 -79.526353) (xy 398.883781 -79.618609)
			(xy 398.817133 -79.706283) (xy 398.744332 -79.78892) (xy 398.665757 -79.866088) (xy 398.581819 -79.937386)
			(xy 398.492956 -80.002441) (xy 398.39963 -80.060913) (xy 398.302328 -80.1125) (xy 398.201557 -80.156931)
			(xy 398.097843 -80.193974) (xy 397.991726 -80.223437) (xy 397.88376 -80.245167) (xy 397.774507 -80.259049)
			(xy 397.664537 -80.265011) (xy 397.554424 -80.263023) (xy 397.444741 -80.253094) (xy 397.336061 -80.235277)
			(xy 397.22895 -80.209664) (xy 397.123966 -80.176389) (xy 397.021657 -80.135625) (xy 396.922556 -80.087585)
			(xy 396.827179 -80.03252) (xy 396.736025 -79.970715) (xy 396.649568 -79.902495) (xy 396.568259 -79.828214)
			(xy 396.492522 -79.748259) (xy 396.422751 -79.663048) (xy 396.359312 -79.573024) (xy 396.302533 -79.478657)
			(xy 396.252712 -79.38044) (xy 396.210108 -79.278883) (xy 396.174943 -79.174517) (xy 396.1474 -79.067886)
			(xy 396.127624 -78.959545) (xy 396.115716 -78.850059) (xy 396.111741 -78.74) (xy 379.603762 -78.74)
			(xy 379.603265 -78.795066) (xy 379.595318 -78.90491) (xy 379.579466 -79.013894) (xy 379.555791 -79.12145)
			(xy 379.524417 -79.227018) (xy 379.485507 -79.330046) (xy 379.439264 -79.429998) (xy 379.38593 -79.526353)
			(xy 379.325781 -79.618609) (xy 379.259133 -79.706283) (xy 379.186332 -79.78892) (xy 379.107757 -79.866088)
			(xy 379.023819 -79.937386) (xy 378.934956 -80.002441) (xy 378.84163 -80.060913) (xy 378.744328 -80.1125)
			(xy 378.643557 -80.156931) (xy 378.539843 -80.193974) (xy 378.433726 -80.223437) (xy 378.32576 -80.245167)
			(xy 378.216507 -80.259049) (xy 378.106537 -80.265011) (xy 377.996424 -80.263023) (xy 377.886741 -80.253094)
			(xy 377.778061 -80.235277) (xy 377.67095 -80.209664) (xy 377.565966 -80.176389) (xy 377.463657 -80.135625)
			(xy 377.364556 -80.087585) (xy 377.269179 -80.03252) (xy 377.178025 -79.970715) (xy 377.091568 -79.902495)
			(xy 377.010259 -79.828214) (xy 376.934522 -79.748259) (xy 376.864751 -79.663048) (xy 376.801312 -79.573024)
			(xy 376.744533 -79.478657) (xy 376.694712 -79.38044) (xy 376.652108 -79.278883) (xy 376.616943 -79.174517)
			(xy 376.5894 -79.067886) (xy 376.569624 -78.959545) (xy 376.557716 -78.850059) (xy 376.553741 -78.74)
			(xy 334.855653 -78.74) (xy 334.796617 -78.769022) (xy 334.718542 -78.798681) (xy 334.63803 -78.820893)
			(xy 334.596994 -78.828646) (xy 334.58687 -78.830944) (xy 334.569549 -78.842349) (xy 334.558144 -78.85967)
			(xy 334.555846 -78.869794) (xy 334.548093 -78.91083) (xy 334.525881 -78.991342) (xy 334.496222 -79.069417)
			(xy 334.459376 -79.144369) (xy 334.415667 -79.215538) (xy 334.365482 -79.282298) (xy 334.30926 -79.34406)
			(xy 334.247498 -79.400282) (xy 334.180738 -79.450467) (xy 334.109569 -79.494176) (xy 334.034617 -79.531022)
			(xy 333.956542 -79.560681) (xy 333.87603 -79.582893) (xy 333.834994 -79.590646) (xy 333.82487 -79.592944)
			(xy 333.807549 -79.604349) (xy 333.796144 -79.62167) (xy 333.793846 -79.631794) (xy 333.786139 -79.672459)
			(xy 333.764175 -79.752265) (xy 333.734893 -79.829685) (xy 333.698547 -79.904051) (xy 333.655451 -79.97472)
			(xy 333.605977 -80.04108) (xy 333.550554 -80.102559) (xy 333.489659 -80.158623) (xy 333.423821 -80.208789)
			(xy 333.353608 -80.252624) (xy 333.279627 -80.289747) (xy 333.202517 -80.319838) (xy 333.122946 -80.342637)
			(xy 333.041601 -80.357947) (xy 332.959186 -80.365635) (xy 332.9178 -80.366108) (xy 332.917292 -80.366108)
			(xy 332.87096 -80.365502) (xy 332.778802 -80.355831) (xy 332.688148 -80.336635) (xy 332.599979 -80.308123)
			(xy 332.557374 -80.289908) (xy 332.547432 -80.286102) (xy 332.526168 -80.286102) (xy 332.516226 -80.289908)
			(xy 332.473623 -80.30813) (xy 332.385456 -80.336648) (xy 332.2948 -80.35584) (xy 332.20264 -80.3655)
			(xy 332.156308 -80.366108) (xy 332.1558 -80.366108) (xy 332.114698 -80.365633) (xy 332.032843 -80.358048)
			(xy 331.952038 -80.342943) (xy 331.872971 -80.320447) (xy 331.796317 -80.290751) (xy 331.72273 -80.254109)
			(xy 331.652838 -80.210834) (xy 331.587237 -80.161294) (xy 331.526487 -80.105913) (xy 331.471106 -80.045163)
			(xy 331.421566 -79.979562) (xy 331.378291 -79.90967) (xy 331.341649 -79.836083) (xy 331.311953 -79.759429)
			(xy 331.289457 -79.680362) (xy 331.274352 -79.599557) (xy 331.266767 -79.517702) (xy 331.266292 -79.4766)
			(xy 325.12 -79.4766) (xy 325.12 -79.883) (xy 325.119461 -79.916259) (xy 325.110775 -79.982209) (xy 325.093553 -80.04646)
			(xy 325.068089 -80.107911) (xy 325.034818 -80.165512) (xy 324.994312 -80.218276) (xy 324.971156 -80.242156)
			(xy 324.336156 -80.877156) (xy 324.312271 -80.900308) (xy 324.259511 -80.940821) (xy 324.201912 -80.974097)
			(xy 324.140461 -80.999566) (xy 324.07621 -81.016791) (xy 324.01026 -81.025479) (xy 323.977 -81.026)
			(xy 311.395364 -81.026) (xy 311.362104 -81.025484) (xy 311.296153 -81.016794) (xy 311.231902 -80.999567)
			(xy 311.17045 -80.974099) (xy 311.11285 -80.940824) (xy 311.060087 -80.900314) (xy 311.036208 -80.877156)
			(xy 310.362854 -80.203802) (xy 310.339678 -80.179939) (xy 310.299167 -80.127175) (xy 310.265894 -80.069571)
			(xy 310.240429 -80.008116) (xy 310.223209 -79.943861) (xy 310.214528 -79.877907) (xy 310.21401 -79.844646)
			(xy 310.21401 -68.489322) (xy 310.213597 -68.479251) (xy 310.20587 -68.460652) (xy 310.199024 -68.453254)
			(xy 309.613046 -67.867276) (xy 309.605627 -67.86046) (xy 309.587042 -67.852727) (xy 309.576978 -67.85229)
			(xy 308.297834 -67.85229) (xy 308.288617 -67.852597) (xy 308.27136 -67.859068) (xy 308.25753 -67.87125)
			(xy 308.252876 -67.879214) (xy 308.23281 -67.915996) (xy 308.186744 -67.985991) (xy 308.134301 -68.051344)
			(xy 308.075945 -68.111477) (xy 308.012194 -68.165856) (xy 307.943612 -68.214001) (xy 307.870808 -68.255483)
			(xy 307.794425 -68.289937) (xy 307.715142 -68.317056) (xy 307.633659 -68.3366) (xy 307.550701 -68.348396)
			(xy 307.467 -68.35234) (xy 307.383299 -68.348396) (xy 307.300341 -68.3366) (xy 307.218858 -68.317056)
			(xy 307.139575 -68.289937) (xy 307.063192 -68.255483) (xy 306.990388 -68.214001) (xy 306.921806 -68.165856)
			(xy 306.858055 -68.111477) (xy 306.799699 -68.051344) (xy 306.747256 -67.985991) (xy 306.70119 -67.915996)
			(xy 306.681124 -67.879214) (xy 306.676465 -67.87127) (xy 306.6626 -67.859162) (xy 306.645369 -67.852685)
			(xy 306.636166 -67.85229) (xy 305.487578 -67.85229) (xy 305.476114 -67.85278) (xy 305.455445 -67.862699)
			(xy 305.44113 -67.880606) (xy 305.438048 -67.89166) (xy 305.428779 -67.929708) (xy 305.404431 -68.004145)
			(xy 305.37363 -68.076151) (xy 305.355498 -68.110862) (xy 305.350086 -68.12233) (xy 305.350082 -68.147656)
			(xy 305.355498 -68.159122) (xy 305.375775 -68.198007) (xy 305.409465 -68.27898) (xy 305.43503 -68.362874)
			(xy 305.452222 -68.448875) (xy 305.460875 -68.536149) (xy 305.461416 -68.58) (xy 305.460899 -68.623763)
			(xy 305.4523 -68.710865) (xy 305.435194 -68.796702) (xy 305.409747 -68.880447) (xy 305.376204 -68.961289)
			(xy 305.356006 -69.000116) (xy 305.350776 -69.011509) (xy 305.350889 -69.036543) (xy 305.35626 -69.047868)
			(xy 305.376521 -69.086782) (xy 305.410157 -69.167817) (xy 305.435668 -69.251765) (xy 305.452807 -69.337814)
			(xy 305.461409 -69.42513) (xy 305.461924 -69.469) (xy 305.461407 -69.512819) (xy 305.452768 -69.60003)
			(xy 305.435612 -69.685973) (xy 305.410106 -69.769817) (xy 305.376495 -69.850754) (xy 305.35626 -69.889624)
			(xy 305.35095 -69.90098) (xy 305.35095 -69.92602) (xy 305.35626 -69.937376) (xy 305.376509 -69.976241)
			(xy 305.410141 -70.057171) (xy 305.435652 -70.141016) (xy 305.452795 -70.226963) (xy 305.461403 -70.31418)
			(xy 305.461924 -70.358) (xy 305.46142 -70.400397) (xy 305.45336 -70.484807) (xy 305.437312 -70.568068)
			(xy 305.413423 -70.649427) (xy 305.381908 -70.728147) (xy 305.343054 -70.803515) (xy 305.297211 -70.874848)
			(xy 305.244795 -70.9415) (xy 305.18628 -71.002868) (xy 305.122198 -71.058396) (xy 305.053127 -71.107581)
			(xy 304.979693 -71.149978) (xy 304.902562 -71.185203) (xy 304.822432 -71.212936) (xy 304.740028 -71.232927)
			(xy 304.656098 -71.244994) (xy 304.5714 -71.249029) (xy 304.486702 -71.244994) (xy 304.402772 -71.232927)
			(xy 304.320368 -71.212936) (xy 304.240238 -71.185203) (xy 304.163107 -71.149978) (xy 304.089673 -71.107581)
			(xy 304.020602 -71.058396) (xy 303.95652 -71.002868) (xy 303.898005 -70.9415) (xy 303.845589 -70.874848)
			(xy 303.799746 -70.803515) (xy 303.760892 -70.728147) (xy 303.729377 -70.649427) (xy 303.705488 -70.568068)
			(xy 303.68944 -70.484807) (xy 303.68138 -70.400397) (xy 303.680876 -70.358) (xy 303.681393 -70.314181)
			(xy 303.690032 -70.22697) (xy 303.707188 -70.141027) (xy 303.732694 -70.057183) (xy 303.766305 -69.976246)
			(xy 303.78654 -69.937376) (xy 303.79185 -69.92602) (xy 303.79185 -69.90098) (xy 303.78654 -69.889624)
			(xy 303.766291 -69.850759) (xy 303.732659 -69.769829) (xy 303.707148 -69.685984) (xy 303.690005 -69.600037)
			(xy 303.681397 -69.51282) (xy 303.680876 -69.469) (xy 303.681366 -69.425129) (xy 303.689958 -69.337809)
			(xy 303.707097 -69.251758) (xy 303.732618 -69.167811) (xy 303.766273 -69.08678) (xy 303.78654 -69.047868)
			(xy 303.791948 -69.036553) (xy 303.792061 -69.0115) (xy 303.786794 -69.000116) (xy 303.766602 -68.961287)
			(xy 303.733053 -68.880446) (xy 303.707604 -68.796703) (xy 303.6905 -68.710865) (xy 303.681907 -68.623763)
			(xy 303.681384 -68.58) (xy 303.681935 -68.536149) (xy 303.690574 -68.448872) (xy 303.707759 -68.36287)
			(xy 303.733323 -68.278975) (xy 303.767017 -68.198003) (xy 303.787302 -68.159122) (xy 303.792725 -68.147658)
			(xy 303.792722 -68.122328) (xy 303.787302 -68.110862) (xy 303.769177 -68.076148) (xy 303.738379 -68.004141)
			(xy 303.714026 -67.929707) (xy 303.704752 -67.89166) (xy 303.701577 -67.88066) (xy 303.68727 -67.862821)
			(xy 303.666655 -67.852924) (xy 303.655222 -67.85229) (xy 302.506634 -67.85229) (xy 302.497417 -67.852597)
			(xy 302.48016 -67.859068) (xy 302.46633 -67.87125) (xy 302.461676 -67.879214) (xy 302.44161 -67.915996)
			(xy 302.395544 -67.985991) (xy 302.343101 -68.051344) (xy 302.284745 -68.111477) (xy 302.220994 -68.165856)
			(xy 302.152412 -68.214001) (xy 302.079608 -68.255483) (xy 302.003225 -68.289937) (xy 301.923942 -68.317056)
			(xy 301.842459 -68.3366) (xy 301.759501 -68.348396) (xy 301.6758 -68.35234) (xy 301.592099 -68.348396)
			(xy 301.509141 -68.3366) (xy 301.427658 -68.317056) (xy 301.348375 -68.289937) (xy 301.271992 -68.255483)
			(xy 301.199188 -68.214001) (xy 301.130606 -68.165856) (xy 301.066855 -68.111477) (xy 301.008499 -68.051344)
			(xy 300.956056 -67.985991) (xy 300.90999 -67.915996) (xy 300.889924 -67.879214) (xy 300.885265 -67.87127)
			(xy 300.8714 -67.859162) (xy 300.854169 -67.852685) (xy 300.844966 -67.85229) (xy 298.858432 -67.85229)
			(xy 298.849396 -67.852715) (xy 298.83248 -67.85909) (xy 298.825412 -67.864736) (xy 298.802155 -67.884208)
			(xy 298.751837 -67.918083) (xy 298.697843 -67.945724) (xy 298.640941 -67.966738) (xy 298.611544 -67.97421)
			(xy 298.601535 -67.977085) (xy 298.584883 -67.989557) (xy 298.579286 -67.99834) (xy 298.537122 -68.071238)
			(xy 298.534582 -68.091558) (xy 298.53763 -68.101718) (xy 298.549123 -68.142547) (xy 298.565256 -68.225824)
			(xy 298.573404 -68.310258) (xy 298.573952 -68.35267) (xy 298.573952 -68.35394) (xy 298.573428 -68.396357)
			(xy 298.565359 -68.480805) (xy 298.549288 -68.564102) (xy 298.525362 -68.645491) (xy 298.493797 -68.724233)
			(xy 298.454881 -68.799613) (xy 298.408966 -68.870947) (xy 298.35647 -68.937587) (xy 298.297869 -68.998927)
			(xy 298.266104 -69.02704) (xy 298.258204 -69.034606) (xy 298.249106 -69.05447) (xy 298.248578 -69.065394)
			(xy 298.248578 -69.14261) (xy 298.2491 -69.153536) (xy 298.258191 -69.173411) (xy 298.266104 -69.180964)
			(xy 298.297847 -69.209103) (xy 298.356452 -69.270438) (xy 298.408954 -69.337073) (xy 298.454874 -69.408403)
			(xy 298.493797 -69.48378) (xy 298.525369 -69.562519) (xy 298.549303 -69.643905) (xy 298.565381 -69.7272)
			(xy 298.573459 -69.811648) (xy 298.573952 -69.854064) (xy 298.573448 -69.896412) (xy 298.565397 -69.980726)
			(xy 298.549368 -70.063892) (xy 298.525507 -70.145159) (xy 298.494028 -70.223789) (xy 298.455217 -70.29907)
			(xy 298.409427 -70.370322) (xy 298.357071 -70.436898) (xy 298.298623 -70.498196) (xy 298.234613 -70.553661)
			(xy 298.165621 -70.60279) (xy 298.092271 -70.645139) (xy 298.015228 -70.680323) (xy 297.935189 -70.708025)
			(xy 297.85288 -70.727993) (xy 297.769045 -70.740046) (xy 297.684444 -70.744077) (xy 297.599843 -70.740046)
			(xy 297.516008 -70.727993) (xy 297.433699 -70.708025) (xy 297.35366 -70.680323) (xy 297.276617 -70.645139)
			(xy 297.203267 -70.60279) (xy 297.134275 -70.553661) (xy 297.070265 -70.498196) (xy 297.011817 -70.436898)
			(xy 296.959461 -70.370322) (xy 296.913671 -70.29907) (xy 296.87486 -70.223789) (xy 296.843381 -70.145159)
			(xy 296.81952 -70.063892) (xy 296.803491 -69.980726) (xy 296.79544 -69.896412) (xy 296.794936 -69.854064)
			(xy 296.795467 -69.811648) (xy 296.803535 -69.727199) (xy 296.819606 -69.643903) (xy 296.843531 -69.562514)
			(xy 296.875095 -69.483772) (xy 296.91401 -69.408392) (xy 296.959924 -69.337058) (xy 297.012419 -69.270418)
			(xy 297.071019 -69.209078) (xy 297.102784 -69.180964) (xy 297.110696 -69.173409) (xy 297.119784 -69.153536)
			(xy 297.12031 -69.14261) (xy 297.12031 -69.065394) (xy 297.119789 -69.054467) (xy 297.110698 -69.034593)
			(xy 297.102784 -69.02704) (xy 297.07104 -68.998902) (xy 297.012435 -68.937566) (xy 296.959935 -68.870931)
			(xy 296.914014 -68.799601) (xy 296.875092 -68.724224) (xy 296.84352 -68.645485) (xy 296.819586 -68.564099)
			(xy 296.803507 -68.480804) (xy 296.795429 -68.396356) (xy 296.794936 -68.35394) (xy 296.795441 -68.312106)
			(xy 296.803292 -68.228806) (xy 296.818929 -68.146612) (xy 296.842213 -68.066249) (xy 296.872939 -67.988426)
			(xy 296.910835 -67.913832) (xy 296.955566 -67.843124) (xy 297.006738 -67.776929) (xy 297.063899 -67.71583)
			(xy 297.126543 -67.660367) (xy 297.194117 -67.61103) (xy 297.266025 -67.568255) (xy 297.34163 -67.532419)
			(xy 297.420267 -67.50384) (xy 297.501238 -67.482769) (xy 297.542458 -67.475608) (xy 297.556682 -67.473322)
			(xy 297.578272 -67.45478) (xy 297.61053 -67.354958) (xy 297.612969 -67.345949) (xy 297.611952 -67.32733)
			(xy 297.60437 -67.310294) (xy 297.598084 -67.303396) (xy 296.185844 -65.891156) (xy 296.162692 -65.867271)
			(xy 296.122179 -65.814511) (xy 296.088903 -65.756912) (xy 296.063434 -65.695461) (xy 296.046209 -65.63121)
			(xy 296.037521 -65.56526) (xy 296.037 -65.532) (xy 296.037 -62.080394) (xy 296.036604 -62.070321)
			(xy 296.028866 -62.051722) (xy 296.022014 -62.044326) (xy 293.301674 -59.323986) (xy 293.294279 -59.31714)
			(xy 293.275676 -59.309424) (xy 293.265606 -59.309) (xy 282.448 -59.309) (xy 282.414741 -59.308461)
			(xy 282.348791 -59.299775) (xy 282.28454 -59.282553) (xy 282.223089 -59.257089) (xy 282.165488 -59.223818)
			(xy 282.112724 -59.183312) (xy 282.088844 -59.160156) (xy 274.690586 -51.761898) (xy 274.683185 -51.755059)
			(xy 274.664586 -51.747339) (xy 274.654518 -51.746912) (xy 262.820912 -51.746912) (xy 262.787652 -51.746391)
			(xy 262.721701 -51.737705) (xy 262.657449 -51.720481) (xy 262.595996 -51.695014) (xy 262.538396 -51.661739)
			(xy 262.485634 -51.621227) (xy 262.461756 -51.598068) (xy 258.774692 -47.911004) (xy 258.74472 -47.904908)
			(xy 258.730496 -47.911004) (xy 258.721368 -47.915219) (xy 258.707133 -47.929396) (xy 258.699425 -47.947949)
			(xy 258.699 -47.957994) (xy 258.699 -50.894996) (xy 258.698458 -50.928255) (xy 258.689773 -50.994205)
			(xy 258.672551 -51.058455) (xy 258.647088 -51.119907) (xy 258.613818 -51.177508) (xy 258.573312 -51.230272)
			(xy 258.550156 -51.254152) (xy 257.878072 -51.926236) (xy 257.854176 -51.949376) (xy 257.801419 -51.989891)
			(xy 257.743823 -52.023169) (xy 257.682374 -52.04864) (xy 257.618124 -52.065868) (xy 257.552175 -52.074558)
			(xy 257.518916 -52.07508) (xy 257.502294 -52.074945) (xy 257.469121 -52.072786) (xy 257.452622 -52.070762)
			(xy 257.439414 -52.070762) (xy 257.422916 -52.072793) (xy 257.389742 -52.074955) (xy 257.37312 -52.07508)
			(xy 247.302782 -52.07508) (xy 247.269522 -52.074558) (xy 247.203572 -52.06587) (xy 247.13932 -52.048645)
			(xy 247.077868 -52.023177) (xy 247.020268 -51.989904) (xy 246.967505 -51.949394) (xy 246.943626 -51.926236)
			(xy 246.398796 -51.381406) (xy 246.375611 -51.357551) (xy 246.335103 -51.304784) (xy 246.301833 -51.247179)
			(xy 246.27637 -51.185722) (xy 246.259151 -51.121466) (xy 246.25047 -51.055512) (xy 246.249952 -51.02225)
			(xy 246.249952 -46.654466) (xy 246.250454 -46.621205) (xy 246.259145 -46.555254) (xy 246.276374 -46.491002)
			(xy 246.301845 -46.42955) (xy 246.335122 -46.37195) (xy 246.375636 -46.319188) (xy 246.398796 -46.29531)
			(xy 250.260866 -42.43324) (xy 250.266962 -42.403268) (xy 250.260866 -42.389044) (xy 250.256653 -42.379914)
			(xy 250.242478 -42.365674) (xy 250.223922 -42.357969) (xy 250.213876 -42.357548) (xy 249.2248 -42.357548)
			(xy 249.214729 -42.357961) (xy 249.196131 -42.365689) (xy 249.188732 -42.372534) (xy 243.32311 -48.238156)
			(xy 243.299245 -48.26133) (xy 243.246481 -48.301841) (xy 243.188878 -48.335114) (xy 243.127423 -48.360579)
			(xy 243.063168 -48.3778) (xy 242.997215 -48.386482) (xy 242.963954 -48.387) (xy 230.251 -48.387)
			(xy 230.217741 -48.386461) (xy 230.151791 -48.377775) (xy 230.08754 -48.360553) (xy 230.026089 -48.335089)
			(xy 229.968488 -48.301818) (xy 229.915724 -48.261312) (xy 229.891844 -48.238156) (xy 229.002844 -47.349156)
			(xy 228.979692 -47.325271) (xy 228.939179 -47.272511) (xy 228.905903 -47.214912) (xy 228.880434 -47.153461)
			(xy 228.863209 -47.08921) (xy 228.854521 -47.02326) (xy 228.854 -46.99) (xy 211.4804 -46.99) (xy 211.479861 -47.023259)
			(xy 211.471175 -47.089209) (xy 211.453953 -47.15346) (xy 211.428489 -47.214911) (xy 211.395218 -47.272512)
			(xy 211.354712 -47.325276) (xy 211.331556 -47.349156) (xy 210.442556 -48.238156) (xy 210.418671 -48.261308)
			(xy 210.365911 -48.301821) (xy 210.308312 -48.335097) (xy 210.246861 -48.360566) (xy 210.18261 -48.377791)
			(xy 210.11666 -48.386479) (xy 210.0834 -48.387) (xy 197.797166 -48.387) (xy 197.763906 -48.386483)
			(xy 197.697955 -48.377793) (xy 197.633704 -48.360566) (xy 197.572252 -48.335098) (xy 197.514652 -48.301824)
			(xy 197.461889 -48.261314) (xy 197.43801 -48.238156) (xy 191.552068 -42.352214) (xy 191.544671 -42.345369)
			(xy 191.52607 -42.337652) (xy 191.516 -42.337228) (xy 190.21425 -42.337228) (xy 190.203612 -42.337748)
			(xy 190.184155 -42.346351) (xy 190.169854 -42.362101) (xy 190.16599 -42.372026) (xy 190.13551 -42.463466)
			(xy 190.132593 -42.473671) (xy 190.134551 -42.494786) (xy 190.144888 -42.513301) (xy 190.153036 -42.520108)
			(xy 190.15329 -42.520108) (xy 190.167457 -42.530955) (xy 190.194407 -42.554343) (xy 190.207138 -42.566844)
			(xy 193.935604 -46.29531) (xy 193.958748 -46.319202) (xy 193.99926 -46.371961) (xy 194.032536 -46.429559)
			(xy 194.058006 -46.491009) (xy 194.075234 -46.555258) (xy 194.083925 -46.621207) (xy 194.084448 -46.654466)
			(xy 194.084448 -51.02225) (xy 194.084038 -51.049936) (xy 207.409803 -51.049936) (xy 207.413813 -50.944033)
			(xy 207.425821 -50.838737) (xy 207.445758 -50.734651) (xy 207.47351 -50.632371) (xy 207.508918 -50.532482)
			(xy 207.551779 -50.435558) (xy 207.601847 -50.342152) (xy 207.658837 -50.252801) (xy 207.72242 -50.168015)
			(xy 207.792234 -50.088281) (xy 207.867878 -50.014056) (xy 207.948918 -49.945763) (xy 208.034892 -49.883796)
			(xy 208.125306 -49.828508) (xy 208.219642 -49.780216) (xy 208.317361 -49.739197) (xy 208.417901 -49.705686)
			(xy 208.520689 -49.679874) (xy 208.625133 -49.66191) (xy 208.730638 -49.651897) (xy 208.836597 -49.649891)
			(xy 208.942405 -49.655905) (xy 209.047455 -49.669904) (xy 209.151145 -49.691807) (xy 209.252882 -49.72149)
			(xy 209.352083 -49.758781) (xy 209.448179 -49.803469) (xy 209.54062 -49.855296) (xy 209.628877 -49.913966)
			(xy 209.712444 -49.979143) (xy 209.790843 -50.050453) (xy 209.863624 -50.127487) (xy 209.93037 -50.209806)
			(xy 209.9907 -50.296937) (xy 210.044267 -50.388381) (xy 210.090765 -50.483614) (xy 210.129927 -50.582091)
			(xy 210.16153 -50.683248) (xy 210.185391 -50.786506) (xy 210.201376 -50.891272) (xy 210.209391 -50.996947)
			(xy 210.209892 -51.049936) (xy 237.409743 -51.049936) (xy 237.413753 -50.944033) (xy 237.425761 -50.838737)
			(xy 237.445698 -50.734651) (xy 237.47345 -50.632371) (xy 237.508858 -50.532482) (xy 237.551719 -50.435558)
			(xy 237.601787 -50.342152) (xy 237.658777 -50.252801) (xy 237.72236 -50.168015) (xy 237.792174 -50.088281)
			(xy 237.867818 -50.014056) (xy 237.948858 -49.945763) (xy 238.034832 -49.883796) (xy 238.125246 -49.828508)
			(xy 238.219582 -49.780216) (xy 238.317301 -49.739197) (xy 238.417841 -49.705686) (xy 238.520629 -49.679874)
			(xy 238.625073 -49.66191) (xy 238.730578 -49.651897) (xy 238.836537 -49.649891) (xy 238.942345 -49.655905)
			(xy 239.047395 -49.669904) (xy 239.151085 -49.691807) (xy 239.252822 -49.72149) (xy 239.352023 -49.758781)
			(xy 239.448119 -49.803469) (xy 239.54056 -49.855296) (xy 239.628817 -49.913966) (xy 239.712384 -49.979143)
			(xy 239.790783 -50.050453) (xy 239.863564 -50.127487) (xy 239.93031 -50.209806) (xy 239.99064 -50.296937)
			(xy 240.044207 -50.388381) (xy 240.090705 -50.483614) (xy 240.129867 -50.582091) (xy 240.16147 -50.683248)
			(xy 240.185331 -50.786506) (xy 240.201316 -50.891272) (xy 240.209331 -50.996947) (xy 240.209832 -51.049936)
			(xy 240.209331 -51.102925) (xy 240.201316 -51.2086) (xy 240.185331 -51.313366) (xy 240.16147 -51.416624)
			(xy 240.129867 -51.517781) (xy 240.090705 -51.616258) (xy 240.044207 -51.711491) (xy 239.99064 -51.802935)
			(xy 239.93031 -51.890066) (xy 239.863564 -51.972385) (xy 239.790783 -52.049419) (xy 239.712384 -52.120729)
			(xy 239.628817 -52.185906) (xy 239.54056 -52.244576) (xy 239.448119 -52.296403) (xy 239.352023 -52.341091)
			(xy 239.252822 -52.378382) (xy 239.151085 -52.408065) (xy 239.047395 -52.429968) (xy 238.942345 -52.443967)
			(xy 238.836537 -52.449981) (xy 238.730578 -52.447975) (xy 238.625073 -52.437962) (xy 238.520629 -52.419998)
			(xy 238.417841 -52.394186) (xy 238.317301 -52.360675) (xy 238.219582 -52.319656) (xy 238.125246 -52.271364)
			(xy 238.034832 -52.216076) (xy 237.948858 -52.154109) (xy 237.867818 -52.085816) (xy 237.792174 -52.011591)
			(xy 237.72236 -51.931857) (xy 237.658777 -51.847071) (xy 237.601787 -51.75772) (xy 237.551719 -51.664314)
			(xy 237.508858 -51.56739) (xy 237.47345 -51.467501) (xy 237.445698 -51.365221) (xy 237.425761 -51.261135)
			(xy 237.413753 -51.155839) (xy 237.409743 -51.049936) (xy 210.209892 -51.049936) (xy 210.209391 -51.102925)
			(xy 210.201376 -51.2086) (xy 210.185391 -51.313366) (xy 210.16153 -51.416624) (xy 210.129927 -51.517781)
			(xy 210.090765 -51.616258) (xy 210.044267 -51.711491) (xy 209.9907 -51.802935) (xy 209.93037 -51.890066)
			(xy 209.863624 -51.972385) (xy 209.790843 -52.049419) (xy 209.712444 -52.120729) (xy 209.628877 -52.185906)
			(xy 209.54062 -52.244576) (xy 209.448179 -52.296403) (xy 209.352083 -52.341091) (xy 209.252882 -52.378382)
			(xy 209.151145 -52.408065) (xy 209.047455 -52.429968) (xy 208.942405 -52.443967) (xy 208.836597 -52.449981)
			(xy 208.730638 -52.447975) (xy 208.625133 -52.437962) (xy 208.520689 -52.419998) (xy 208.417901 -52.394186)
			(xy 208.317361 -52.360675) (xy 208.219642 -52.319656) (xy 208.125306 -52.271364) (xy 208.034892 -52.216076)
			(xy 207.948918 -52.154109) (xy 207.867878 -52.085816) (xy 207.792234 -52.011591) (xy 207.72242 -51.931857)
			(xy 207.658837 -51.847071) (xy 207.601847 -51.75772) (xy 207.551779 -51.664314) (xy 207.508918 -51.56739)
			(xy 207.47351 -51.467501) (xy 207.445758 -51.365221) (xy 207.425821 -51.261135) (xy 207.413813 -51.155839)
			(xy 207.409803 -51.049936) (xy 194.084038 -51.049936) (xy 194.083956 -51.055511) (xy 194.075263 -51.121463)
			(xy 194.058032 -51.185715) (xy 194.03256 -51.247167) (xy 193.99928 -51.304767) (xy 193.958765 -51.357528)
			(xy 193.935604 -51.381406) (xy 193.390774 -51.926236) (xy 193.366877 -51.949375) (xy 193.31412 -51.989891)
			(xy 193.256524 -52.023169) (xy 193.195075 -52.04864) (xy 193.130826 -52.065868) (xy 193.064877 -52.074557)
			(xy 193.031618 -52.07508) (xy 182.815484 -52.07508) (xy 182.782224 -52.074557) (xy 182.716274 -52.065869)
			(xy 182.652022 -52.048644) (xy 182.59057 -52.023177) (xy 182.53297 -51.989903) (xy 182.480207 -51.949394)
			(xy 182.456328 -51.926236) (xy 181.784244 -51.254152) (xy 181.76109 -51.230269) (xy 181.720577 -51.177508)
			(xy 181.687302 -51.119909) (xy 181.661833 -51.058458) (xy 181.644608 -50.994207) (xy 181.635921 -50.928256)
			(xy 181.6354 -50.894996) (xy 181.6354 -46.609) (xy 181.635939 -46.575741) (xy 181.644625 -46.509791)
			(xy 181.661847 -46.44554) (xy 181.687311 -46.384089) (xy 181.720582 -46.326488) (xy 181.761088 -46.273724)
			(xy 181.784244 -46.249844) (xy 185.467244 -42.566844) (xy 185.479973 -42.554341) (xy 185.506922 -42.530951)
			(xy 185.521092 -42.520108) (xy 185.521346 -42.520108) (xy 185.529459 -42.513289) (xy 185.539717 -42.494765)
			(xy 185.541693 -42.473684) (xy 185.538872 -42.463466) (xy 185.508392 -42.372026) (xy 185.504497 -42.362119)
			(xy 185.4902 -42.346385) (xy 185.470761 -42.337776) (xy 185.460132 -42.337228) (xy 174.147226 -42.337228)
			(xy 174.137157 -42.337659) (xy 174.118559 -42.345375) (xy 174.111158 -42.352214) (xy 172.697648 -43.765724)
			(xy 172.690812 -43.773127) (xy 172.683088 -43.791724) (xy 172.682662 -43.801792) (xy 172.682662 -47.032361)
			(xy 177.987702 -47.032361) (xy 177.987702 -46.947639) (xy 177.995755 -46.863302) (xy 178.011789 -46.780112)
			(xy 178.035657 -46.698822) (xy 178.067145 -46.62017) (xy 178.105967 -46.544867) (xy 178.15177 -46.473595)
			(xy 178.204141 -46.406999) (xy 178.262606 -46.345684) (xy 178.326634 -46.290203) (xy 178.395646 -46.24106)
			(xy 178.469016 -46.1987) (xy 178.546081 -46.163505) (xy 178.626143 -46.135796) (xy 178.708476 -46.115822)
			(xy 178.792335 -46.103765) (xy 178.87696 -46.099734) (xy 178.961585 -46.103765) (xy 179.045444 -46.115822)
			(xy 179.127777 -46.135796) (xy 179.207839 -46.163505) (xy 179.284904 -46.1987) (xy 179.358274 -46.24106)
			(xy 179.427286 -46.290203) (xy 179.491314 -46.345684) (xy 179.549779 -46.406999) (xy 179.60215 -46.473595)
			(xy 179.647953 -46.544867) (xy 179.686775 -46.62017) (xy 179.718263 -46.698822) (xy 179.742131 -46.780112)
			(xy 179.758165 -46.863302) (xy 179.766218 -46.947639) (xy 179.766722 -46.99) (xy 179.766218 -47.032361)
			(xy 179.758165 -47.116698) (xy 179.742131 -47.199888) (xy 179.718263 -47.281178) (xy 179.686775 -47.35983)
			(xy 179.647953 -47.435133) (xy 179.60215 -47.506405) (xy 179.549779 -47.573001) (xy 179.491314 -47.634316)
			(xy 179.427286 -47.689797) (xy 179.358274 -47.73894) (xy 179.284904 -47.7813) (xy 179.207839 -47.816495)
			(xy 179.127777 -47.844204) (xy 179.045444 -47.864178) (xy 178.961585 -47.876235) (xy 178.87696 -47.880267)
			(xy 178.792335 -47.876235) (xy 178.708476 -47.864178) (xy 178.626143 -47.844204) (xy 178.546081 -47.816495)
			(xy 178.469016 -47.7813) (xy 178.395646 -47.73894) (xy 178.326634 -47.689797) (xy 178.262606 -47.634316)
			(xy 178.204141 -47.573001) (xy 178.15177 -47.506405) (xy 178.105967 -47.435133) (xy 178.067145 -47.35983)
			(xy 178.035657 -47.281178) (xy 178.011789 -47.199888) (xy 177.995755 -47.116698) (xy 177.987702 -47.032361)
			(xy 172.682662 -47.032361) (xy 172.682662 -50.465228) (xy 172.683056 -50.475301) (xy 172.690797 -50.4939)
			(xy 172.697648 -50.501296) (xy 172.778674 -50.582322) (xy 172.786086 -50.589146) (xy 172.804676 -50.596875)
			(xy 172.814742 -50.597308) (xy 173.980348 -50.597308) (xy 174.013609 -50.597814) (xy 174.07956 -50.606506)
			(xy 174.143811 -50.623734) (xy 174.205263 -50.649205) (xy 174.262863 -50.682481) (xy 174.315625 -50.722993)
			(xy 174.339504 -50.746152) (xy 176.661318 -53.067966) (xy 176.684492 -53.091831) (xy 176.725 -53.144596)
			(xy 176.758272 -53.2022) (xy 176.783737 -53.263655) (xy 176.800958 -53.327908) (xy 176.809642 -53.393861)
			(xy 176.810162 -53.427122) (xy 176.810162 -54.812438) (xy 176.809658 -54.845699) (xy 176.800967 -54.91165)
			(xy 176.783739 -54.975902) (xy 176.758268 -55.037354) (xy 176.724991 -55.094954) (xy 176.684477 -55.147715)
			(xy 176.661318 -55.171594) (xy 175.492156 -56.340756) (xy 175.468271 -56.363908) (xy 175.415511 -56.404421)
			(xy 175.357912 -56.437697) (xy 175.296461 -56.463166) (xy 175.23221 -56.480391) (xy 175.16626 -56.489079)
			(xy 175.133 -56.4896) (xy 160.276794 -56.4896) (xy 160.266721 -56.489996) (xy 160.248122 -56.497734)
			(xy 160.240726 -56.504586) (xy 158.833312 -57.912) (xy 268.756388 -57.912) (xy 268.760418 -57.827399)
			(xy 268.772471 -57.743564) (xy 268.792439 -57.661255) (xy 268.820141 -57.581216) (xy 268.855325 -57.504173)
			(xy 268.897674 -57.430823) (xy 268.946803 -57.361831) (xy 269.002268 -57.297821) (xy 269.063566 -57.239373)
			(xy 269.130142 -57.187017) (xy 269.201394 -57.141227) (xy 269.276675 -57.102416) (xy 269.355305 -57.070937)
			(xy 269.436572 -57.047076) (xy 269.519738 -57.031047) (xy 269.604052 -57.022996) (xy 269.6464 -57.022492)
			(xy 269.646908 -57.022492) (xy 269.69324 -57.023098) (xy 269.785398 -57.032769) (xy 269.876052 -57.051965)
			(xy 269.964221 -57.080477) (xy 270.006826 -57.098692) (xy 270.016768 -57.102498) (xy 270.038032 -57.102498)
			(xy 270.047974 -57.098692) (xy 270.090636 -57.080447) (xy 270.178929 -57.051903) (xy 270.269714 -57.03271)
			(xy 270.362004 -57.023077) (xy 270.4084 -57.022492) (xy 270.451753 -57.02298) (xy 270.538049 -57.031388)
			(xy 270.623118 -57.048154) (xy 270.706152 -57.073118) (xy 270.786362 -57.106044) (xy 270.862988 -57.146619)
			(xy 270.935302 -57.194458) (xy 271.002617 -57.249107) (xy 271.064295 -57.310046) (xy 271.092422 -57.34304)
			(xy 271.099534 -57.351676) (xy 271.119854 -57.361328) (xy 271.220946 -57.361328) (xy 271.241266 -57.351676)
			(xy 271.248378 -57.34304) (xy 271.276524 -57.310064) (xy 271.338205 -57.249132) (xy 271.40552 -57.194489)
			(xy 271.477833 -57.146654) (xy 271.554455 -57.106081) (xy 271.634662 -57.073155) (xy 271.717692 -57.048188)
			(xy 271.802756 -57.031418) (xy 271.889049 -57.023002) (xy 271.9324 -57.022492) (xy 271.978796 -57.023075)
			(xy 272.071084 -57.03272) (xy 272.161868 -57.051916) (xy 272.250161 -57.080454) (xy 272.292826 -57.098692)
			(xy 272.302768 -57.102498) (xy 272.324032 -57.102498) (xy 272.333974 -57.098692) (xy 272.376577 -57.08047)
			(xy 272.464744 -57.051952) (xy 272.5554 -57.03276) (xy 272.64756 -57.0231) (xy 272.693892 -57.022492)
			(xy 272.6944 -57.022492) (xy 272.736748 -57.022996) (xy 272.821062 -57.031047) (xy 272.904228 -57.047076)
			(xy 272.985495 -57.070937) (xy 273.064125 -57.102416) (xy 273.139406 -57.141227) (xy 273.210658 -57.187017)
			(xy 273.277234 -57.239373) (xy 273.338532 -57.297821) (xy 273.393997 -57.361831) (xy 273.443126 -57.430823)
			(xy 273.485475 -57.504173) (xy 273.520659 -57.581216) (xy 273.548361 -57.661255) (xy 273.568329 -57.743564)
			(xy 273.580382 -57.827399) (xy 273.584413 -57.912) (xy 273.580382 -57.996601) (xy 273.568329 -58.080436)
			(xy 273.548361 -58.162745) (xy 273.520659 -58.242784) (xy 273.485475 -58.319827) (xy 273.443126 -58.393177)
			(xy 273.393997 -58.462169) (xy 273.338532 -58.526179) (xy 273.277234 -58.584627) (xy 273.210658 -58.636983)
			(xy 273.139406 -58.682773) (xy 273.064125 -58.721584) (xy 272.985495 -58.753063) (xy 272.904228 -58.776924)
			(xy 272.821062 -58.792953) (xy 272.736748 -58.801004) (xy 272.6944 -58.801508) (xy 272.693892 -58.801508)
			(xy 272.64756 -58.800902) (xy 272.555402 -58.791231) (xy 272.464748 -58.772035) (xy 272.376579 -58.743523)
			(xy 272.333974 -58.725308) (xy 272.324032 -58.721502) (xy 272.302768 -58.721502) (xy 272.292826 -58.725308)
			(xy 272.250164 -58.743553) (xy 272.161871 -58.772097) (xy 272.071086 -58.79129) (xy 271.978796 -58.800923)
			(xy 271.9324 -58.801508) (xy 271.889047 -58.80102) (xy 271.802751 -58.792612) (xy 271.717682 -58.775846)
			(xy 271.634648 -58.750882) (xy 271.554438 -58.717956) (xy 271.477812 -58.677381) (xy 271.405498 -58.629542)
			(xy 271.338183 -58.574893) (xy 271.276505 -58.513954) (xy 271.248378 -58.48096) (xy 271.241266 -58.472324)
			(xy 271.220946 -58.462672) (xy 271.119854 -58.462672) (xy 271.099534 -58.472324) (xy 271.092422 -58.48096)
			(xy 271.064276 -58.513936) (xy 271.002595 -58.574868) (xy 270.93528 -58.629511) (xy 270.862967 -58.677346)
			(xy 270.786345 -58.717919) (xy 270.706138 -58.750845) (xy 270.623108 -58.775812) (xy 270.538044 -58.792582)
			(xy 270.451751 -58.800998) (xy 270.4084 -58.801508) (xy 270.362004 -58.800925) (xy 270.269716 -58.79128)
			(xy 270.178932 -58.772084) (xy 270.090639 -58.743546) (xy 270.047974 -58.725308) (xy 270.038032 -58.721502)
			(xy 270.016768 -58.721502) (xy 270.006826 -58.725308) (xy 269.964223 -58.74353) (xy 269.876056 -58.772048)
			(xy 269.7854 -58.79124) (xy 269.69324 -58.8009) (xy 269.646908 -58.801508) (xy 269.6464 -58.801508)
			(xy 269.604052 -58.801004) (xy 269.519738 -58.792953) (xy 269.436572 -58.776924) (xy 269.355305 -58.753063)
			(xy 269.276675 -58.721584) (xy 269.201394 -58.682773) (xy 269.130142 -58.636983) (xy 269.063566 -58.584627)
			(xy 269.002268 -58.526179) (xy 268.946803 -58.462169) (xy 268.897674 -58.393177) (xy 268.855325 -58.319827)
			(xy 268.820141 -58.242784) (xy 268.792439 -58.162745) (xy 268.772471 -58.080436) (xy 268.760418 -57.996601)
			(xy 268.756388 -57.912) (xy 158.833312 -57.912) (xy 156.369512 -60.3758) (xy 165.632388 -60.3758)
			(xy 165.636418 -60.291199) (xy 165.648471 -60.207364) (xy 165.668439 -60.125055) (xy 165.696141 -60.045016)
			(xy 165.731325 -59.967973) (xy 165.773674 -59.894623) (xy 165.822803 -59.825631) (xy 165.878268 -59.761621)
			(xy 165.939566 -59.703173) (xy 166.006142 -59.650817) (xy 166.077394 -59.605027) (xy 166.152675 -59.566216)
			(xy 166.231305 -59.534737) (xy 166.312572 -59.510876) (xy 166.395738 -59.494847) (xy 166.480052 -59.486796)
			(xy 166.5224 -59.486292) (xy 166.522908 -59.486292) (xy 166.56924 -59.486898) (xy 166.661398 -59.496569)
			(xy 166.752052 -59.515765) (xy 166.840221 -59.544277) (xy 166.882826 -59.562492) (xy 166.892768 -59.566298)
			(xy 166.914032 -59.566298) (xy 166.923974 -59.562492) (xy 166.966577 -59.54427) (xy 167.054744 -59.515752)
			(xy 167.1454 -59.49656) (xy 167.23756 -59.4869) (xy 167.283892 -59.486292) (xy 167.2844 -59.486292)
			(xy 167.326748 -59.486796) (xy 167.411062 -59.494847) (xy 167.494228 -59.510876) (xy 167.575495 -59.534737)
			(xy 167.654125 -59.566216) (xy 167.729406 -59.605027) (xy 167.800658 -59.650817) (xy 167.867234 -59.703173)
			(xy 167.928532 -59.761621) (xy 167.983997 -59.825631) (xy 168.033126 -59.894623) (xy 168.075475 -59.967973)
			(xy 168.110659 -60.045016) (xy 168.138361 -60.125055) (xy 168.158329 -60.207364) (xy 168.170382 -60.291199)
			(xy 168.174413 -60.3758) (xy 168.170382 -60.460401) (xy 168.158329 -60.544236) (xy 168.138361 -60.626545)
			(xy 168.110659 -60.706584) (xy 168.075475 -60.783627) (xy 168.033126 -60.856977) (xy 167.983997 -60.925969)
			(xy 167.928532 -60.989979) (xy 167.867234 -61.048427) (xy 167.800658 -61.100783) (xy 167.729406 -61.146573)
			(xy 167.654125 -61.185384) (xy 167.575495 -61.216863) (xy 167.494228 -61.240724) (xy 167.411062 -61.256753)
			(xy 167.326748 -61.264804) (xy 167.2844 -61.265308) (xy 167.283892 -61.265308) (xy 167.23756 -61.264702)
			(xy 167.145402 -61.255031) (xy 167.054748 -61.235835) (xy 166.966579 -61.207323) (xy 166.923974 -61.189108)
			(xy 166.914032 -61.185302) (xy 166.892768 -61.185302) (xy 166.882826 -61.189108) (xy 166.840223 -61.20733)
			(xy 166.752056 -61.235848) (xy 166.6614 -61.25504) (xy 166.56924 -61.2647) (xy 166.522908 -61.265308)
			(xy 166.5224 -61.265308) (xy 166.480052 -61.264804) (xy 166.395738 -61.256753) (xy 166.312572 -61.240724)
			(xy 166.231305 -61.216863) (xy 166.152675 -61.185384) (xy 166.077394 -61.146573) (xy 166.006142 -61.100783)
			(xy 165.939566 -61.048427) (xy 165.878268 -60.989979) (xy 165.822803 -60.925969) (xy 165.773674 -60.856977)
			(xy 165.731325 -60.783627) (xy 165.696141 -60.706584) (xy 165.668439 -60.626545) (xy 165.648471 -60.544236)
			(xy 165.636418 -60.460401) (xy 165.632388 -60.3758) (xy 156.369512 -60.3758) (xy 152.186951 -64.558361)
			(xy 261.838182 -64.558361) (xy 261.838182 -64.473639) (xy 261.846235 -64.389302) (xy 261.862269 -64.306112)
			(xy 261.886137 -64.224822) (xy 261.917625 -64.14617) (xy 261.956447 -64.070867) (xy 262.00225 -63.999595)
			(xy 262.054621 -63.932999) (xy 262.113086 -63.871684) (xy 262.177114 -63.816203) (xy 262.246126 -63.76706)
			(xy 262.319496 -63.7247) (xy 262.396561 -63.689505) (xy 262.476623 -63.661796) (xy 262.558956 -63.641822)
			(xy 262.642815 -63.629765) (xy 262.72744 -63.625734) (xy 262.812065 -63.629765) (xy 262.895924 -63.641822)
			(xy 262.978257 -63.661796) (xy 263.058319 -63.689505) (xy 263.135384 -63.7247) (xy 263.208754 -63.76706)
			(xy 263.277766 -63.816203) (xy 263.341794 -63.871684) (xy 263.400259 -63.932999) (xy 263.45263 -63.999595)
			(xy 263.498433 -64.070867) (xy 263.537255 -64.14617) (xy 263.568743 -64.224822) (xy 263.592611 -64.306112)
			(xy 263.608645 -64.389302) (xy 263.616698 -64.473639) (xy 263.617202 -64.516) (xy 263.616698 -64.558361)
			(xy 263.608645 -64.642698) (xy 263.592611 -64.725888) (xy 263.568743 -64.807178) (xy 263.537255 -64.88583)
			(xy 263.498433 -64.961133) (xy 263.45263 -65.032405) (xy 263.400259 -65.099001) (xy 263.341794 -65.160316)
			(xy 263.277766 -65.215797) (xy 263.208754 -65.26494) (xy 263.135384 -65.3073) (xy 263.058319 -65.342495)
			(xy 262.978257 -65.370204) (xy 262.895924 -65.390178) (xy 262.812065 -65.402235) (xy 262.72744 -65.406267)
			(xy 262.642815 -65.402235) (xy 262.558956 -65.390178) (xy 262.476623 -65.370204) (xy 262.396561 -65.342495)
			(xy 262.319496 -65.3073) (xy 262.246126 -65.26494) (xy 262.177114 -65.215797) (xy 262.113086 -65.160316)
			(xy 262.054621 -65.099001) (xy 262.00225 -65.032405) (xy 261.956447 -64.961133) (xy 261.917625 -64.88583)
			(xy 261.886137 -64.807178) (xy 261.862269 -64.725888) (xy 261.846235 -64.642698) (xy 261.838182 -64.558361)
			(xy 152.186951 -64.558361) (xy 150.560786 -66.184526) (xy 150.55394 -66.191921) (xy 150.546224 -66.210524)
			(xy 150.5458 -66.220594) (xy 150.5458 -66.3194) (xy 178.683872 -66.3194) (xy 178.687902 -66.234795)
			(xy 178.699957 -66.150957) (xy 178.719926 -66.068644) (xy 178.74763 -65.988602) (xy 178.782817 -65.911556)
			(xy 178.825168 -65.838204) (xy 178.8743 -65.769209) (xy 178.929768 -65.705198) (xy 178.99107 -65.646749)
			(xy 179.057651 -65.594392) (xy 179.128907 -65.548601) (xy 179.204193 -65.509791) (xy 179.282827 -65.478314)
			(xy 179.364098 -65.454453) (xy 179.447268 -65.438427) (xy 179.531586 -65.430378) (xy 179.573936 -65.429892)
			(xy 179.574698 -65.429892) (xy 179.613046 -65.430288) (xy 179.689453 -65.436923) (xy 179.765005 -65.450117)
			(xy 179.839139 -65.469774) (xy 179.911302 -65.495746) (xy 179.9463 -65.511426) (xy 179.956573 -65.515566)
			(xy 179.978699 -65.515566) (xy 179.988972 -65.511426) (xy 180.023978 -65.49577) (xy 180.096146 -65.469818)
			(xy 180.170278 -65.45017) (xy 180.245826 -65.436971) (xy 180.322228 -65.430321) (xy 180.360574 -65.429892)
			(xy 180.361336 -65.429892) (xy 180.403683 -65.430397) (xy 180.487994 -65.438451) (xy 180.571158 -65.454483)
			(xy 180.652421 -65.478347) (xy 180.731048 -65.509827) (xy 180.806327 -65.548639) (xy 180.877576 -65.59443)
			(xy 180.944149 -65.646786) (xy 181.005444 -65.705234) (xy 181.060907 -65.769243) (xy 181.110033 -65.838234)
			(xy 181.15238 -65.911582) (xy 181.187562 -65.988624) (xy 181.215263 -66.068661) (xy 181.23523 -66.150968)
			(xy 181.247283 -66.234801) (xy 181.251313 -66.3194) (xy 181.247283 -66.403999) (xy 181.23523 -66.487832)
			(xy 181.215263 -66.570139) (xy 181.187562 -66.650176) (xy 181.15238 -66.727218) (xy 181.110033 -66.800566)
			(xy 181.060907 -66.869557) (xy 181.005444 -66.933566) (xy 180.944149 -66.992014) (xy 180.877576 -67.04437)
			(xy 180.806327 -67.090161) (xy 180.731048 -67.128973) (xy 180.652421 -67.160453) (xy 180.571158 -67.184317)
			(xy 180.487994 -67.200349) (xy 180.403683 -67.208403) (xy 180.361336 -67.208908) (xy 180.360574 -67.208908)
			(xy 180.322227 -67.208485) (xy 180.24582 -67.201857) (xy 180.170269 -67.188668) (xy 180.096135 -67.169018)
			(xy 180.02397 -67.143051) (xy 179.988972 -67.127374) (xy 179.978699 -67.123234) (xy 179.956573 -67.123234)
			(xy 179.9463 -67.127374) (xy 179.911298 -67.14304) (xy 179.839129 -67.16899) (xy 179.764996 -67.188636)
			(xy 179.689447 -67.201832) (xy 179.613044 -67.20848) (xy 179.574698 -67.208908) (xy 179.573936 -67.208908)
			(xy 179.531586 -67.208422) (xy 179.447268 -67.200373) (xy 179.364098 -67.184347) (xy 179.282827 -67.160486)
			(xy 179.204193 -67.129009) (xy 179.128907 -67.090199) (xy 179.057651 -67.044408) (xy 178.99107 -66.992051)
			(xy 178.929768 -66.933602) (xy 178.8743 -66.869591) (xy 178.825168 -66.800596) (xy 178.782817 -66.727244)
			(xy 178.74763 -66.650198) (xy 178.719926 -66.570156) (xy 178.699957 -66.487843) (xy 178.687902 -66.404005)
			(xy 178.683872 -66.3194) (xy 150.5458 -66.3194) (xy 150.5458 -67.2592) (xy 150.545261 -67.292459)
			(xy 150.536575 -67.358409) (xy 150.519353 -67.42266) (xy 150.493889 -67.484111) (xy 150.460618 -67.541712)
			(xy 150.420112 -67.594476) (xy 150.396956 -67.618356) (xy 150.34133 -67.673982) (xy 150.317461 -67.697151)
			(xy 150.264697 -67.737661) (xy 150.207095 -67.770935) (xy 150.145641 -67.7964) (xy 150.081387 -67.813623)
			(xy 150.015435 -67.822306) (xy 149.982174 -67.822826) (xy 147.268438 -67.822826) (xy 147.258918 -67.823235)
			(xy 147.241193 -67.830193) (xy 147.22722 -67.84313) (xy 147.222718 -67.851528) (xy 147.20415 -67.888594)
			(xy 147.161092 -67.959444) (xy 147.111631 -68.025982) (xy 147.056195 -68.08763) (xy 146.995265 -68.143854)
			(xy 146.929368 -68.194166) (xy 146.859078 -68.238131) (xy 146.785002 -68.275367) (xy 146.707784 -68.30555)
			(xy 146.628093 -68.32842) (xy 146.54662 -68.343777) (xy 146.464072 -68.351489) (xy 146.381164 -68.351489)
			(xy 146.298616 -68.343777) (xy 146.217143 -68.32842) (xy 146.137452 -68.30555) (xy 146.060234 -68.275367)
			(xy 145.986158 -68.238131) (xy 145.915868 -68.194166) (xy 145.849971 -68.143854) (xy 145.789041 -68.08763)
			(xy 145.733605 -68.025982) (xy 145.684144 -67.959444) (xy 145.641086 -67.888594) (xy 145.622518 -67.851528)
			(xy 145.618028 -67.84312) (xy 145.604056 -67.830173) (xy 145.586322 -67.82322) (xy 145.576798 -67.822826)
			(xy 143.862806 -67.822826) (xy 143.834866 -67.845686) (xy 143.83131 -67.86372) (xy 143.822279 -67.9067)
			(xy 143.796815 -67.99076) (xy 143.763184 -68.071898) (xy 143.742918 -68.110862) (xy 143.737504 -68.12233)
			(xy 143.737501 -68.147656) (xy 143.742918 -68.159122) (xy 143.763197 -68.198006) (xy 143.796886 -68.27898)
			(xy 143.822451 -68.362874) (xy 143.839643 -68.448874) (xy 143.848295 -68.536149) (xy 143.848836 -68.58)
			(xy 143.848317 -68.623763) (xy 143.839718 -68.710864) (xy 143.822612 -68.796702) (xy 143.797165 -68.880446)
			(xy 143.763623 -68.961289) (xy 143.743426 -69.000116) (xy 143.738194 -69.011509) (xy 143.738307 -69.036544)
			(xy 143.74368 -69.047868) (xy 143.763943 -69.086781) (xy 143.797578 -69.167817) (xy 143.804198 -69.1896)
			(xy 177.667872 -69.1896) (xy 177.671902 -69.104995) (xy 177.683957 -69.021157) (xy 177.703926 -68.938844)
			(xy 177.73163 -68.858802) (xy 177.766817 -68.781756) (xy 177.809168 -68.708404) (xy 177.8583 -68.639409)
			(xy 177.913768 -68.575398) (xy 177.97507 -68.516949) (xy 178.041651 -68.464592) (xy 178.112907 -68.418801)
			(xy 178.188193 -68.379991) (xy 178.266827 -68.348514) (xy 178.348098 -68.324653) (xy 178.431268 -68.308627)
			(xy 178.515586 -68.300578) (xy 178.557936 -68.300092) (xy 178.558444 -68.300092) (xy 178.597192 -68.300509)
			(xy 178.674394 -68.307273) (xy 178.750714 -68.320729) (xy 178.825573 -68.340774) (xy 178.898405 -68.367256)
			(xy 178.968657 -68.399975) (xy 179.002436 -68.418964) (xy 179.01031 -68.423123) (xy 179.027836 -68.426217)
			(xy 179.045362 -68.423123) (xy 179.053236 -68.418964) (xy 179.087017 -68.399978) (xy 179.157269 -68.367265)
			(xy 179.230101 -68.340786) (xy 179.304961 -68.320743) (xy 179.38128 -68.307289) (xy 179.45848 -68.300524)
			(xy 179.497228 -68.300092) (xy 179.497736 -68.300092) (xy 179.540083 -68.300597) (xy 179.624394 -68.308651)
			(xy 179.707558 -68.324683) (xy 179.788821 -68.348547) (xy 179.867448 -68.380027) (xy 179.942727 -68.418839)
			(xy 180.013976 -68.46463) (xy 180.080549 -68.516986) (xy 180.141844 -68.575434) (xy 180.197307 -68.639443)
			(xy 180.246433 -68.708434) (xy 180.28878 -68.781782) (xy 180.323962 -68.858824) (xy 180.351663 -68.938861)
			(xy 180.37163 -69.021168) (xy 180.383683 -69.105001) (xy 180.387713 -69.1896) (xy 180.383683 -69.274199)
			(xy 180.37163 -69.358032) (xy 180.351663 -69.440339) (xy 180.350534 -69.4436) (xy 181.326028 -69.4436)
			(xy 181.326532 -69.401252) (xy 181.334583 -69.316938) (xy 181.350612 -69.233772) (xy 181.374473 -69.152505)
			(xy 181.405952 -69.073875) (xy 181.444763 -68.998594) (xy 181.490553 -68.927342) (xy 181.542909 -68.860766)
			(xy 181.601357 -68.799468) (xy 181.665367 -68.744003) (xy 181.734359 -68.694874) (xy 181.807709 -68.652525)
			(xy 181.884752 -68.617341) (xy 181.964791 -68.589639) (xy 182.0471 -68.569671) (xy 182.130935 -68.557618)
			(xy 182.215536 -68.553588) (xy 182.300137 -68.557618) (xy 182.383972 -68.569671) (xy 182.426549 -68.58)
			(xy 183.920388 -68.58) (xy 183.924418 -68.495399) (xy 183.936471 -68.411564) (xy 183.956439 -68.329255)
			(xy 183.984141 -68.249216) (xy 184.019325 -68.172173) (xy 184.061674 -68.098823) (xy 184.110803 -68.029831)
			(xy 184.166268 -67.965821) (xy 184.227566 -67.907373) (xy 184.294142 -67.855017) (xy 184.365394 -67.809227)
			(xy 184.440675 -67.770416) (xy 184.519305 -67.738937) (xy 184.600572 -67.715076) (xy 184.683738 -67.699047)
			(xy 184.768052 -67.690996) (xy 184.8104 -67.690492) (xy 184.810908 -67.690492) (xy 184.85724 -67.691098)
			(xy 184.949398 -67.700769) (xy 185.040052 -67.719965) (xy 185.128221 -67.748477) (xy 185.170826 -67.766692)
			(xy 185.180768 -67.770498) (xy 185.202032 -67.770498) (xy 185.211974 -67.766692) (xy 185.254577 -67.74847)
			(xy 185.342744 -67.719952) (xy 185.4334 -67.70076) (xy 185.52556 -67.6911) (xy 185.571892 -67.690492)
			(xy 185.5724 -67.690492) (xy 185.614748 -67.690996) (xy 185.699062 -67.699047) (xy 185.782228 -67.715076)
			(xy 185.863495 -67.738937) (xy 185.942125 -67.770416) (xy 186.017406 -67.809227) (xy 186.088658 -67.855017)
			(xy 186.155234 -67.907373) (xy 186.216532 -67.965821) (xy 186.271997 -68.029831) (xy 186.321126 -68.098823)
			(xy 186.363475 -68.172173) (xy 186.375726 -68.199) (xy 267.232388 -68.199) (xy 267.236418 -68.114399)
			(xy 267.248471 -68.030564) (xy 267.268439 -67.948255) (xy 267.296141 -67.868216) (xy 267.331325 -67.791173)
			(xy 267.373674 -67.717823) (xy 267.422803 -67.648831) (xy 267.478268 -67.584821) (xy 267.539566 -67.526373)
			(xy 267.606142 -67.474017) (xy 267.677394 -67.428227) (xy 267.752675 -67.389416) (xy 267.831305 -67.357937)
			(xy 267.912572 -67.334076) (xy 267.995738 -67.318047) (xy 268.080052 -67.309996) (xy 268.1224 -67.309492)
			(xy 268.122908 -67.309492) (xy 268.161656 -67.309926) (xy 268.238857 -67.316687) (xy 268.315177 -67.330139)
			(xy 268.390036 -67.350181) (xy 268.462869 -67.37666) (xy 268.53312 -67.409376) (xy 268.5669 -67.428364)
			(xy 268.574774 -67.432523) (xy 268.5923 -67.435617) (xy 268.609826 -67.432523) (xy 268.6177 -67.428364)
			(xy 268.651489 -67.409393) (xy 268.721739 -67.376677) (xy 268.79457 -67.350196) (xy 268.869428 -67.330151)
			(xy 268.945745 -67.316693) (xy 269.022945 -67.309925) (xy 269.061692 -67.309492) (xy 269.0622 -67.309492)
			(xy 269.104548 -67.309996) (xy 269.188862 -67.318047) (xy 269.272028 -67.334076) (xy 269.353295 -67.357937)
			(xy 269.431925 -67.389416) (xy 269.507206 -67.428227) (xy 269.578458 -67.474017) (xy 269.645034 -67.526373)
			(xy 269.706332 -67.584821) (xy 269.761797 -67.648831) (xy 269.810926 -67.717823) (xy 269.853275 -67.791173)
			(xy 269.888459 -67.868216) (xy 269.916161 -67.948255) (xy 269.936129 -68.030564) (xy 269.948182 -68.114399)
			(xy 269.952213 -68.199) (xy 269.948182 -68.283601) (xy 269.936129 -68.367436) (xy 269.916161 -68.449745)
			(xy 269.888459 -68.529784) (xy 269.853275 -68.606827) (xy 269.810926 -68.680177) (xy 269.761797 -68.749169)
			(xy 269.706332 -68.813179) (xy 269.645034 -68.871627) (xy 269.578458 -68.923983) (xy 269.507206 -68.969773)
			(xy 269.431925 -69.008584) (xy 269.353295 -69.040063) (xy 269.272028 -69.063924) (xy 269.188862 -69.079953)
			(xy 269.104548 -69.088004) (xy 269.0622 -69.088508) (xy 269.061692 -69.088508) (xy 269.022944 -69.088074)
			(xy 268.945743 -69.081313) (xy 268.869423 -69.067861) (xy 268.794564 -69.047819) (xy 268.721731 -69.02134)
			(xy 268.65148 -68.988624) (xy 268.6177 -68.969636) (xy 268.609826 -68.965477) (xy 268.5923 -68.962383)
			(xy 268.574774 -68.965477) (xy 268.5669 -68.969636) (xy 268.533111 -68.988607) (xy 268.462861 -69.021323)
			(xy 268.39003 -69.047804) (xy 268.315172 -69.067849) (xy 268.238855 -69.081307) (xy 268.161655 -69.088075)
			(xy 268.122908 -69.088508) (xy 268.1224 -69.088508) (xy 268.080052 -69.088004) (xy 267.995738 -69.079953)
			(xy 267.912572 -69.063924) (xy 267.831305 -69.040063) (xy 267.752675 -69.008584) (xy 267.677394 -68.969773)
			(xy 267.606142 -68.923983) (xy 267.539566 -68.871627) (xy 267.478268 -68.813179) (xy 267.422803 -68.749169)
			(xy 267.373674 -68.680177) (xy 267.331325 -68.606827) (xy 267.296141 -68.529784) (xy 267.268439 -68.449745)
			(xy 267.248471 -68.367436) (xy 267.236418 -68.283601) (xy 267.232388 -68.199) (xy 186.375726 -68.199)
			(xy 186.398659 -68.249216) (xy 186.426361 -68.329255) (xy 186.446329 -68.411564) (xy 186.458382 -68.495399)
			(xy 186.462413 -68.58) (xy 186.458382 -68.664601) (xy 186.446329 -68.748436) (xy 186.426361 -68.830745)
			(xy 186.398659 -68.910784) (xy 186.363475 -68.987827) (xy 186.321126 -69.061177) (xy 186.271997 -69.130169)
			(xy 186.216532 -69.194179) (xy 186.155234 -69.252627) (xy 186.088658 -69.304983) (xy 186.023153 -69.34708)
			(xy 263.981692 -69.34708) (xy 263.982196 -69.304732) (xy 263.990247 -69.220418) (xy 264.006276 -69.137252)
			(xy 264.030137 -69.055985) (xy 264.061616 -68.977355) (xy 264.100427 -68.902074) (xy 264.146217 -68.830822)
			(xy 264.198573 -68.764246) (xy 264.257021 -68.702948) (xy 264.321031 -68.647483) (xy 264.390023 -68.598354)
			(xy 264.463373 -68.556005) (xy 264.540416 -68.520821) (xy 264.620455 -68.493119) (xy 264.702764 -68.473151)
			(xy 264.786599 -68.461098) (xy 264.8712 -68.457068) (xy 264.955801 -68.461098) (xy 265.039636 -68.473151)
			(xy 265.121945 -68.493119) (xy 265.201984 -68.520821) (xy 265.279027 -68.556005) (xy 265.352377 -68.598354)
			(xy 265.421369 -68.647483) (xy 265.485379 -68.702948) (xy 265.543827 -68.764246) (xy 265.596183 -68.830822)
			(xy 265.641973 -68.902074) (xy 265.680784 -68.977355) (xy 265.712263 -69.055985) (xy 265.736124 -69.137252)
			(xy 265.752153 -69.220418) (xy 265.760204 -69.304732) (xy 265.760708 -69.34708) (xy 265.760708 -69.347842)
			(xy 265.760124 -69.39309) (xy 265.750905 -69.483115) (xy 265.732585 -69.571738) (xy 265.705356 -69.658041)
			(xy 265.669499 -69.74113) (xy 265.647932 -69.780912) (xy 265.643026 -69.790878) (xy 265.641461 -69.813015)
			(xy 265.644884 -69.823584) (xy 265.676126 -69.906896) (xy 265.691874 -69.92239) (xy 265.702542 -69.9262)
			(xy 265.741999 -69.940786) (xy 265.818247 -69.976332) (xy 265.8908 -70.018917) (xy 265.959008 -70.068161)
			(xy 266.022264 -70.123623) (xy 266.080001 -70.184809) (xy 266.131705 -70.251172) (xy 266.176914 -70.322119)
			(xy 266.215223 -70.397017) (xy 266.246292 -70.475197) (xy 266.269842 -70.55596) (xy 266.285663 -70.638586)
			(xy 266.293613 -70.722337) (xy 266.294108 -70.7644) (xy 266.293604 -70.806748) (xy 266.285553 -70.891062)
			(xy 266.269524 -70.974228) (xy 266.256555 -71.0184) (xy 267.232388 -71.0184) (xy 267.236418 -70.933799)
			(xy 267.248471 -70.849964) (xy 267.268439 -70.767655) (xy 267.296141 -70.687616) (xy 267.331325 -70.610573)
			(xy 267.373674 -70.537223) (xy 267.422803 -70.468231) (xy 267.478268 -70.404221) (xy 267.539566 -70.345773)
			(xy 267.606142 -70.293417) (xy 267.677394 -70.247627) (xy 267.752675 -70.208816) (xy 267.831305 -70.177337)
			(xy 267.912572 -70.153476) (xy 267.995738 -70.137447) (xy 268.080052 -70.129396) (xy 268.1224 -70.128892)
			(xy 268.122908 -70.128892) (xy 268.161656 -70.129326) (xy 268.238857 -70.136087) (xy 268.315177 -70.149539)
			(xy 268.390036 -70.169581) (xy 268.462869 -70.19606) (xy 268.53312 -70.228776) (xy 268.5669 -70.247764)
			(xy 268.574774 -70.251923) (xy 268.5923 -70.255017) (xy 268.609826 -70.251923) (xy 268.6177 -70.247764)
			(xy 268.651489 -70.228793) (xy 268.721739 -70.196077) (xy 268.79457 -70.169596) (xy 268.869428 -70.149551)
			(xy 268.945745 -70.136093) (xy 269.022945 -70.129325) (xy 269.061692 -70.128892) (xy 269.0622 -70.128892)
			(xy 269.104548 -70.129396) (xy 269.188862 -70.137447) (xy 269.272028 -70.153476) (xy 269.353295 -70.177337)
			(xy 269.431925 -70.208816) (xy 269.507206 -70.247627) (xy 269.578458 -70.293417) (xy 269.645034 -70.345773)
			(xy 269.706332 -70.404221) (xy 269.761797 -70.468231) (xy 269.810926 -70.537223) (xy 269.853275 -70.610573)
			(xy 269.888459 -70.687616) (xy 269.916161 -70.767655) (xy 269.936129 -70.849964) (xy 269.948182 -70.933799)
			(xy 269.952213 -71.0184) (xy 269.948182 -71.103001) (xy 269.936129 -71.186836) (xy 269.916161 -71.269145)
			(xy 269.888459 -71.349184) (xy 269.853275 -71.426227) (xy 269.810926 -71.499577) (xy 269.761797 -71.568569)
			(xy 269.706332 -71.632579) (xy 269.645034 -71.691027) (xy 269.578458 -71.743383) (xy 269.507206 -71.789173)
			(xy 269.431925 -71.827984) (xy 269.353295 -71.859463) (xy 269.272028 -71.883324) (xy 269.188862 -71.899353)
			(xy 269.104548 -71.907404) (xy 269.0622 -71.907908) (xy 269.061692 -71.907908) (xy 269.022944 -71.907474)
			(xy 268.945743 -71.900713) (xy 268.869423 -71.887261) (xy 268.794564 -71.867219) (xy 268.721731 -71.84074)
			(xy 268.65148 -71.808024) (xy 268.6177 -71.789036) (xy 268.609826 -71.784877) (xy 268.5923 -71.781783)
			(xy 268.574774 -71.784877) (xy 268.5669 -71.789036) (xy 268.533111 -71.808007) (xy 268.462861 -71.840723)
			(xy 268.39003 -71.867204) (xy 268.315172 -71.887249) (xy 268.238855 -71.900707) (xy 268.161655 -71.907475)
			(xy 268.122908 -71.907908) (xy 268.1224 -71.907908) (xy 268.080052 -71.907404) (xy 267.995738 -71.899353)
			(xy 267.912572 -71.883324) (xy 267.831305 -71.859463) (xy 267.752675 -71.827984) (xy 267.677394 -71.789173)
			(xy 267.606142 -71.743383) (xy 267.539566 -71.691027) (xy 267.478268 -71.632579) (xy 267.422803 -71.568569)
			(xy 267.373674 -71.499577) (xy 267.331325 -71.426227) (xy 267.296141 -71.349184) (xy 267.268439 -71.269145)
			(xy 267.248471 -71.186836) (xy 267.236418 -71.103001) (xy 267.232388 -71.0184) (xy 266.256555 -71.0184)
			(xy 266.245663 -71.055495) (xy 266.214184 -71.134125) (xy 266.175373 -71.209406) (xy 266.129583 -71.280658)
			(xy 266.077227 -71.347234) (xy 266.018779 -71.408532) (xy 265.954769 -71.463997) (xy 265.885777 -71.513126)
			(xy 265.812427 -71.555475) (xy 265.735384 -71.590659) (xy 265.655345 -71.618361) (xy 265.573036 -71.638329)
			(xy 265.489201 -71.650382) (xy 265.4046 -71.654413) (xy 265.319999 -71.650382) (xy 265.236164 -71.638329)
			(xy 265.153855 -71.618361) (xy 265.073816 -71.590659) (xy 264.996773 -71.555475) (xy 264.923423 -71.513126)
			(xy 264.854431 -71.463997) (xy 264.790421 -71.408532) (xy 264.731973 -71.347234) (xy 264.679617 -71.280658)
			(xy 264.633827 -71.209406) (xy 264.595016 -71.134125) (xy 264.563537 -71.055495) (xy 264.539676 -70.974228)
			(xy 264.523647 -70.891062) (xy 264.515596 -70.806748) (xy 264.515092 -70.7644) (xy 264.515092 -70.763638)
			(xy 264.515667 -70.71839) (xy 264.524889 -70.628364) (xy 264.54321 -70.539741) (xy 264.570441 -70.453439)
			(xy 264.6063 -70.37035) (xy 264.627868 -70.330568) (xy 264.632726 -70.320583) (xy 264.634321 -70.298463)
			(xy 264.630916 -70.287896) (xy 264.599674 -70.204584) (xy 264.583926 -70.18909) (xy 264.573258 -70.18528)
			(xy 264.533794 -70.170712) (xy 264.457545 -70.135164) (xy 264.384993 -70.092578) (xy 264.316784 -70.043333)
			(xy 264.253528 -69.987869) (xy 264.195791 -69.926681) (xy 264.144087 -69.860317) (xy 264.098879 -69.789368)
			(xy 264.06057 -69.714469) (xy 264.029503 -69.636288) (xy 264.005954 -69.555523) (xy 263.990135 -69.472895)
			(xy 263.982186 -69.389144) (xy 263.981692 -69.34708) (xy 186.023153 -69.34708) (xy 186.017406 -69.350773)
			(xy 185.942125 -69.389584) (xy 185.863495 -69.421063) (xy 185.782228 -69.444924) (xy 185.699062 -69.460953)
			(xy 185.614748 -69.469004) (xy 185.5724 -69.469508) (xy 185.571892 -69.469508) (xy 185.52556 -69.468902)
			(xy 185.433402 -69.459231) (xy 185.342748 -69.440035) (xy 185.254579 -69.411523) (xy 185.211974 -69.393308)
			(xy 185.202032 -69.389502) (xy 185.180768 -69.389502) (xy 185.170826 -69.393308) (xy 185.128223 -69.41153)
			(xy 185.040056 -69.440048) (xy 184.9494 -69.45924) (xy 184.85724 -69.4689) (xy 184.810908 -69.469508)
			(xy 184.8104 -69.469508) (xy 184.768052 -69.469004) (xy 184.683738 -69.460953) (xy 184.600572 -69.444924)
			(xy 184.519305 -69.421063) (xy 184.440675 -69.389584) (xy 184.365394 -69.350773) (xy 184.294142 -69.304983)
			(xy 184.227566 -69.252627) (xy 184.166268 -69.194179) (xy 184.110803 -69.130169) (xy 184.061674 -69.061177)
			(xy 184.019325 -68.987827) (xy 183.984141 -68.910784) (xy 183.956439 -68.830745) (xy 183.936471 -68.748436)
			(xy 183.924418 -68.664601) (xy 183.920388 -68.58) (xy 182.426549 -68.58) (xy 182.466281 -68.589639)
			(xy 182.54632 -68.617341) (xy 182.623363 -68.652525) (xy 182.696713 -68.694874) (xy 182.765705 -68.744003)
			(xy 182.829715 -68.799468) (xy 182.888163 -68.860766) (xy 182.940519 -68.927342) (xy 182.986309 -68.998594)
			(xy 183.02512 -69.073875) (xy 183.056599 -69.152505) (xy 183.08046 -69.233772) (xy 183.096489 -69.316938)
			(xy 183.10454 -69.401252) (xy 183.105044 -69.4436) (xy 183.105044 -69.444362) (xy 183.104477 -69.489611)
			(xy 183.095255 -69.579637) (xy 183.076932 -69.66826) (xy 183.049699 -69.754562) (xy 183.013837 -69.837651)
			(xy 182.992268 -69.877432) (xy 182.98741 -69.887417) (xy 182.985813 -69.909537) (xy 182.98922 -69.920104)
			(xy 183.020462 -70.003416) (xy 183.03621 -70.01891) (xy 183.046878 -70.02272) (xy 183.08635 -70.037268)
			(xy 183.162598 -70.072818) (xy 183.23515 -70.115407) (xy 183.303358 -70.164655) (xy 183.366613 -70.220121)
			(xy 183.424349 -70.28131) (xy 183.476052 -70.347676) (xy 183.521259 -70.418626) (xy 183.559567 -70.493527)
			(xy 183.590634 -70.571709) (xy 183.614182 -70.652475) (xy 183.630002 -70.735103) (xy 183.63795 -70.818856)
			(xy 183.638444 -70.86092) (xy 183.63794 -70.903268) (xy 183.629889 -70.987582) (xy 183.61386 -71.070748)
			(xy 183.589999 -71.152015) (xy 183.55852 -71.230645) (xy 183.519709 -71.305926) (xy 183.473919 -71.377178)
			(xy 183.421563 -71.443754) (xy 183.363115 -71.505052) (xy 183.299105 -71.560517) (xy 183.275677 -71.5772)
			(xy 260.602988 -71.5772) (xy 260.607018 -71.492599) (xy 260.619071 -71.408764) (xy 260.639039 -71.326455)
			(xy 260.666741 -71.246416) (xy 260.701925 -71.169373) (xy 260.744274 -71.096023) (xy 260.793403 -71.027031)
			(xy 260.848868 -70.963021) (xy 260.910166 -70.904573) (xy 260.976742 -70.852217) (xy 261.047994 -70.806427)
			(xy 261.123275 -70.767616) (xy 261.201905 -70.736137) (xy 261.283172 -70.712276) (xy 261.366338 -70.696247)
			(xy 261.450652 -70.688196) (xy 261.493 -70.687692) (xy 261.493508 -70.687692) (xy 261.53984 -70.688298)
			(xy 261.631998 -70.697969) (xy 261.722652 -70.717165) (xy 261.810821 -70.745677) (xy 261.853426 -70.763892)
			(xy 261.863368 -70.767698) (xy 261.884632 -70.767698) (xy 261.894574 -70.763892) (xy 261.937177 -70.74567)
			(xy 262.025344 -70.717152) (xy 262.116 -70.69796) (xy 262.20816 -70.6883) (xy 262.254492 -70.687692)
			(xy 262.255 -70.687692) (xy 262.297348 -70.688196) (xy 262.381662 -70.696247) (xy 262.464828 -70.712276)
			(xy 262.546095 -70.736137) (xy 262.624725 -70.767616) (xy 262.700006 -70.806427) (xy 262.771258 -70.852217)
			(xy 262.837834 -70.904573) (xy 262.899132 -70.963021) (xy 262.954597 -71.027031) (xy 263.003726 -71.096023)
			(xy 263.046075 -71.169373) (xy 263.081259 -71.246416) (xy 263.108961 -71.326455) (xy 263.128929 -71.408764)
			(xy 263.140982 -71.492599) (xy 263.145013 -71.5772) (xy 263.140982 -71.661801) (xy 263.128929 -71.745636)
			(xy 263.108961 -71.827945) (xy 263.081259 -71.907984) (xy 263.046075 -71.985027) (xy 263.003726 -72.058377)
			(xy 262.954597 -72.127369) (xy 262.899132 -72.191379) (xy 262.837834 -72.249827) (xy 262.771258 -72.302183)
			(xy 262.700006 -72.347973) (xy 262.624725 -72.386784) (xy 262.546095 -72.418263) (xy 262.464828 -72.442124)
			(xy 262.381662 -72.458153) (xy 262.297348 -72.466204) (xy 262.255 -72.466708) (xy 262.254492 -72.466708)
			(xy 262.20816 -72.466102) (xy 262.116002 -72.456431) (xy 262.025348 -72.437235) (xy 261.937179 -72.408723)
			(xy 261.894574 -72.390508) (xy 261.884632 -72.386702) (xy 261.863368 -72.386702) (xy 261.853426 -72.390508)
			(xy 261.810823 -72.40873) (xy 261.722656 -72.437248) (xy 261.632 -72.45644) (xy 261.53984 -72.4661)
			(xy 261.493508 -72.466708) (xy 261.493 -72.466708) (xy 261.450652 -72.466204) (xy 261.366338 -72.458153)
			(xy 261.283172 -72.442124) (xy 261.201905 -72.418263) (xy 261.123275 -72.386784) (xy 261.047994 -72.347973)
			(xy 260.976742 -72.302183) (xy 260.910166 -72.249827) (xy 260.848868 -72.191379) (xy 260.793403 -72.127369)
			(xy 260.744274 -72.058377) (xy 260.701925 -71.985027) (xy 260.666741 -71.907984) (xy 260.639039 -71.827945)
			(xy 260.619071 -71.745636) (xy 260.607018 -71.661801) (xy 260.602988 -71.5772) (xy 183.275677 -71.5772)
			(xy 183.230113 -71.609646) (xy 183.156763 -71.651995) (xy 183.07972 -71.687179) (xy 182.999681 -71.714881)
			(xy 182.917372 -71.734849) (xy 182.833537 -71.746902) (xy 182.748936 -71.750933) (xy 182.664335 -71.746902)
			(xy 182.5805 -71.734849) (xy 182.498191 -71.714881) (xy 182.418152 -71.687179) (xy 182.341109 -71.651995)
			(xy 182.267759 -71.609646) (xy 182.198767 -71.560517) (xy 182.134757 -71.505052) (xy 182.076309 -71.443754)
			(xy 182.023953 -71.377178) (xy 181.978163 -71.305926) (xy 181.939352 -71.230645) (xy 181.907873 -71.152015)
			(xy 181.884012 -71.070748) (xy 181.867983 -70.987582) (xy 181.859932 -70.903268) (xy 181.859428 -70.86092)
			(xy 181.859428 -70.860158) (xy 181.860007 -70.81491) (xy 181.869227 -70.724884) (xy 181.887547 -70.636261)
			(xy 181.914778 -70.549959) (xy 181.950636 -70.466869) (xy 181.972204 -70.427088) (xy 181.977111 -70.417122)
			(xy 181.978678 -70.394985) (xy 181.975252 -70.384416) (xy 181.94401 -70.301104) (xy 181.928262 -70.28561)
			(xy 181.917594 -70.2818) (xy 181.878145 -70.267193) (xy 181.801896 -70.23165) (xy 181.729343 -70.189068)
			(xy 181.661134 -70.139826) (xy 181.597877 -70.084366) (xy 181.540139 -70.023182) (xy 181.488434 -69.956821)
			(xy 181.443225 -69.885875) (xy 181.404914 -69.810979) (xy 181.373845 -69.7328) (xy 181.350295 -69.652037)
			(xy 181.334473 -69.569413) (xy 181.326523 -69.485663) (xy 181.326028 -69.4436) (xy 180.350534 -69.4436)
			(xy 180.323962 -69.520376) (xy 180.28878 -69.597418) (xy 180.246433 -69.670766) (xy 180.197307 -69.739757)
			(xy 180.141844 -69.803766) (xy 180.080549 -69.862214) (xy 180.013976 -69.91457) (xy 179.942727 -69.960361)
			(xy 179.867448 -69.999173) (xy 179.788821 -70.030653) (xy 179.707558 -70.054517) (xy 179.624394 -70.070549)
			(xy 179.540083 -70.078603) (xy 179.497736 -70.079108) (xy 179.497228 -70.079108) (xy 179.45848 -70.078658)
			(xy 179.38128 -70.0719) (xy 179.304961 -70.058451) (xy 179.230101 -70.038412) (xy 179.157268 -70.011936)
			(xy 179.087016 -69.979222) (xy 179.053236 -69.960236) (xy 179.045362 -69.956077) (xy 179.027836 -69.952983)
			(xy 179.01031 -69.956077) (xy 179.002436 -69.960236) (xy 178.968662 -69.979233) (xy 178.898407 -70.011945)
			(xy 178.825574 -70.038422) (xy 178.750713 -70.058462) (xy 178.674393 -70.071915) (xy 178.597192 -70.078678)
			(xy 178.558444 -70.079108) (xy 178.557936 -70.079108) (xy 178.515586 -70.078622) (xy 178.431268 -70.070573)
			(xy 178.348098 -70.054547) (xy 178.266827 -70.030686) (xy 178.188193 -69.999209) (xy 178.112907 -69.960399)
			(xy 178.041651 -69.914608) (xy 177.97507 -69.862251) (xy 177.913768 -69.803802) (xy 177.8583 -69.739791)
			(xy 177.809168 -69.670796) (xy 177.766817 -69.597444) (xy 177.73163 -69.520398) (xy 177.703926 -69.440356)
			(xy 177.683957 -69.358043) (xy 177.671902 -69.274205) (xy 177.667872 -69.1896) (xy 143.804198 -69.1896)
			(xy 143.823089 -69.251765) (xy 143.840228 -69.337814) (xy 143.848829 -69.42513) (xy 143.849344 -69.469)
			(xy 143.848824 -69.512819) (xy 143.840185 -69.60003) (xy 143.82303 -69.685972) (xy 143.797525 -69.769817)
			(xy 143.763915 -69.850753) (xy 143.74368 -69.889624) (xy 143.738368 -69.90098) (xy 143.738368 -69.92602)
			(xy 143.74368 -69.937376) (xy 143.763922 -69.976244) (xy 143.797557 -70.057173) (xy 143.82307 -70.141017)
			(xy 143.840214 -70.226964) (xy 143.848823 -70.31418) (xy 143.849344 -70.358) (xy 143.84884 -70.400397)
			(xy 143.84078 -70.484807) (xy 143.824732 -70.568068) (xy 143.800843 -70.649427) (xy 143.769328 -70.728147)
			(xy 143.730474 -70.803515) (xy 143.684631 -70.874848) (xy 143.632215 -70.9415) (xy 143.5737 -71.002868)
			(xy 143.509618 -71.058396) (xy 143.440547 -71.107581) (xy 143.367113 -71.149978) (xy 143.289982 -71.185203)
			(xy 143.209852 -71.212936) (xy 143.127448 -71.232927) (xy 143.043518 -71.244994) (xy 142.95882 -71.249029)
			(xy 142.874122 -71.244994) (xy 142.790192 -71.232927) (xy 142.707788 -71.212936) (xy 142.627658 -71.185203)
			(xy 142.550527 -71.149978) (xy 142.477093 -71.107581) (xy 142.408022 -71.058396) (xy 142.34394 -71.002868)
			(xy 142.285425 -70.9415) (xy 142.233009 -70.874848) (xy 142.187166 -70.803515) (xy 142.148312 -70.728147)
			(xy 142.116797 -70.649427) (xy 142.092908 -70.568068) (xy 142.07686 -70.484807) (xy 142.0688 -70.400397)
			(xy 142.068296 -70.358) (xy 142.068812 -70.314181) (xy 142.077451 -70.22697) (xy 142.094607 -70.141027)
			(xy 142.120113 -70.057183) (xy 142.153725 -69.976247) (xy 142.17396 -69.937376) (xy 142.179269 -69.92602)
			(xy 142.179269 -69.90098) (xy 142.17396 -69.889624) (xy 142.153713 -69.850758) (xy 142.12008 -69.769829)
			(xy 142.094568 -69.685984) (xy 142.077425 -69.600037) (xy 142.068817 -69.51282) (xy 142.068296 -69.469)
			(xy 142.068784 -69.425129) (xy 142.077376 -69.337809) (xy 142.094516 -69.251758) (xy 142.120037 -69.16781)
			(xy 142.153693 -69.08678) (xy 142.17396 -69.047868) (xy 142.179366 -69.036553) (xy 142.179479 -69.0115)
			(xy 142.174214 -69.000116) (xy 142.154023 -68.961286) (xy 142.120474 -68.880446) (xy 142.095025 -68.796702)
			(xy 142.07792 -68.710865) (xy 142.069327 -68.623763) (xy 142.068804 -68.58) (xy 142.069352 -68.536149)
			(xy 142.077992 -68.448872) (xy 142.095177 -68.362869) (xy 142.120741 -68.278975) (xy 142.154437 -68.198003)
			(xy 142.174722 -68.159122) (xy 142.180144 -68.147657) (xy 142.18014 -68.122329) (xy 142.174722 -68.110862)
			(xy 142.154472 -68.071891) (xy 142.120849 -67.990752) (xy 142.095381 -67.906695) (xy 142.08633 -67.86372)
			(xy 142.082774 -67.845686) (xy 142.054834 -67.822826) (xy 140.90904 -67.822826) (xy 140.89952 -67.823236)
			(xy 140.881795 -67.830194) (xy 140.867822 -67.84313) (xy 140.86332 -67.851528) (xy 140.844752 -67.888594)
			(xy 140.801694 -67.959444) (xy 140.752233 -68.025982) (xy 140.696797 -68.08763) (xy 140.635867 -68.143854)
			(xy 140.56997 -68.194166) (xy 140.49968 -68.238131) (xy 140.425604 -68.275367) (xy 140.348386 -68.30555)
			(xy 140.268695 -68.32842) (xy 140.187222 -68.343777) (xy 140.104674 -68.351489) (xy 140.021766 -68.351489)
			(xy 139.939218 -68.343777) (xy 139.857745 -68.32842) (xy 139.778054 -68.30555) (xy 139.700836 -68.275367)
			(xy 139.62676 -68.238131) (xy 139.55647 -68.194166) (xy 139.490573 -68.143854) (xy 139.429643 -68.08763)
			(xy 139.374207 -68.025982) (xy 139.324746 -67.959444) (xy 139.281688 -67.888594) (xy 139.26312 -67.851528)
			(xy 139.258628 -67.843121) (xy 139.244657 -67.830174) (xy 139.226924 -67.823221) (xy 139.2174 -67.822826)
			(xy 138.0871 -67.822826) (xy 138.07703 -67.823245) (xy 138.058432 -67.830969) (xy 138.051032 -67.837812)
			(xy 137.389616 -68.499228) (xy 137.382773 -68.506626) (xy 137.375054 -68.525227) (xy 137.37463 -68.535296)
			(xy 137.37463 -71.85406) (xy 149.046184 -71.85406) (xy 149.046695 -71.811643) (xy 149.054765 -71.727194)
			(xy 149.070836 -71.643896) (xy 149.094764 -71.562507) (xy 149.12633 -71.483764) (xy 149.165248 -71.408384)
			(xy 149.211164 -71.33705) (xy 149.263662 -71.270412) (xy 149.322265 -71.209073) (xy 149.354032 -71.18096)
			(xy 149.361938 -71.173399) (xy 149.371032 -71.153531) (xy 149.371558 -71.142606) (xy 149.371558 -71.06539)
			(xy 149.371056 -71.054461) (xy 149.361953 -71.034585) (xy 149.354032 -71.027036) (xy 149.322275 -70.998912)
			(xy 149.263673 -70.937573) (xy 149.211174 -70.870935) (xy 149.165256 -70.799603) (xy 149.126335 -70.724225)
			(xy 149.094765 -70.645485) (xy 149.070832 -70.564097) (xy 149.054754 -70.480801) (xy 149.046677 -70.396353)
			(xy 149.046184 -70.353936) (xy 149.046688 -70.311588) (xy 149.054739 -70.227274) (xy 149.070768 -70.144108)
			(xy 149.094629 -70.062841) (xy 149.126108 -69.984211) (xy 149.164919 -69.90893) (xy 149.210709 -69.837678)
			(xy 149.263065 -69.771102) (xy 149.321513 -69.709804) (xy 149.385523 -69.654339) (xy 149.454515 -69.60521)
			(xy 149.527865 -69.562861) (xy 149.604908 -69.527677) (xy 149.684947 -69.499975) (xy 149.767256 -69.480007)
			(xy 149.851091 -69.467954) (xy 149.935692 -69.463924) (xy 150.020293 -69.467954) (xy 150.104128 -69.480007)
			(xy 150.186437 -69.499975) (xy 150.266476 -69.527677) (xy 150.343519 -69.562861) (xy 150.416869 -69.60521)
			(xy 150.485861 -69.654339) (xy 150.549871 -69.709804) (xy 150.608319 -69.771102) (xy 150.660675 -69.837678)
			(xy 150.706465 -69.90893) (xy 150.745276 -69.984211) (xy 150.776755 -70.062841) (xy 150.800616 -70.144108)
			(xy 150.816645 -70.227274) (xy 150.824696 -70.311588) (xy 150.8252 -70.353936) (xy 150.824691 -70.396353)
			(xy 150.816622 -70.480803) (xy 150.800551 -70.5641) (xy 150.776623 -70.64549) (xy 150.745057 -70.724233)
			(xy 150.706139 -70.799613) (xy 150.660221 -70.870946) (xy 150.607723 -70.937585) (xy 150.549119 -70.998924)
			(xy 150.517352 -71.027036) (xy 150.509446 -71.034596) (xy 150.500353 -71.054465) (xy 150.499826 -71.06539)
			(xy 150.499826 -71.142606) (xy 150.500336 -71.153534) (xy 150.509433 -71.173409) (xy 150.517352 -71.18096)
			(xy 150.549103 -71.20909) (xy 150.607707 -71.270428) (xy 150.660206 -71.337064) (xy 150.706125 -71.408396)
			(xy 150.745047 -71.483773) (xy 150.776617 -71.562513) (xy 150.800551 -71.6439) (xy 150.816629 -71.727196)
			(xy 150.824707 -71.811643) (xy 150.8252 -71.85406) (xy 150.824696 -71.896408) (xy 150.816645 -71.980722)
			(xy 150.811195 -72.009) (xy 177.667872 -72.009) (xy 177.671902 -71.924395) (xy 177.683957 -71.840557)
			(xy 177.703926 -71.758244) (xy 177.73163 -71.678202) (xy 177.766817 -71.601156) (xy 177.809168 -71.527804)
			(xy 177.8583 -71.458809) (xy 177.913768 -71.394798) (xy 177.97507 -71.336349) (xy 178.041651 -71.283992)
			(xy 178.112907 -71.238201) (xy 178.188193 -71.199391) (xy 178.266827 -71.167914) (xy 178.348098 -71.144053)
			(xy 178.431268 -71.128027) (xy 178.515586 -71.119978) (xy 178.557936 -71.119492) (xy 178.596727 -71.119889)
			(xy 178.674016 -71.126624) (xy 178.750424 -71.140065) (xy 178.825371 -71.16011) (xy 178.898288 -71.186607)
			(xy 178.968619 -71.219355) (xy 179.002436 -71.238364) (xy 179.01031 -71.242523) (xy 179.027836 -71.245617)
			(xy 179.045362 -71.242523) (xy 179.053236 -71.238364) (xy 179.087054 -71.219359) (xy 179.157387 -71.186616)
			(xy 179.230303 -71.160122) (xy 179.30525 -71.140079) (xy 179.381658 -71.126639) (xy 179.458946 -71.119903)
			(xy 179.497736 -71.119492) (xy 179.540083 -71.119997) (xy 179.624394 -71.128051) (xy 179.707558 -71.144083)
			(xy 179.788821 -71.167947) (xy 179.867448 -71.199427) (xy 179.942727 -71.238239) (xy 180.013976 -71.28403)
			(xy 180.080549 -71.336386) (xy 180.141844 -71.394834) (xy 180.197307 -71.458843) (xy 180.246433 -71.527834)
			(xy 180.28878 -71.601182) (xy 180.323962 -71.678224) (xy 180.351663 -71.758261) (xy 180.37163 -71.840568)
			(xy 180.383683 -71.924401) (xy 180.387713 -72.009) (xy 180.383683 -72.093599) (xy 180.37163 -72.177432)
			(xy 180.351663 -72.259739) (xy 180.323962 -72.339776) (xy 180.28878 -72.416818) (xy 180.246433 -72.490166)
			(xy 180.197307 -72.559157) (xy 180.141844 -72.623166) (xy 180.080549 -72.681614) (xy 180.013976 -72.73397)
			(xy 179.942727 -72.779761) (xy 179.867448 -72.818573) (xy 179.788821 -72.850053) (xy 179.707558 -72.873917)
			(xy 179.624394 -72.889949) (xy 179.540083 -72.898003) (xy 179.497736 -72.898508) (xy 179.458945 -72.898124)
			(xy 179.381656 -72.891387) (xy 179.305247 -72.877943) (xy 179.2303 -72.857895) (xy 179.157383 -72.831396)
			(xy 179.087053 -72.798646) (xy 179.053236 -72.779636) (xy 179.045362 -72.775477) (xy 179.027836 -72.772383)
			(xy 179.01031 -72.775477) (xy 179.002436 -72.779636) (xy 178.968624 -72.798653) (xy 178.89829 -72.831394)
			(xy 178.825372 -72.857885) (xy 178.750424 -72.877926) (xy 178.674015 -72.891365) (xy 178.596727 -72.898098)
			(xy 178.557936 -72.898508) (xy 178.515586 -72.898022) (xy 178.431268 -72.889973) (xy 178.348098 -72.873947)
			(xy 178.266827 -72.850086) (xy 178.188193 -72.818609) (xy 178.112907 -72.779799) (xy 178.041651 -72.734008)
			(xy 177.97507 -72.681651) (xy 177.913768 -72.623202) (xy 177.8583 -72.559191) (xy 177.809168 -72.490196)
			(xy 177.766817 -72.416844) (xy 177.73163 -72.339798) (xy 177.703926 -72.259756) (xy 177.683957 -72.177443)
			(xy 177.671902 -72.093605) (xy 177.667872 -72.009) (xy 150.811195 -72.009) (xy 150.800616 -72.063888)
			(xy 150.776755 -72.145155) (xy 150.745276 -72.223785) (xy 150.706465 -72.299066) (xy 150.660675 -72.370318)
			(xy 150.608319 -72.436894) (xy 150.549871 -72.498192) (xy 150.485861 -72.553657) (xy 150.416869 -72.602786)
			(xy 150.343519 -72.645135) (xy 150.266476 -72.680319) (xy 150.186437 -72.708021) (xy 150.104128 -72.727989)
			(xy 150.020293 -72.740042) (xy 149.935692 -72.744073) (xy 149.851091 -72.740042) (xy 149.767256 -72.727989)
			(xy 149.684947 -72.708021) (xy 149.604908 -72.680319) (xy 149.527865 -72.645135) (xy 149.454515 -72.602786)
			(xy 149.385523 -72.553657) (xy 149.321513 -72.498192) (xy 149.263065 -72.436894) (xy 149.210709 -72.370318)
			(xy 149.164919 -72.299066) (xy 149.126108 -72.223785) (xy 149.094629 -72.145155) (xy 149.070768 -72.063888)
			(xy 149.054739 -71.980722) (xy 149.046688 -71.896408) (xy 149.046184 -71.85406) (xy 137.37463 -71.85406)
			(xy 137.37463 -74.360278) (xy 144.226788 -74.360278) (xy 144.227274 -74.317132) (xy 144.23562 -74.231244)
			(xy 144.252241 -74.146568) (xy 144.276981 -74.063898) (xy 144.309607 -73.984012) (xy 144.349813 -73.907659)
			(xy 144.373092 -73.871328) (xy 144.377639 -73.863717) (xy 144.381747 -73.846485) (xy 144.37974 -73.828884)
			(xy 144.37614 -73.820782) (xy 144.358096 -73.78366) (xy 144.328174 -73.706728) (xy 144.305503 -73.627357)
			(xy 144.290279 -73.546227) (xy 144.28263 -73.464037) (xy 144.28216 -73.422764) (xy 144.28216 -73.42251)
			(xy 144.282664 -73.380162) (xy 144.290715 -73.295848) (xy 144.306744 -73.212682) (xy 144.330605 -73.131415)
			(xy 144.362084 -73.052785) (xy 144.400895 -72.977504) (xy 144.446685 -72.906252) (xy 144.499041 -72.839676)
			(xy 144.557489 -72.778378) (xy 144.621499 -72.722913) (xy 144.690491 -72.673784) (xy 144.763841 -72.631435)
			(xy 144.840884 -72.596251) (xy 144.920923 -72.568549) (xy 145.003232 -72.548581) (xy 145.087067 -72.536528)
			(xy 145.171668 -72.532498) (xy 145.256269 -72.536528) (xy 145.340104 -72.548581) (xy 145.422413 -72.568549)
			(xy 145.502452 -72.596251) (xy 145.579495 -72.631435) (xy 145.652845 -72.673784) (xy 145.721837 -72.722913)
			(xy 145.785847 -72.778378) (xy 145.844295 -72.839676) (xy 145.896651 -72.906252) (xy 145.942441 -72.977504)
			(xy 145.981252 -73.052785) (xy 146.012731 -73.131415) (xy 146.036592 -73.212682) (xy 146.052621 -73.295848)
			(xy 146.060672 -73.380162) (xy 146.061176 -73.42251) (xy 146.061176 -73.423272) (xy 146.060668 -73.466348)
			(xy 146.052315 -73.552094) (xy 146.035714 -73.636632) (xy 146.011019 -73.719169) (xy 145.978463 -73.798933)
			(xy 145.93835 -73.875177) (xy 145.915126 -73.91146) (xy 145.910587 -73.919075) (xy 145.906476 -73.936305)
			(xy 145.908479 -73.953905) (xy 145.912078 -73.962006) (xy 145.930176 -73.999137) (xy 145.960164 -74.076112)
			(xy 145.982889 -74.155534) (xy 145.998156 -74.236721) (xy 146.005833 -74.318973) (xy 146.006312 -74.360278)
			(xy 146.005808 -74.402639) (xy 145.997755 -74.486976) (xy 145.981721 -74.570166) (xy 145.957853 -74.651456)
			(xy 145.926365 -74.730108) (xy 145.887543 -74.805411) (xy 145.84174 -74.876683) (xy 145.789369 -74.943279)
			(xy 145.730904 -75.004594) (xy 145.666876 -75.060075) (xy 145.597864 -75.109218) (xy 145.524494 -75.151578)
			(xy 145.447429 -75.186773) (xy 145.367367 -75.214482) (xy 145.285034 -75.234456) (xy 145.201175 -75.246513)
			(xy 145.11655 -75.250545) (xy 145.031925 -75.246513) (xy 144.948066 -75.234456) (xy 144.865733 -75.214482)
			(xy 144.785671 -75.186773) (xy 144.708606 -75.151578) (xy 144.635236 -75.109218) (xy 144.566224 -75.060075)
			(xy 144.502196 -75.004594) (xy 144.443731 -74.943279) (xy 144.39136 -74.876683) (xy 144.345557 -74.805411)
			(xy 144.306735 -74.730108) (xy 144.275247 -74.651456) (xy 144.251379 -74.570166) (xy 144.235345 -74.486976)
			(xy 144.227292 -74.402639) (xy 144.226788 -74.360278) (xy 137.37463 -74.360278) (xy 137.37463 -76.8584)
			(xy 142.64304 -76.8584) (xy 142.64707 -76.773794) (xy 142.659125 -76.689953) (xy 142.679094 -76.607639)
			(xy 142.706798 -76.527595) (xy 142.741985 -76.450547) (xy 142.784337 -76.377193) (xy 142.833469 -76.308197)
			(xy 142.888938 -76.244183) (xy 142.95024 -76.185733) (xy 143.016821 -76.133374) (xy 143.088078 -76.087581)
			(xy 143.163365 -76.048769) (xy 143.242 -76.017289) (xy 143.323272 -75.993427) (xy 143.406444 -75.977398)
			(xy 143.490763 -75.969347) (xy 143.533114 -75.96886) (xy 143.533368 -75.96886) (xy 143.576522 -75.969355)
			(xy 143.662423 -75.977737) (xy 143.747109 -75.994397) (xy 143.829784 -76.019177) (xy 143.909671 -76.051846)
			(xy 143.98602 -76.092095) (xy 144.058114 -76.139548) (xy 144.125275 -76.193757) (xy 144.15643 -76.223622)
			(xy 144.163594 -76.230101) (xy 144.181339 -76.237687) (xy 144.190974 -76.238354) (xy 144.270476 -76.239878)
			(xy 144.28851 -76.23302) (xy 144.295876 -76.226416) (xy 144.32649 -76.199346) (xy 144.391887 -76.150331)
			(xy 144.461506 -76.107524) (xy 144.534759 -76.071287) (xy 144.611029 -76.041924) (xy 144.689671 -76.019684)
			(xy 144.770022 -76.004754) (xy 144.851405 -75.997261) (xy 144.892268 -75.9968) (xy 144.892522 -75.9968)
			(xy 144.93487 -75.997289) (xy 145.019183 -76.005341) (xy 145.102348 -76.021372) (xy 145.183614 -76.045236)
			(xy 145.262242 -76.076716) (xy 145.337523 -76.115527) (xy 145.408773 -76.161318) (xy 145.475349 -76.213675)
			(xy 145.536645 -76.272123) (xy 145.592109 -76.336133) (xy 145.641237 -76.405125) (xy 145.683585 -76.478475)
			(xy 145.718768 -76.555518) (xy 145.74647 -76.635556) (xy 145.766437 -76.717865) (xy 145.778491 -76.8017)
			(xy 145.782521 -76.8863) (xy 145.778491 -76.9709) (xy 145.766437 -77.054735) (xy 145.74647 -77.137044)
			(xy 145.718768 -77.217082) (xy 145.683585 -77.294125) (xy 145.641237 -77.367475) (xy 145.592109 -77.436467)
			(xy 145.536645 -77.500477) (xy 145.475349 -77.558925) (xy 145.408773 -77.611282) (xy 145.337523 -77.657073)
			(xy 145.262242 -77.695884) (xy 145.183614 -77.727364) (xy 145.102348 -77.751228) (xy 145.019183 -77.767259)
			(xy 144.93487 -77.775311) (xy 144.892522 -77.775816) (xy 144.892268 -77.775816) (xy 144.849115 -77.775276)
			(xy 144.763216 -77.766898) (xy 144.678532 -77.750243) (xy 144.595858 -77.725468) (xy 144.515971 -77.692806)
			(xy 144.439621 -77.652563) (xy 144.367526 -77.605117) (xy 144.300363 -77.550915) (xy 144.269206 -77.521054)
			(xy 144.262065 -77.514545) (xy 144.244303 -77.506978) (xy 144.234662 -77.506322) (xy 144.15516 -77.504798)
			(xy 144.137126 -77.511656) (xy 144.12976 -77.51826) (xy 144.099127 -77.545309) (xy 144.033734 -77.594326)
			(xy 143.964118 -77.637135) (xy 143.890867 -77.673375) (xy 143.8146 -77.702741) (xy 143.73596 -77.724984)
			(xy 143.655611 -77.739917) (xy 143.574231 -77.747414) (xy 143.533368 -77.747876) (xy 143.533114 -77.747876)
			(xy 143.490763 -77.747453) (xy 143.406444 -77.739402) (xy 143.323272 -77.723373) (xy 143.242 -77.699511)
			(xy 143.163365 -77.668031) (xy 143.088078 -77.629219) (xy 143.016821 -77.583426) (xy 142.95024 -77.531067)
			(xy 142.888938 -77.472617) (xy 142.833469 -77.408603) (xy 142.784337 -77.339607) (xy 142.741985 -77.266253)
			(xy 142.706798 -77.189205) (xy 142.679094 -77.109161) (xy 142.659125 -77.026847) (xy 142.64707 -76.943006)
			(xy 142.64304 -76.8584) (xy 137.37463 -76.8584) (xy 137.37463 -79.7052) (xy 149.144228 -79.7052)
			(xy 149.144228 -79.704692) (xy 149.144831 -79.65836) (xy 149.154503 -79.566202) (xy 149.173699 -79.475548)
			(xy 149.202212 -79.387379) (xy 149.220428 -79.344774) (xy 149.224232 -79.334831) (xy 149.224232 -79.313569)
			(xy 149.220428 -79.303626) (xy 149.202185 -79.260963) (xy 149.17364 -79.172671) (xy 149.154447 -79.081886)
			(xy 149.144813 -78.989596) (xy 149.144228 -78.9432) (xy 149.144748 -78.900127) (xy 149.153068 -78.814385)
			(xy 149.169639 -78.729849) (xy 149.194307 -78.647311) (xy 149.226839 -78.567545) (xy 149.266932 -78.491298)
			(xy 149.314209 -78.419286) (xy 149.340824 -78.385416) (xy 149.345985 -78.378445) (xy 149.351698 -78.36208)
			(xy 149.352 -78.353412) (xy 149.352 -76.2) (xy 149.352539 -76.166741) (xy 149.361225 -76.100791)
			(xy 149.378447 -76.03654) (xy 149.403911 -75.975089) (xy 149.437182 -75.917488) (xy 149.477688 -75.864724)
			(xy 149.500844 -75.840844) (xy 150.988014 -74.353674) (xy 150.99486 -74.346279) (xy 151.002576 -74.327676)
			(xy 151.003 -74.317606) (xy 151.003 -73.0504) (xy 151.003539 -73.017141) (xy 151.012225 -72.951191)
			(xy 151.029447 -72.88694) (xy 151.054911 -72.825489) (xy 151.088182 -72.767888) (xy 151.128688 -72.715124)
			(xy 151.151844 -72.691244) (xy 151.177244 -72.665844) (xy 151.199259 -72.644443) (xy 151.247581 -72.606562)
			(xy 151.300117 -72.574785) (xy 151.356103 -72.549575) (xy 151.41472 -72.531301) (xy 151.475113 -72.520228)
			(xy 151.5364 -72.516519) (xy 151.597687 -72.520228) (xy 151.65808 -72.531301) (xy 151.716697 -72.549575)
			(xy 151.772683 -72.574785) (xy 151.825219 -72.606562) (xy 151.873541 -72.644443) (xy 151.895556 -72.665844)
			(xy 152.251156 -73.021444) (xy 152.274308 -73.045329) (xy 152.314821 -73.098089) (xy 152.348097 -73.155688)
			(xy 152.373566 -73.217139) (xy 152.390791 -73.28139) (xy 152.399479 -73.34734) (xy 152.4 -73.3806)
			(xy 152.4 -74.337361) (xy 183.260742 -74.337361) (xy 183.260742 -74.252639) (xy 183.268795 -74.168302)
			(xy 183.284829 -74.085112) (xy 183.308697 -74.003822) (xy 183.340185 -73.92517) (xy 183.379007 -73.849867)
			(xy 183.42481 -73.778595) (xy 183.477181 -73.711999) (xy 183.535646 -73.650684) (xy 183.599674 -73.595203)
			(xy 183.668686 -73.54606) (xy 183.742056 -73.5037) (xy 183.819121 -73.468505) (xy 183.899183 -73.440796)
			(xy 183.981516 -73.420822) (xy 184.065375 -73.408765) (xy 184.15 -73.404734) (xy 184.234625 -73.408765)
			(xy 184.318484 -73.420822) (xy 184.400817 -73.440796) (xy 184.480879 -73.468505) (xy 184.557944 -73.5037)
			(xy 184.631314 -73.54606) (xy 184.700326 -73.595203) (xy 184.764354 -73.650684) (xy 184.822819 -73.711999)
			(xy 184.87519 -73.778595) (xy 184.920993 -73.849867) (xy 184.940962 -73.8886) (xy 266.368788 -73.8886)
			(xy 266.372818 -73.803999) (xy 266.384871 -73.720164) (xy 266.404839 -73.637855) (xy 266.432541 -73.557816)
			(xy 266.467725 -73.480773) (xy 266.510074 -73.407423) (xy 266.559203 -73.338431) (xy 266.614668 -73.274421)
			(xy 266.675966 -73.215973) (xy 266.742542 -73.163617) (xy 266.813794 -73.117827) (xy 266.889075 -73.079016)
			(xy 266.967705 -73.047537) (xy 267.048972 -73.023676) (xy 267.132138 -73.007647) (xy 267.216452 -72.999596)
			(xy 267.2588 -72.999092) (xy 267.259562 -72.999092) (xy 267.297909 -72.999501) (xy 267.374317 -73.006133)
			(xy 267.449868 -73.019325) (xy 267.524002 -73.038978) (xy 267.596166 -73.064947) (xy 267.631164 -73.080626)
			(xy 267.641437 -73.084766) (xy 267.663563 -73.084766) (xy 267.673836 -73.080626) (xy 267.708833 -73.064947)
			(xy 267.781003 -73.039) (xy 267.855138 -73.019357) (xy 267.930687 -73.006163) (xy 268.007092 -72.999518)
			(xy 268.045438 -72.999092) (xy 268.0462 -72.999092) (xy 268.088548 -72.999596) (xy 268.172862 -73.007647)
			(xy 268.256028 -73.023676) (xy 268.337295 -73.047537) (xy 268.415925 -73.079016) (xy 268.491206 -73.117827)
			(xy 268.562458 -73.163617) (xy 268.629034 -73.215973) (xy 268.690332 -73.274421) (xy 268.745797 -73.338431)
			(xy 268.794926 -73.407423) (xy 268.837275 -73.480773) (xy 268.872459 -73.557816) (xy 268.900161 -73.637855)
			(xy 268.920129 -73.720164) (xy 268.932182 -73.803999) (xy 268.936213 -73.8886) (xy 268.932182 -73.973201)
			(xy 268.920129 -74.057036) (xy 268.900161 -74.139345) (xy 268.872459 -74.219384) (xy 268.837275 -74.296427)
			(xy 268.794926 -74.369777) (xy 268.745797 -74.438769) (xy 268.697852 -74.4941) (xy 303.021024 -74.4941)
			(xy 303.025053 -74.409502) (xy 303.037107 -74.325671) (xy 303.057074 -74.243365) (xy 303.084774 -74.163329)
			(xy 303.119957 -74.086289) (xy 303.162304 -74.012942) (xy 303.211431 -73.943953) (xy 303.266894 -73.879946)
			(xy 303.328189 -73.821501) (xy 303.394763 -73.769147) (xy 303.466012 -73.723358) (xy 303.54129 -73.684549)
			(xy 303.619917 -73.653071) (xy 303.70118 -73.629211) (xy 303.784343 -73.613182) (xy 303.868653 -73.605132)
			(xy 303.911 -73.604628) (xy 303.951046 -73.605059) (xy 304.030815 -73.612254) (xy 304.109614 -73.626586)
			(xy 304.186807 -73.647939) (xy 304.26177 -73.67614) (xy 304.333897 -73.710962) (xy 304.402603 -73.752123)
			(xy 304.467334 -73.799289) (xy 304.49774 -73.825354) (xy 304.504826 -73.831124) (xy 304.521886 -73.837632)
			(xy 304.531014 -73.838054) (xy 304.560986 -73.838054) (xy 304.570108 -73.837612) (xy 304.587158 -73.831097)
			(xy 304.59426 -73.825354) (xy 304.624664 -73.799286) (xy 304.689385 -73.752101) (xy 304.758087 -73.710928)
			(xy 304.830213 -73.676099) (xy 304.905178 -73.647896) (xy 304.982375 -73.626549) (xy 305.06118 -73.61223)
			(xy 305.140952 -73.605055) (xy 305.181 -73.604628) (xy 305.22335 -73.60506) (xy 305.307667 -73.613111)
			(xy 305.390837 -73.629141) (xy 305.472106 -73.653003) (xy 305.55074 -73.684483) (xy 305.626024 -73.723295)
			(xy 305.697279 -73.769088) (xy 305.763858 -73.821446) (xy 305.825158 -73.879896) (xy 305.880625 -73.943909)
			(xy 305.929756 -74.012903) (xy 305.972107 -74.086256) (xy 306.007292 -74.163302) (xy 306.034995 -74.243344)
			(xy 306.054964 -74.325657) (xy 306.067018 -74.409496) (xy 306.071049 -74.4941) (xy 306.067018 -74.578704)
			(xy 306.054964 -74.662543) (xy 306.034995 -74.744856) (xy 306.007292 -74.824898) (xy 305.972107 -74.901944)
			(xy 305.929756 -74.975297) (xy 305.880625 -75.044291) (xy 305.825158 -75.108304) (xy 305.763858 -75.166754)
			(xy 305.697279 -75.219112) (xy 305.626024 -75.264905) (xy 305.55074 -75.303717) (xy 305.472106 -75.335197)
			(xy 305.390837 -75.359059) (xy 305.307667 -75.375089) (xy 305.22335 -75.38314) (xy 305.181 -75.383644)
			(xy 305.140954 -75.38322) (xy 305.061185 -75.376025) (xy 304.982385 -75.361692) (xy 304.905191 -75.340339)
			(xy 304.830228 -75.312136) (xy 304.758102 -75.277313) (xy 304.689396 -75.236152) (xy 304.624665 -75.188984)
			(xy 304.59426 -75.162918) (xy 304.587168 -75.157157) (xy 304.570113 -75.150642) (xy 304.560986 -75.150218)
			(xy 304.531014 -75.150218) (xy 304.521893 -75.150666) (xy 304.504843 -75.157178) (xy 304.49774 -75.162918)
			(xy 304.467332 -75.188982) (xy 304.402612 -75.236167) (xy 304.333911 -75.277342) (xy 304.261786 -75.312171)
			(xy 304.186821 -75.340374) (xy 304.109624 -75.361722) (xy 304.03082 -75.376042) (xy 303.951047 -75.383217)
			(xy 303.911 -75.383644) (xy 303.868653 -75.383068) (xy 303.784343 -75.375018) (xy 303.70118 -75.358989)
			(xy 303.619917 -75.335129) (xy 303.54129 -75.303651) (xy 303.466012 -75.264842) (xy 303.394763 -75.219053)
			(xy 303.328189 -75.166699) (xy 303.266894 -75.108254) (xy 303.211431 -75.044247) (xy 303.162304 -74.975258)
			(xy 303.119957 -74.901911) (xy 303.084774 -74.824871) (xy 303.057074 -74.744835) (xy 303.037107 -74.662529)
			(xy 303.025053 -74.578698) (xy 303.021024 -74.4941) (xy 268.697852 -74.4941) (xy 268.690332 -74.502779)
			(xy 268.629034 -74.561227) (xy 268.562458 -74.613583) (xy 268.491206 -74.659373) (xy 268.415925 -74.698184)
			(xy 268.337295 -74.729663) (xy 268.256028 -74.753524) (xy 268.172862 -74.769553) (xy 268.088548 -74.777604)
			(xy 268.0462 -74.778108) (xy 268.045438 -74.778108) (xy 268.007091 -74.777699) (xy 267.930683 -74.771067)
			(xy 267.855132 -74.757875) (xy 267.780998 -74.738222) (xy 267.708834 -74.712253) (xy 267.673836 -74.696574)
			(xy 267.663563 -74.692434) (xy 267.641437 -74.692434) (xy 267.631164 -74.696574) (xy 267.596167 -74.712253)
			(xy 267.523997 -74.7382) (xy 267.449862 -74.757843) (xy 267.374313 -74.771037) (xy 267.297908 -74.777682)
			(xy 267.259562 -74.778108) (xy 267.2588 -74.778108) (xy 267.216452 -74.777604) (xy 267.132138 -74.769553)
			(xy 267.048972 -74.753524) (xy 266.967705 -74.729663) (xy 266.889075 -74.698184) (xy 266.813794 -74.659373)
			(xy 266.742542 -74.613583) (xy 266.675966 -74.561227) (xy 266.614668 -74.502779) (xy 266.559203 -74.438769)
			(xy 266.510074 -74.369777) (xy 266.467725 -74.296427) (xy 266.432541 -74.219384) (xy 266.404839 -74.139345)
			(xy 266.384871 -74.057036) (xy 266.372818 -73.973201) (xy 266.368788 -73.8886) (xy 184.940962 -73.8886)
			(xy 184.959815 -73.92517) (xy 184.991303 -74.003822) (xy 185.015171 -74.085112) (xy 185.031205 -74.168302)
			(xy 185.039258 -74.252639) (xy 185.039762 -74.295) (xy 185.039258 -74.337361) (xy 185.031205 -74.421698)
			(xy 185.015171 -74.504888) (xy 184.991303 -74.586178) (xy 184.959815 -74.66483) (xy 184.920993 -74.740133)
			(xy 184.87519 -74.811405) (xy 184.822819 -74.878001) (xy 184.764354 -74.939316) (xy 184.700326 -74.994797)
			(xy 184.631314 -75.04394) (xy 184.557944 -75.0863) (xy 184.480879 -75.121495) (xy 184.400817 -75.149204)
			(xy 184.318484 -75.169178) (xy 184.234625 -75.181235) (xy 184.15 -75.185267) (xy 184.065375 -75.181235)
			(xy 183.981516 -75.169178) (xy 183.899183 -75.149204) (xy 183.819121 -75.121495) (xy 183.742056 -75.0863)
			(xy 183.668686 -75.04394) (xy 183.599674 -74.994797) (xy 183.535646 -74.939316) (xy 183.477181 -74.878001)
			(xy 183.42481 -74.811405) (xy 183.379007 -74.740133) (xy 183.340185 -74.66483) (xy 183.308697 -74.586178)
			(xy 183.284829 -74.504888) (xy 183.268795 -74.421698) (xy 183.260742 -74.337361) (xy 152.4 -74.337361)
			(xy 152.4 -75.861361) (xy 297.179742 -75.861361) (xy 297.179742 -75.776639) (xy 297.187795 -75.692302)
			(xy 297.203829 -75.609112) (xy 297.227697 -75.527822) (xy 297.259185 -75.44917) (xy 297.298007 -75.373867)
			(xy 297.34381 -75.302595) (xy 297.396181 -75.235999) (xy 297.454646 -75.174684) (xy 297.518674 -75.119203)
			(xy 297.587686 -75.07006) (xy 297.661056 -75.0277) (xy 297.738121 -74.992505) (xy 297.818183 -74.964796)
			(xy 297.900516 -74.944822) (xy 297.984375 -74.932765) (xy 298.069 -74.928734) (xy 298.153625 -74.932765)
			(xy 298.237484 -74.944822) (xy 298.319817 -74.964796) (xy 298.399879 -74.992505) (xy 298.476944 -75.0277)
			(xy 298.550314 -75.07006) (xy 298.619326 -75.119203) (xy 298.683354 -75.174684) (xy 298.741819 -75.235999)
			(xy 298.79419 -75.302595) (xy 298.839993 -75.373867) (xy 298.878815 -75.44917) (xy 298.910303 -75.527822)
			(xy 298.934171 -75.609112) (xy 298.950205 -75.692302) (xy 298.958258 -75.776639) (xy 298.958762 -75.819)
			(xy 298.958258 -75.861361) (xy 298.950205 -75.945698) (xy 298.934171 -76.028888) (xy 298.910303 -76.110178)
			(xy 298.878815 -76.18883) (xy 298.839993 -76.264133) (xy 298.810167 -76.310544) (xy 305.873647 -76.310544)
			(xy 305.873647 -76.181404) (xy 305.881597 -76.052509) (xy 305.897467 -75.924349) (xy 305.921196 -75.797408)
			(xy 305.952695 -75.672169) (xy 305.991844 -75.549106) (xy 306.038495 -75.428687) (xy 306.09247 -75.311368)
			(xy 306.153565 -75.197594) (xy 306.221548 -75.087797) (xy 306.296162 -74.982394) (xy 306.377123 -74.881784)
			(xy 306.464123 -74.786349) (xy 306.556834 -74.69645) (xy 306.654904 -74.612429) (xy 306.757959 -74.534605)
			(xy 306.86561 -74.463273) (xy 306.977449 -74.398703) (xy 307.09305 -74.341141) (xy 307.211975 -74.290804)
			(xy 307.333774 -74.247884) (xy 307.457984 -74.212543) (xy 307.584133 -74.184916) (xy 307.711745 -74.165107)
			(xy 307.840334 -74.153191) (xy 307.969412 -74.149215) (xy 308.09849 -74.153191) (xy 308.227079 -74.165107)
			(xy 308.354691 -74.184916) (xy 308.48084 -74.212543) (xy 308.60505 -74.247884) (xy 308.726849 -74.290804)
			(xy 308.845774 -74.341141) (xy 308.961375 -74.398703) (xy 309.073214 -74.463273) (xy 309.180865 -74.534605)
			(xy 309.28392 -74.612429) (xy 309.38199 -74.69645) (xy 309.474701 -74.786349) (xy 309.561701 -74.881784)
			(xy 309.642662 -74.982394) (xy 309.717276 -75.087797) (xy 309.785259 -75.197594) (xy 309.846354 -75.311368)
			(xy 309.900329 -75.428687) (xy 309.94698 -75.549106) (xy 309.986129 -75.672169) (xy 310.017628 -75.797408)
			(xy 310.041357 -75.924349) (xy 310.057227 -76.052509) (xy 310.065177 -76.181404) (xy 310.065674 -76.245974)
			(xy 310.065177 -76.310544) (xy 310.057227 -76.439439) (xy 310.041357 -76.567599) (xy 310.017628 -76.69454)
			(xy 309.986129 -76.819779) (xy 309.94698 -76.942842) (xy 309.900329 -77.063261) (xy 309.846354 -77.18058)
			(xy 309.785259 -77.294354) (xy 309.717276 -77.404151) (xy 309.642662 -77.509554) (xy 309.561701 -77.610164)
			(xy 309.474701 -77.705599) (xy 309.38199 -77.795498) (xy 309.28392 -77.879519) (xy 309.180865 -77.957343)
			(xy 309.073214 -78.028675) (xy 308.961375 -78.093245) (xy 308.845774 -78.150807) (xy 308.726849 -78.201144)
			(xy 308.60505 -78.244064) (xy 308.48084 -78.279405) (xy 308.354691 -78.307032) (xy 308.227079 -78.326841)
			(xy 308.09849 -78.338757) (xy 307.969412 -78.342734) (xy 307.840334 -78.338757) (xy 307.711745 -78.326841)
			(xy 307.584133 -78.307032) (xy 307.457984 -78.279405) (xy 307.333774 -78.244064) (xy 307.211975 -78.201144)
			(xy 307.09305 -78.150807) (xy 306.977449 -78.093245) (xy 306.86561 -78.028675) (xy 306.757959 -77.957343)
			(xy 306.654904 -77.879519) (xy 306.556834 -77.795498) (xy 306.464123 -77.705599) (xy 306.377123 -77.610164)
			(xy 306.296162 -77.509554) (xy 306.221548 -77.404151) (xy 306.153565 -77.294354) (xy 306.09247 -77.18058)
			(xy 306.038495 -77.063261) (xy 305.991844 -76.942842) (xy 305.952695 -76.819779) (xy 305.921196 -76.69454)
			(xy 305.897467 -76.567599) (xy 305.881597 -76.439439) (xy 305.873647 -76.310544) (xy 298.810167 -76.310544)
			(xy 298.79419 -76.335405) (xy 298.741819 -76.402001) (xy 298.683354 -76.463316) (xy 298.619326 -76.518797)
			(xy 298.550314 -76.56794) (xy 298.476944 -76.6103) (xy 298.399879 -76.645495) (xy 298.319817 -76.673204)
			(xy 298.237484 -76.693178) (xy 298.153625 -76.705235) (xy 298.069 -76.709267) (xy 297.984375 -76.705235)
			(xy 297.900516 -76.693178) (xy 297.818183 -76.673204) (xy 297.738121 -76.645495) (xy 297.661056 -76.6103)
			(xy 297.587686 -76.56794) (xy 297.518674 -76.518797) (xy 297.454646 -76.463316) (xy 297.396181 -76.402001)
			(xy 297.34381 -76.335405) (xy 297.298007 -76.264133) (xy 297.259185 -76.18883) (xy 297.227697 -76.110178)
			(xy 297.203829 -76.028888) (xy 297.187795 -75.945698) (xy 297.179742 -75.861361) (xy 152.4 -75.861361)
			(xy 152.4 -79.375) (xy 152.399461 -79.408259) (xy 152.390775 -79.474209) (xy 152.373553 -79.53846)
			(xy 152.348089 -79.599911) (xy 152.314818 -79.657512) (xy 152.274436 -79.710114) (xy 205.177635 -79.710114)
			(xy 205.177635 -79.539758) (xy 205.18562 -79.36959) (xy 205.201572 -79.199983) (xy 205.225457 -79.031311)
			(xy 205.257221 -78.863943) (xy 205.296796 -78.698248) (xy 205.344093 -78.53459) (xy 205.39901 -78.373329)
			(xy 205.461425 -78.214819) (xy 205.531201 -78.059409) (xy 205.608184 -77.907441) (xy 205.692206 -77.759247)
			(xy 205.783082 -77.615155) (xy 205.880612 -77.475481) (xy 205.984582 -77.340532) (xy 206.094763 -77.210604)
			(xy 206.210912 -77.085984) (xy 206.332776 -76.966945) (xy 206.460084 -76.853749) (xy 206.592559 -76.746644)
			(xy 206.729909 -76.645867) (xy 206.871831 -76.551638) (xy 207.018013 -76.464165) (xy 207.168136 -76.38364)
			(xy 207.321867 -76.31024) (xy 207.47887 -76.244126) (xy 207.6388 -76.185444) (xy 207.801304 -76.134323)
			(xy 207.966025 -76.090875) (xy 208.132603 -76.055196) (xy 208.300669 -76.027364) (xy 208.469855 -76.00744)
			(xy 208.639789 -75.995468) (xy 208.810098 -75.991475) (xy 208.980407 -75.995468) (xy 209.150341 -76.00744)
			(xy 209.319527 -76.027364) (xy 209.487593 -76.055196) (xy 209.654171 -76.090875) (xy 209.818892 -76.134323)
			(xy 209.981396 -76.185444) (xy 210.141326 -76.244126) (xy 210.298329 -76.31024) (xy 210.45206 -76.38364)
			(xy 210.602183 -76.464165) (xy 210.748365 -76.551638) (xy 210.890287 -76.645867) (xy 211.027637 -76.746644)
			(xy 211.160112 -76.853749) (xy 211.28742 -76.966945) (xy 211.409284 -77.085984) (xy 211.525433 -77.210604)
			(xy 211.635614 -77.340532) (xy 211.739584 -77.475481) (xy 211.837114 -77.615155) (xy 211.92799 -77.759247)
			(xy 212.012012 -77.907441) (xy 212.088995 -78.059409) (xy 212.158771 -78.214819) (xy 212.221186 -78.373329)
			(xy 212.276103 -78.53459) (xy 212.3234 -78.698248) (xy 212.362975 -78.863943) (xy 212.394739 -79.031311)
			(xy 212.418624 -79.199983) (xy 212.434576 -79.36959) (xy 212.442561 -79.539758) (xy 212.44306 -79.624936)
			(xy 212.442561 -79.710114) (xy 235.177575 -79.710114) (xy 235.177575 -79.539758) (xy 235.18556 -79.36959)
			(xy 235.201512 -79.199983) (xy 235.225397 -79.031311) (xy 235.257161 -78.863943) (xy 235.296736 -78.698248)
			(xy 235.344033 -78.53459) (xy 235.39895 -78.373329) (xy 235.461365 -78.214819) (xy 235.531141 -78.059409)
			(xy 235.608124 -77.907441) (xy 235.692146 -77.759247) (xy 235.783022 -77.615155) (xy 235.880552 -77.475481)
			(xy 235.984522 -77.340532) (xy 236.094703 -77.210604) (xy 236.210852 -77.085984) (xy 236.332716 -76.966945)
			(xy 236.460024 -76.853749) (xy 236.592499 -76.746644) (xy 236.729849 -76.645867) (xy 236.871771 -76.551638)
			(xy 237.017953 -76.464165) (xy 237.168076 -76.38364) (xy 237.321807 -76.31024) (xy 237.47881 -76.244126)
			(xy 237.63874 -76.185444) (xy 237.801244 -76.134323) (xy 237.965965 -76.090875) (xy 238.132543 -76.055196)
			(xy 238.300609 -76.027364) (xy 238.469795 -76.00744) (xy 238.639729 -75.995468) (xy 238.810038 -75.991475)
			(xy 238.980347 -75.995468) (xy 239.150281 -76.00744) (xy 239.319467 -76.027364) (xy 239.487533 -76.055196)
			(xy 239.654111 -76.090875) (xy 239.818832 -76.134323) (xy 239.981336 -76.185444) (xy 240.141266 -76.244126)
			(xy 240.298269 -76.31024) (xy 240.452 -76.38364) (xy 240.602123 -76.464165) (xy 240.748305 -76.551638)
			(xy 240.890227 -76.645867) (xy 241.027577 -76.746644) (xy 241.160052 -76.853749) (xy 241.28736 -76.966945)
			(xy 241.409224 -77.085984) (xy 241.525373 -77.210604) (xy 241.635554 -77.340532) (xy 241.739524 -77.475481)
			(xy 241.837054 -77.615155) (xy 241.92793 -77.759247) (xy 242.011952 -77.907441) (xy 242.088935 -78.059409)
			(xy 242.158711 -78.214819) (xy 242.221126 -78.373329) (xy 242.276043 -78.53459) (xy 242.32334 -78.698248)
			(xy 242.362915 -78.863943) (xy 242.394679 -79.031311) (xy 242.418564 -79.199983) (xy 242.434516 -79.36959)
			(xy 242.442501 -79.539758) (xy 242.443 -79.624936) (xy 242.442501 -79.710114) (xy 242.434516 -79.880282)
			(xy 242.418564 -80.049889) (xy 242.394679 -80.218561) (xy 242.362915 -80.385929) (xy 242.32334 -80.551624)
			(xy 242.276043 -80.715282) (xy 242.221126 -80.876543) (xy 242.158711 -81.035053) (xy 242.088935 -81.190463)
			(xy 242.011952 -81.342431) (xy 241.92793 -81.490625) (xy 241.837054 -81.634717) (xy 241.739524 -81.774391)
			(xy 241.635554 -81.90934) (xy 241.525373 -82.039268) (xy 241.409224 -82.163888) (xy 241.28736 -82.282927)
			(xy 241.160052 -82.396123) (xy 241.027577 -82.503228) (xy 240.890227 -82.604005) (xy 240.748305 -82.698234)
			(xy 240.602123 -82.785707) (xy 240.452 -82.866232) (xy 240.298269 -82.939632) (xy 240.141266 -83.005746)
			(xy 239.981336 -83.064428) (xy 239.818832 -83.115549) (xy 239.654111 -83.158997) (xy 239.487533 -83.194676)
			(xy 239.319467 -83.222508) (xy 239.150281 -83.242432) (xy 238.980347 -83.254404) (xy 238.810038 -83.258398)
			(xy 238.639729 -83.254404) (xy 238.469795 -83.242432) (xy 238.300609 -83.222508) (xy 238.132543 -83.194676)
			(xy 237.965965 -83.158997) (xy 237.801244 -83.115549) (xy 237.63874 -83.064428) (xy 237.47881 -83.005746)
			(xy 237.321807 -82.939632) (xy 237.168076 -82.866232) (xy 237.017953 -82.785707) (xy 236.871771 -82.698234)
			(xy 236.729849 -82.604005) (xy 236.592499 -82.503228) (xy 236.460024 -82.396123) (xy 236.332716 -82.282927)
			(xy 236.210852 -82.163888) (xy 236.094703 -82.039268) (xy 235.984522 -81.90934) (xy 235.880552 -81.774391)
			(xy 235.783022 -81.634717) (xy 235.692146 -81.490625) (xy 235.608124 -81.342431) (xy 235.531141 -81.190463)
			(xy 235.461365 -81.035053) (xy 235.39895 -80.876543) (xy 235.344033 -80.715282) (xy 235.296736 -80.551624)
			(xy 235.257161 -80.385929) (xy 235.225397 -80.218561) (xy 235.201512 -80.049889) (xy 235.18556 -79.880282)
			(xy 235.177575 -79.710114) (xy 212.442561 -79.710114) (xy 212.434576 -79.880282) (xy 212.418624 -80.049889)
			(xy 212.394739 -80.218561) (xy 212.362975 -80.385929) (xy 212.3234 -80.551624) (xy 212.276103 -80.715282)
			(xy 212.221186 -80.876543) (xy 212.158771 -81.035053) (xy 212.088995 -81.190463) (xy 212.012012 -81.342431)
			(xy 211.92799 -81.490625) (xy 211.837114 -81.634717) (xy 211.739584 -81.774391) (xy 211.635614 -81.90934)
			(xy 211.525433 -82.039268) (xy 211.409284 -82.163888) (xy 211.28742 -82.282927) (xy 211.160112 -82.396123)
			(xy 211.027637 -82.503228) (xy 210.890287 -82.604005) (xy 210.748365 -82.698234) (xy 210.602183 -82.785707)
			(xy 210.45206 -82.866232) (xy 210.298329 -82.939632) (xy 210.141326 -83.005746) (xy 209.981396 -83.064428)
			(xy 209.818892 -83.115549) (xy 209.654171 -83.158997) (xy 209.487593 -83.194676) (xy 209.319527 -83.222508)
			(xy 209.150341 -83.242432) (xy 208.980407 -83.254404) (xy 208.810098 -83.258398) (xy 208.639789 -83.254404)
			(xy 208.469855 -83.242432) (xy 208.300669 -83.222508) (xy 208.132603 -83.194676) (xy 207.966025 -83.158997)
			(xy 207.801304 -83.115549) (xy 207.6388 -83.064428) (xy 207.47887 -83.005746) (xy 207.321867 -82.939632)
			(xy 207.168136 -82.866232) (xy 207.018013 -82.785707) (xy 206.871831 -82.698234) (xy 206.729909 -82.604005)
			(xy 206.592559 -82.503228) (xy 206.460084 -82.396123) (xy 206.332776 -82.282927) (xy 206.210912 -82.163888)
			(xy 206.094763 -82.039268) (xy 205.984582 -81.90934) (xy 205.880612 -81.774391) (xy 205.783082 -81.634717)
			(xy 205.692206 -81.490625) (xy 205.608184 -81.342431) (xy 205.531201 -81.190463) (xy 205.461425 -81.035053)
			(xy 205.39901 -80.876543) (xy 205.344093 -80.715282) (xy 205.296796 -80.551624) (xy 205.257221 -80.385929)
			(xy 205.225457 -80.218561) (xy 205.201572 -80.049889) (xy 205.18562 -79.880282) (xy 205.177635 -79.710114)
			(xy 152.274436 -79.710114) (xy 152.274312 -79.710276) (xy 152.251156 -79.734156) (xy 151.616156 -80.369156)
			(xy 151.592271 -80.392308) (xy 151.539511 -80.432821) (xy 151.481912 -80.466097) (xy 151.420461 -80.491566)
			(xy 151.35621 -80.508791) (xy 151.29026 -80.517479) (xy 151.257 -80.518) (xy 150.4061 -80.518) (xy 150.400943 -80.518134)
			(xy 150.390834 -80.520176) (xy 150.386034 -80.522064) (xy 150.344311 -80.539436) (xy 150.258112 -80.566613)
			(xy 150.1696 -80.584906) (xy 150.079689 -80.594125) (xy 150.034498 -80.594708) (xy 150.033736 -80.594708)
			(xy 149.992633 -80.594214) (xy 149.910779 -80.586632) (xy 149.829973 -80.571529) (xy 149.750905 -80.549036)
			(xy 149.67425 -80.519342) (xy 149.600662 -80.482702) (xy 149.530769 -80.439429) (xy 149.465166 -80.38989)
			(xy 149.404415 -80.334511) (xy 149.349033 -80.273761) (xy 149.299492 -80.208161) (xy 149.256215 -80.138269)
			(xy 149.219573 -80.064683) (xy 149.189876 -79.988029) (xy 149.167379 -79.908962) (xy 149.152273 -79.828157)
			(xy 149.144688 -79.746303) (xy 149.144228 -79.7052) (xy 137.37463 -79.7052) (xy 137.37463 -79.89062)
			(xy 137.374124 -79.923881) (xy 137.365434 -79.989832) (xy 137.348207 -80.054084) (xy 137.322737 -80.115537)
			(xy 137.28946 -80.173137) (xy 137.248946 -80.225898) (xy 137.225786 -80.249776) (xy 136.598406 -80.877156)
			(xy 136.574543 -80.900332) (xy 136.521779 -80.940843) (xy 136.464175 -80.974115) (xy 136.40272 -80.99958)
			(xy 136.338465 -81.0168) (xy 136.272511 -81.025482) (xy 136.23925 -81.026) (xy 123.4694 -81.026)
			(xy 123.436141 -81.025461) (xy 123.370191 -81.016775) (xy 123.30594 -80.999553) (xy 123.244489 -80.974089)
			(xy 123.186888 -80.940818) (xy 123.134124 -80.900312) (xy 123.110244 -80.877156) (xy 122.475244 -80.242156)
			(xy 122.452092 -80.218271) (xy 122.411579 -80.165511) (xy 122.378303 -80.107912) (xy 122.352834 -80.046461)
			(xy 122.335609 -79.98221) (xy 122.326921 -79.91626) (xy 122.3264 -79.883) (xy 62.930237 -79.883)
			(xy 62.866209 -79.937386) (xy 62.777346 -80.002441) (xy 62.68402 -80.060913) (xy 62.586718 -80.1125)
			(xy 62.485947 -80.156931) (xy 62.382233 -80.193974) (xy 62.276116 -80.223437) (xy 62.16815 -80.245167)
			(xy 62.058897 -80.259049) (xy 61.948927 -80.265011) (xy 61.838814 -80.263023) (xy 61.729131 -80.253094)
			(xy 61.620451 -80.235277) (xy 61.51334 -80.209664) (xy 61.408356 -80.176389) (xy 61.306047 -80.135625)
			(xy 61.206946 -80.087585) (xy 61.111569 -80.03252) (xy 61.020415 -79.970715) (xy 60.933958 -79.902495)
			(xy 60.852649 -79.828214) (xy 60.776912 -79.748259) (xy 60.707141 -79.663048) (xy 60.643702 -79.573024)
			(xy 60.586923 -79.478657) (xy 60.537102 -79.38044) (xy 60.494498 -79.278883) (xy 60.459333 -79.174517)
			(xy 60.43179 -79.067886) (xy 60.412014 -78.959545) (xy 60.400106 -78.850059) (xy 60.396131 -78.74)
			(xy 43.888152 -78.74) (xy 43.887655 -78.795066) (xy 43.879708 -78.90491) (xy 43.863856 -79.013894)
			(xy 43.840181 -79.12145) (xy 43.808807 -79.227018) (xy 43.769897 -79.330046) (xy 43.723654 -79.429998)
			(xy 43.67032 -79.526353) (xy 43.610171 -79.618609) (xy 43.543523 -79.706283) (xy 43.470722 -79.78892)
			(xy 43.392147 -79.866088) (xy 43.308209 -79.937386) (xy 43.219346 -80.002441) (xy 43.12602 -80.060913)
			(xy 43.028718 -80.1125) (xy 42.927947 -80.156931) (xy 42.824233 -80.193974) (xy 42.718116 -80.223437)
			(xy 42.61015 -80.245167) (xy 42.500897 -80.259049) (xy 42.390927 -80.265011) (xy 42.280814 -80.263023)
			(xy 42.171131 -80.253094) (xy 42.062451 -80.235277) (xy 41.95534 -80.209664) (xy 41.850356 -80.176389)
			(xy 41.748047 -80.135625) (xy 41.648946 -80.087585) (xy 41.553569 -80.03252) (xy 41.462415 -79.970715)
			(xy 41.375958 -79.902495) (xy 41.294649 -79.828214) (xy 41.218912 -79.748259) (xy 41.149141 -79.663048)
			(xy 41.085702 -79.573024) (xy 41.028923 -79.478657) (xy 40.979102 -79.38044) (xy 40.936498 -79.278883)
			(xy 40.901333 -79.174517) (xy 40.87379 -79.067886) (xy 40.854014 -78.959545) (xy 40.842106 -78.850059)
			(xy 40.838131 -78.74) (xy 0.509016 -78.74) (xy 0.509016 -82.3041) (xy 175.3616 -82.3041) (xy 175.36563 -82.219499)
			(xy 175.377684 -82.135664) (xy 175.397652 -82.053355) (xy 175.425354 -81.973317) (xy 175.460539 -81.896274)
			(xy 175.502888 -81.822925) (xy 175.552017 -81.753933) (xy 175.607482 -81.689924) (xy 175.668781 -81.631477)
			(xy 175.735357 -81.579122) (xy 175.806609 -81.533332) (xy 175.881891 -81.494523) (xy 175.960521 -81.463045)
			(xy 176.041788 -81.439185) (xy 176.124954 -81.423157) (xy 176.209268 -81.415107) (xy 176.251616 -81.41462)
			(xy 176.252378 -81.41462) (xy 176.293924 -81.415132) (xy 176.37665 -81.422912) (xy 176.458292 -81.438368)
			(xy 176.538137 -81.461365) (xy 176.57699 -81.476088) (xy 176.586068 -81.479207) (xy 176.60525 -81.479207)
			(xy 176.614328 -81.476088) (xy 176.653174 -81.461346) (xy 176.733019 -81.438336) (xy 176.814663 -81.422879)
			(xy 176.897393 -81.415109) (xy 176.93894 -81.41462) (xy 176.939702 -81.41462) (xy 176.982052 -81.415068)
			(xy 177.066368 -81.423119) (xy 177.149537 -81.439149) (xy 177.230805 -81.463012) (xy 177.309438 -81.494491)
			(xy 177.384721 -81.533303) (xy 177.455975 -81.579095) (xy 177.522553 -81.631453) (xy 177.583853 -81.689902)
			(xy 177.63932 -81.753914) (xy 177.68845 -81.822908) (xy 177.7308 -81.89626) (xy 177.765985 -81.973306)
			(xy 177.793688 -82.053347) (xy 177.813656 -82.135659) (xy 177.82571 -82.219496) (xy 177.829741 -82.3041)
			(xy 177.82571 -82.388704) (xy 177.813656 -82.472541) (xy 177.793688 -82.554853) (xy 177.765985 -82.634894)
			(xy 177.7308 -82.71194) (xy 177.68845 -82.785292) (xy 177.63932 -82.854286) (xy 177.583853 -82.918298)
			(xy 177.522553 -82.976747) (xy 177.455975 -83.029105) (xy 177.384721 -83.074897) (xy 177.309438 -83.113709)
			(xy 177.230805 -83.145188) (xy 177.149537 -83.169051) (xy 177.066368 -83.185081) (xy 176.982052 -83.193132)
			(xy 176.939702 -83.193636) (xy 176.93894 -83.193636) (xy 176.897394 -83.193153) (xy 176.814666 -83.185365)
			(xy 176.733025 -83.169901) (xy 176.65318 -83.146895) (xy 176.614328 -83.132168) (xy 176.605259 -83.128992)
			(xy 176.586059 -83.128992) (xy 176.57699 -83.132168) (xy 176.538143 -83.146908) (xy 176.458298 -83.169917)
			(xy 176.376655 -83.185375) (xy 176.293925 -83.193146) (xy 176.252378 -83.193636) (xy 176.251616 -83.193636)
			(xy 176.209268 -83.193093) (xy 176.124954 -83.185043) (xy 176.041788 -83.169015) (xy 175.960521 -83.145155)
			(xy 175.881891 -83.113677) (xy 175.806609 -83.074868) (xy 175.735357 -83.029078) (xy 175.668781 -82.976723)
			(xy 175.607482 -82.918276) (xy 175.552017 -82.854267) (xy 175.502888 -82.785275) (xy 175.460539 -82.711926)
			(xy 175.425354 -82.634883) (xy 175.397652 -82.554845) (xy 175.377684 -82.472536) (xy 175.36563 -82.388701)
			(xy 175.3616 -82.3041) (xy 0.509016 -82.3041) (xy 0.509016 -86.127279) (xy 159.685986 -86.127279)
			(xy 159.685986 -86.042557) (xy 159.694039 -85.95822) (xy 159.710073 -85.87503) (xy 159.733941 -85.79374)
			(xy 159.765429 -85.715088) (xy 159.804251 -85.639785) (xy 159.850054 -85.568513) (xy 159.902425 -85.501917)
			(xy 159.96089 -85.440602) (xy 160.024918 -85.385121) (xy 160.09393 -85.335978) (xy 160.1673 -85.293618)
			(xy 160.244365 -85.258423) (xy 160.324427 -85.230714) (xy 160.40676 -85.21074) (xy 160.490619 -85.198683)
			(xy 160.575244 -85.194652) (xy 160.659869 -85.198683) (xy 160.743728 -85.21074) (xy 160.826061 -85.230714)
			(xy 160.906123 -85.258423) (xy 160.983188 -85.293618) (xy 161.056558 -85.335978) (xy 161.12557 -85.385121)
			(xy 161.189598 -85.440602) (xy 161.240138 -85.493606) (xy 260.00583 -85.493606) (xy 260.00583 -78.47457)
			(xy 260.006341 -78.44131) (xy 260.015031 -78.375359) (xy 260.032258 -78.311107) (xy 260.057728 -78.249655)
			(xy 260.091003 -78.192055) (xy 260.131515 -78.139293) (xy 260.154674 -78.115414) (xy 260.524244 -77.745844)
			(xy 260.548129 -77.722692) (xy 260.600889 -77.682179) (xy 260.658488 -77.648903) (xy 260.719939 -77.623434)
			(xy 260.78419 -77.606209) (xy 260.85014 -77.597521) (xy 260.8834 -77.597) (xy 265.7094 -77.597) (xy 265.742659 -77.597539)
			(xy 265.808609 -77.606225) (xy 265.87286 -77.623447) (xy 265.934311 -77.648911) (xy 265.991912 -77.682182)
			(xy 266.044676 -77.722688) (xy 266.068556 -77.745844) (xy 266.478512 -78.1558) (xy 279.439887 -78.1558)
			(xy 279.443918 -78.071199) (xy 279.455971 -77.987365) (xy 279.475939 -77.905056) (xy 279.50364 -77.825017)
			(xy 279.538825 -77.747974) (xy 279.581173 -77.674625) (xy 279.630301 -77.605633) (xy 279.685766 -77.541623)
			(xy 279.747063 -77.483176) (xy 279.813639 -77.430819) (xy 279.88489 -77.385029) (xy 279.960171 -77.346218)
			(xy 280.038801 -77.314739) (xy 280.120067 -77.290877) (xy 280.203233 -77.274847) (xy 280.287546 -77.266796)
			(xy 280.329894 -77.266292) (xy 280.330402 -77.266292) (xy 280.376734 -77.2669) (xy 280.468892 -77.276571)
			(xy 280.559546 -77.295766) (xy 280.647715 -77.324277) (xy 280.69032 -77.342492) (xy 280.700262 -77.346298)
			(xy 280.721526 -77.346298) (xy 280.731468 -77.342492) (xy 280.774072 -77.324272) (xy 280.862239 -77.295754)
			(xy 280.952894 -77.276561) (xy 281.045054 -77.2669) (xy 281.091386 -77.266292) (xy 281.091894 -77.266292)
			(xy 281.134243 -77.26678) (xy 281.218559 -77.27483) (xy 281.301727 -77.290859) (xy 281.382995 -77.314721)
			(xy 281.461627 -77.3462) (xy 281.536911 -77.385011) (xy 281.608164 -77.430802) (xy 281.674742 -77.48316)
			(xy 281.736042 -77.541608) (xy 281.791508 -77.605619) (xy 281.840638 -77.674613) (xy 281.882988 -77.747964)
			(xy 281.918173 -77.825009) (xy 281.945875 -77.905049) (xy 281.965844 -77.98736) (xy 281.977898 -78.071197)
			(xy 281.981928 -78.1558) (xy 281.977898 -78.240403) (xy 281.965844 -78.32424) (xy 281.945875 -78.406551)
			(xy 281.918173 -78.486591) (xy 281.882988 -78.563636) (xy 281.840638 -78.636987) (xy 281.791508 -78.705981)
			(xy 281.736042 -78.769992) (xy 281.674742 -78.82844) (xy 281.608164 -78.880798) (xy 281.536911 -78.926589)
			(xy 281.461627 -78.9654) (xy 281.382995 -78.996879) (xy 281.301727 -79.020741) (xy 281.218559 -79.03677)
			(xy 281.134243 -79.04482) (xy 281.091894 -79.045308) (xy 281.091386 -79.045308) (xy 281.045054 -79.044704)
			(xy 280.952896 -79.035032) (xy 280.862242 -79.015836) (xy 280.774073 -78.987323) (xy 280.731468 -78.969108)
			(xy 280.721526 -78.965302) (xy 280.700262 -78.965302) (xy 280.69032 -78.969108) (xy 280.647718 -78.987332)
			(xy 280.55955 -79.015849) (xy 280.468894 -79.035041) (xy 280.376734 -79.0447) (xy 280.330402 -79.045308)
			(xy 280.329894 -79.045308) (xy 280.287546 -79.044804) (xy 280.203233 -79.036753) (xy 280.120067 -79.020723)
			(xy 280.038801 -78.996861) (xy 279.960171 -78.965382) (xy 279.88489 -78.926571) (xy 279.813639 -78.880781)
			(xy 279.747063 -78.828424) (xy 279.685766 -78.769977) (xy 279.630301 -78.705967) (xy 279.581173 -78.636975)
			(xy 279.538825 -78.563626) (xy 279.50364 -78.486583) (xy 279.475939 -78.406544) (xy 279.455971 -78.324235)
			(xy 279.443918 -78.240401) (xy 279.439887 -78.1558) (xy 266.478512 -78.1558) (xy 266.579858 -78.257146)
			(xy 266.603011 -78.28103) (xy 266.643524 -78.33379) (xy 266.6768 -78.391389) (xy 266.702268 -78.45284)
			(xy 266.719494 -78.517092) (xy 266.728181 -78.583042) (xy 266.728702 -78.616302) (xy 266.728702 -80.391)
			(xy 297.102788 -80.391) (xy 297.106818 -80.306399) (xy 297.118871 -80.222564) (xy 297.138839 -80.140255)
			(xy 297.166541 -80.060216) (xy 297.201725 -79.983173) (xy 297.244074 -79.909823) (xy 297.293203 -79.840831)
			(xy 297.348668 -79.776821) (xy 297.409966 -79.718373) (xy 297.476542 -79.666017) (xy 297.547794 -79.620227)
			(xy 297.623075 -79.581416) (xy 297.701705 -79.549937) (xy 297.782972 -79.526076) (xy 297.866138 -79.510047)
			(xy 297.950452 -79.501996) (xy 297.9928 -79.501492) (xy 297.993308 -79.501492) (xy 298.03964 -79.502098)
			(xy 298.131798 -79.511769) (xy 298.222452 -79.530965) (xy 298.310621 -79.559477) (xy 298.353226 -79.577692)
			(xy 298.363168 -79.581498) (xy 298.384432 -79.581498) (xy 298.394374 -79.577692) (xy 298.436977 -79.55947)
			(xy 298.525144 -79.530952) (xy 298.6158 -79.51176) (xy 298.70796 -79.5021) (xy 298.754292 -79.501492)
			(xy 298.7548 -79.501492) (xy 298.797148 -79.501996) (xy 298.881462 -79.510047) (xy 298.964628 -79.526076)
			(xy 299.045895 -79.549937) (xy 299.124525 -79.581416) (xy 299.199806 -79.620227) (xy 299.271058 -79.666017)
			(xy 299.337634 -79.718373) (xy 299.398932 -79.776821) (xy 299.450937 -79.836838) (xy 303.180186 -79.836838)
			(xy 303.182815 -79.753015) (xy 303.19332 -79.66981) (xy 303.211608 -79.587964) (xy 303.237517 -79.508202)
			(xy 303.270817 -79.431231) (xy 303.311212 -79.357736) (xy 303.358343 -79.288368) (xy 303.411794 -79.223743)
			(xy 303.471088 -79.164435) (xy 303.5357 -79.110969) (xy 303.605057 -79.063821) (xy 303.678543 -79.023409)
			(xy 303.755505 -78.990091) (xy 303.835261 -78.964164) (xy 303.917103 -78.945856) (xy 304.000305 -78.935331)
			(xy 304.084128 -78.932683) (xy 304.167828 -78.937934) (xy 304.250663 -78.951038) (xy 304.331897 -78.971879)
			(xy 304.410809 -79.000271) (xy 304.4867 -79.035964) (xy 304.558894 -79.078639) (xy 304.626753 -79.127919)
			(xy 304.689673 -79.183366) (xy 304.747097 -79.244487) (xy 304.798514 -79.310741) (xy 304.843468 -79.38154)
			(xy 304.881561 -79.456254) (xy 304.912453 -79.534222) (xy 304.935872 -79.61475) (xy 304.951609 -79.697125)
			(xy 304.959525 -79.780616) (xy 304.96002 -79.822548) (xy 304.96002 -79.823056) (xy 304.959492 -79.865875)
			(xy 304.951224 -79.951114) (xy 304.94351 -79.993236) (xy 304.941789 -80.004521) (xy 304.94747 -80.026607)
			(xy 304.954432 -80.035654) (xy 305.012852 -80.104996) (xy 305.03368 -80.114394) (xy 305.044856 -80.11414)
			(xy 305.045872 -80.11414) (xy 305.063398 -80.11414) (xy 305.105333 -80.11462) (xy 305.18883 -80.122512)
			(xy 305.271215 -80.138226) (xy 305.351755 -80.161624) (xy 305.429736 -80.192496) (xy 305.504465 -80.23057)
			(xy 305.57528 -80.275507) (xy 305.641553 -80.326908) (xy 305.702694 -80.384318) (xy 305.758161 -80.447227)
			(xy 305.807463 -80.515076) (xy 305.85016 -80.587263) (xy 305.885876 -80.663148) (xy 305.914292 -80.742058)
			(xy 305.935156 -80.823291) (xy 305.948283 -80.906127) (xy 305.953557 -80.98983) (xy 305.950931 -81.073659)
			(xy 305.940428 -81.156868) (xy 305.922142 -81.23872) (xy 305.896234 -81.318488) (xy 305.862935 -81.395464)
			(xy 305.82254 -81.468965) (xy 305.775407 -81.538338) (xy 305.721955 -81.602968) (xy 305.662659 -81.662282)
			(xy 305.598045 -81.715752) (xy 305.528685 -81.762905) (xy 305.455196 -81.803321) (xy 305.37823 -81.836643)
			(xy 305.298469 -81.862574) (xy 305.216623 -81.880884) (xy 305.133416 -81.891411) (xy 305.049589 -81.894061)
			(xy 304.965883 -81.888812) (xy 304.883044 -81.875708) (xy 304.801804 -81.854868) (xy 304.722887 -81.826475)
			(xy 304.646992 -81.790781) (xy 304.574792 -81.748104) (xy 304.506928 -81.698823) (xy 304.444004 -81.643373)
			(xy 304.386576 -81.582249) (xy 304.335155 -81.515992) (xy 304.290198 -81.445189) (xy 304.252102 -81.370471)
			(xy 304.221207 -81.292499) (xy 304.197787 -81.211966) (xy 304.182048 -81.129586) (xy 304.174132 -81.046091)
			(xy 304.173636 -81.004156) (xy 304.173636 -81.003648) (xy 304.174164 -80.960829) (xy 304.182432 -80.87559)
			(xy 304.190146 -80.833468) (xy 304.191851 -80.822182) (xy 304.186179 -80.800099) (xy 304.179224 -80.79105)
			(xy 304.120804 -80.721708) (xy 304.099976 -80.71231) (xy 304.0888 -80.712564) (xy 304.087784 -80.712564)
			(xy 304.070258 -80.712564) (xy 304.028326 -80.712034) (xy 303.944833 -80.704139) (xy 303.862455 -80.688421)
			(xy 303.78192 -80.665021) (xy 303.703946 -80.634147) (xy 303.629222 -80.596072) (xy 303.558413 -80.551135)
			(xy 303.492147 -80.499733) (xy 303.431012 -80.442324) (xy 303.37555 -80.379417) (xy 303.326255 -80.31157)
			(xy 303.283562 -80.239385) (xy 303.247852 -80.163503) (xy 303.219441 -80.084598) (xy 303.198581 -80.003369)
			(xy 303.185457 -79.920537) (xy 303.180186 -79.836838) (xy 299.450937 -79.836838) (xy 299.454397 -79.840831)
			(xy 299.503526 -79.909823) (xy 299.545875 -79.983173) (xy 299.581059 -80.060216) (xy 299.608761 -80.140255)
			(xy 299.628729 -80.222564) (xy 299.640782 -80.306399) (xy 299.644813 -80.391) (xy 299.640782 -80.475601)
			(xy 299.628729 -80.559436) (xy 299.608761 -80.641745) (xy 299.581059 -80.721784) (xy 299.545875 -80.798827)
			(xy 299.503526 -80.872177) (xy 299.454397 -80.941169) (xy 299.398932 -81.005179) (xy 299.337634 -81.063627)
			(xy 299.271058 -81.115983) (xy 299.199806 -81.161773) (xy 299.124525 -81.200584) (xy 299.045895 -81.232063)
			(xy 298.964628 -81.255924) (xy 298.881462 -81.271953) (xy 298.797148 -81.280004) (xy 298.7548 -81.280508)
			(xy 298.754292 -81.280508) (xy 298.70796 -81.279902) (xy 298.615802 -81.270231) (xy 298.525148 -81.251035)
			(xy 298.436979 -81.222523) (xy 298.394374 -81.204308) (xy 298.384432 -81.200502) (xy 298.363168 -81.200502)
			(xy 298.353226 -81.204308) (xy 298.310623 -81.22253) (xy 298.222456 -81.251048) (xy 298.1318 -81.27024)
			(xy 298.03964 -81.2799) (xy 297.993308 -81.280508) (xy 297.9928 -81.280508) (xy 297.950452 -81.280004)
			(xy 297.866138 -81.271953) (xy 297.782972 -81.255924) (xy 297.701705 -81.232063) (xy 297.623075 -81.200584)
			(xy 297.547794 -81.161773) (xy 297.476542 -81.115983) (xy 297.409966 -81.063627) (xy 297.348668 -81.005179)
			(xy 297.293203 -80.941169) (xy 297.244074 -80.872177) (xy 297.201725 -80.798827) (xy 297.166541 -80.721784)
			(xy 297.138839 -80.641745) (xy 297.118871 -80.559436) (xy 297.106818 -80.475601) (xy 297.102788 -80.391)
			(xy 266.728702 -80.391) (xy 266.728702 -82.52968) (xy 266.729111 -82.539752) (xy 266.73684 -82.558351)
			(xy 266.743688 -82.565748) (xy 267.544042 -83.366102) (xy 267.551433 -83.372953) (xy 267.570039 -83.380666)
			(xy 267.58011 -83.381088) (xy 279.229566 -83.381088) (xy 279.262826 -83.381624) (xy 279.328776 -83.390306)
			(xy 279.393028 -83.407528) (xy 279.454481 -83.432992) (xy 279.512081 -83.466264) (xy 279.564843 -83.506774)
			(xy 279.588722 -83.529932) (xy 280.012394 -83.953604) (xy 280.033463 -83.975277) (xy 280.070852 -84.022773)
			(xy 280.10234 -84.07437) (xy 280.127483 -84.129339) (xy 280.145926 -84.186904) (xy 280.152094 -84.216494)
			(xy 280.153364 -84.224114) (xy 280.160476 -84.237322) (xy 280.551128 -84.627974) (xy 280.558527 -84.634815)
			(xy 280.577127 -84.642535) (xy 280.587196 -84.64296) (xy 281.74696 -84.64296) (xy 281.780219 -84.643508)
			(xy 281.846169 -84.652189) (xy 281.91042 -84.669408) (xy 281.971873 -84.694871) (xy 282.029474 -84.728141)
			(xy 282.082237 -84.768647) (xy 282.106116 -84.791804) (xy 283.061156 -85.746844) (xy 283.084308 -85.770729)
			(xy 283.124821 -85.823489) (xy 283.158097 -85.881088) (xy 283.183566 -85.942539) (xy 283.200791 -86.00679)
			(xy 283.209479 -86.07274) (xy 283.21 -86.106) (xy 283.21 -86.894162) (xy 283.210419 -86.904233) (xy 283.218141 -86.922832)
			(xy 283.224986 -86.93023) (xy 283.440378 -87.145622) (xy 283.44114 -87.146384) (xy 283.451808 -87.154766)
			(xy 283.465841 -87.163562) (xy 283.489209 -87.187012) (xy 283.505725 -87.215703) (xy 283.514268 -87.247687)
			(xy 283.5148 -87.26424) (xy 283.5148 -88.38184) (xy 283.514292 -88.39849) (xy 283.505664 -88.430654)
			(xy 283.489008 -88.459489) (xy 283.465457 -88.483033) (xy 283.436617 -88.49968) (xy 283.40445 -88.508297)
			(xy 283.3878 -88.50884) (xy 282.0162 -88.50884) (xy 281.999555 -88.508257) (xy 281.967399 -88.499643)
			(xy 281.938567 -88.483001) (xy 281.915024 -88.459465) (xy 281.898373 -88.430638) (xy 281.889748 -88.398485)
			(xy 281.8892 -88.38184) (xy 281.8892 -87.26424) (xy 281.889752 -87.247691) (xy 281.898315 -87.215719)
			(xy 281.914823 -87.18703) (xy 281.938162 -87.16356) (xy 281.952192 -87.154766) (xy 281.96286 -87.146384)
			(xy 281.963622 -87.145622) (xy 282.179014 -86.93023) (xy 282.185835 -86.922815) (xy 282.193565 -86.904227)
			(xy 282.194 -86.894162) (xy 282.194 -86.337394) (xy 282.193604 -86.327321) (xy 282.185866 -86.308722)
			(xy 282.179014 -86.301326) (xy 281.551634 -85.673946) (xy 281.544211 -85.667135) (xy 281.52563 -85.659397)
			(xy 281.515566 -85.65896) (xy 280.506678 -85.65896) (xy 280.496516 -85.659373) (xy 280.47778 -85.667246)
			(xy 280.470356 -85.6742) (xy 280.468578 -85.675978) (xy 280.176224 -85.968332) (xy 280.169381 -85.97573)
			(xy 280.161662 -85.994331) (xy 280.161238 -86.0044) (xy 280.161238 -87.84336) (xy 280.160691 -87.876619)
			(xy 280.15201 -87.942569) (xy 280.13479 -88.00682) (xy 280.109327 -88.068273) (xy 280.076058 -88.125874)
			(xy 280.035551 -88.178637) (xy 280.012394 -88.202516) (xy 279.212548 -89.002362) (xy 279.188667 -89.025519)
			(xy 279.135906 -89.066031) (xy 279.078307 -89.099306) (xy 279.016855 -89.124774) (xy 278.952603 -89.141999)
			(xy 278.886652 -89.150685) (xy 278.853392 -89.151206) (xy 263.66343 -89.151206) (xy 263.63017 -89.150675)
			(xy 263.564219 -89.141991) (xy 263.499967 -89.124769) (xy 263.438515 -89.099304) (xy 263.380914 -89.066031)
			(xy 263.328153 -89.02552) (xy 263.304274 -89.002362) (xy 260.154674 -85.852762) (xy 260.131513 -85.828886)
			(xy 260.091003 -85.776123) (xy 260.05773 -85.718522) (xy 260.032263 -85.657069) (xy 260.015039 -85.592817)
			(xy 260.006352 -85.526866) (xy 260.00583 -85.493606) (xy 161.240138 -85.493606) (xy 161.248063 -85.501917)
			(xy 161.300434 -85.568513) (xy 161.346237 -85.639785) (xy 161.385059 -85.715088) (xy 161.416547 -85.79374)
			(xy 161.440415 -85.87503) (xy 161.456449 -85.95822) (xy 161.464502 -86.042557) (xy 161.465006 -86.084918)
			(xy 161.464502 -86.127279) (xy 161.456449 -86.211616) (xy 161.440415 -86.294806) (xy 161.416547 -86.376096)
			(xy 161.385059 -86.454748) (xy 161.346237 -86.530051) (xy 161.300434 -86.601323) (xy 161.248063 -86.667919)
			(xy 161.189598 -86.729234) (xy 161.12557 -86.784715) (xy 161.056558 -86.833858) (xy 160.983188 -86.876218)
			(xy 160.906123 -86.911413) (xy 160.826061 -86.939122) (xy 160.743728 -86.959096) (xy 160.659869 -86.971153)
			(xy 160.575244 -86.975185) (xy 160.490619 -86.971153) (xy 160.40676 -86.959096) (xy 160.324427 -86.939122)
			(xy 160.244365 -86.911413) (xy 160.1673 -86.876218) (xy 160.09393 -86.833858) (xy 160.024918 -86.784715)
			(xy 159.96089 -86.729234) (xy 159.902425 -86.667919) (xy 159.850054 -86.601323) (xy 159.804251 -86.530051)
			(xy 159.765429 -86.454748) (xy 159.733941 -86.376096) (xy 159.710073 -86.294806) (xy 159.694039 -86.211616)
			(xy 159.685986 -86.127279) (xy 0.509016 -86.127279) (xy 0.509016 -91.559888) (xy 41.345622 -91.559888)
			(xy 41.349604 -91.469938) (xy 41.361521 -91.380691) (xy 41.381279 -91.292847) (xy 41.408723 -91.207093)
			(xy 41.443639 -91.1241) (xy 41.485753 -91.044518) (xy 41.534736 -90.968969) (xy 41.590204 -90.898045)
			(xy 41.651724 -90.8323) (xy 41.718813 -90.77225) (xy 41.790947 -90.718365) (xy 41.867561 -90.671065)
			(xy 41.948055 -90.630722) (xy 42.0318 -90.59765) (xy 42.118141 -90.57211) (xy 42.2064 -90.5543) (xy 42.295889 -90.54436)
			(xy 42.385905 -90.542369) (xy 42.475746 -90.54834) (xy 42.564707 -90.562229) (xy 42.652092 -90.583925)
			(xy 42.737218 -90.61326) (xy 42.819418 -90.650003) (xy 42.898049 -90.693867) (xy 42.972496 -90.744509)
			(xy 43.042176 -90.801533) (xy 43.106543 -90.864492) (xy 43.165094 -90.932893) (xy 43.217371 -91.006201)
			(xy 43.262964 -91.083843) (xy 43.301517 -91.16521) (xy 43.332728 -91.249666) (xy 43.356352 -91.33655)
			(xy 43.372205 -91.425182) (xy 43.380162 -91.514869) (xy 43.38066 -91.559888) (xy 60.903622 -91.559888)
			(xy 60.907604 -91.469938) (xy 60.919521 -91.380691) (xy 60.939279 -91.292847) (xy 60.966723 -91.207093)
			(xy 61.001639 -91.1241) (xy 61.043753 -91.044518) (xy 61.092736 -90.968969) (xy 61.148204 -90.898045)
			(xy 61.209724 -90.8323) (xy 61.276813 -90.77225) (xy 61.348947 -90.718365) (xy 61.425561 -90.671065)
			(xy 61.506055 -90.630722) (xy 61.5898 -90.59765) (xy 61.676141 -90.57211) (xy 61.7644 -90.5543) (xy 61.853889 -90.54436)
			(xy 61.943905 -90.542369) (xy 62.033746 -90.54834) (xy 62.122707 -90.562229) (xy 62.210092 -90.583925)
			(xy 62.295218 -90.61326) (xy 62.377418 -90.650003) (xy 62.456049 -90.693867) (xy 62.530496 -90.744509)
			(xy 62.600176 -90.801533) (xy 62.664543 -90.864492) (xy 62.723094 -90.932893) (xy 62.775371 -91.006201)
			(xy 62.820964 -91.083843) (xy 62.859517 -91.16521) (xy 62.890728 -91.249666) (xy 62.914352 -91.33655)
			(xy 62.930205 -91.425182) (xy 62.938162 -91.514869) (xy 62.93866 -91.559888) (xy 377.061232 -91.559888)
			(xy 377.065214 -91.469938) (xy 377.077131 -91.380691) (xy 377.096889 -91.292847) (xy 377.124333 -91.207093)
			(xy 377.159249 -91.1241) (xy 377.201363 -91.044518) (xy 377.250346 -90.968969) (xy 377.305814 -90.898045)
			(xy 377.367334 -90.8323) (xy 377.434423 -90.77225) (xy 377.506557 -90.718365) (xy 377.583171 -90.671065)
			(xy 377.663665 -90.630722) (xy 377.74741 -90.59765) (xy 377.833751 -90.57211) (xy 377.92201 -90.5543)
			(xy 378.011499 -90.54436) (xy 378.101515 -90.542369) (xy 378.191356 -90.54834) (xy 378.280317 -90.562229)
			(xy 378.367702 -90.583925) (xy 378.452828 -90.61326) (xy 378.535028 -90.650003) (xy 378.613659 -90.693867)
			(xy 378.688106 -90.744509) (xy 378.757786 -90.801533) (xy 378.822153 -90.864492) (xy 378.880704 -90.932893)
			(xy 378.932981 -91.006201) (xy 378.978574 -91.083843) (xy 379.017127 -91.16521) (xy 379.048338 -91.249666)
			(xy 379.071962 -91.33655) (xy 379.087815 -91.425182) (xy 379.095772 -91.514869) (xy 379.09627 -91.559888)
			(xy 396.619232 -91.559888) (xy 396.623214 -91.469938) (xy 396.635131 -91.380691) (xy 396.654889 -91.292847)
			(xy 396.682333 -91.207093) (xy 396.717249 -91.1241) (xy 396.759363 -91.044518) (xy 396.808346 -90.968969)
			(xy 396.863814 -90.898045) (xy 396.925334 -90.8323) (xy 396.992423 -90.77225) (xy 397.064557 -90.718365)
			(xy 397.141171 -90.671065) (xy 397.221665 -90.630722) (xy 397.30541 -90.59765) (xy 397.391751 -90.57211)
			(xy 397.48001 -90.5543) (xy 397.569499 -90.54436) (xy 397.659515 -90.542369) (xy 397.749356 -90.54834)
			(xy 397.838317 -90.562229) (xy 397.925702 -90.583925) (xy 398.010828 -90.61326) (xy 398.093028 -90.650003)
			(xy 398.171659 -90.693867) (xy 398.246106 -90.744509) (xy 398.315786 -90.801533) (xy 398.380153 -90.864492)
			(xy 398.438704 -90.932893) (xy 398.490981 -91.006201) (xy 398.536574 -91.083843) (xy 398.575127 -91.16521)
			(xy 398.606338 -91.249666) (xy 398.629962 -91.33655) (xy 398.645815 -91.425182) (xy 398.653772 -91.514869)
			(xy 398.65416 -91.549982) (xy 470.018373 -91.549982) (xy 470.022363 -91.436999) (xy 470.034312 -91.324578)
			(xy 470.054162 -91.213281) (xy 470.081814 -91.103661) (xy 470.117128 -90.996264) (xy 470.159931 -90.891626)
			(xy 470.210008 -90.790268) (xy 470.26711 -90.692695) (xy 470.330952 -90.599393) (xy 470.401217 -90.510827)
			(xy 470.477554 -90.427437) (xy 470.559583 -90.34964) (xy 470.646896 -90.277823) (xy 470.739057 -90.212344)
			(xy 470.835607 -90.153529) (xy 470.936065 -90.101671) (xy 471.039932 -90.057029) (xy 471.146688 -90.019824)
			(xy 471.255803 -89.990242) (xy 471.366733 -89.968431) (xy 471.478925 -89.9545) (xy 471.59182 -89.948516)
			(xy 471.704856 -89.950512) (xy 471.81747 -89.960475) (xy 471.929101 -89.978358) (xy 472.039192 -90.00407)
			(xy 472.147195 -90.037484) (xy 472.252572 -90.078433) (xy 472.354798 -90.126714) (xy 472.453363 -90.182085)
			(xy 472.547778 -90.24427) (xy 472.63757 -90.312961) (xy 472.722294 -90.387815) (xy 472.801527 -90.468458)
			(xy 472.874873 -90.55449) (xy 472.941969 -90.645481) (xy 473.002478 -90.740978) (xy 473.056101 -90.840505)
			(xy 473.10257 -90.943568) (xy 473.141653 -91.049651) (xy 473.173156 -91.158227) (xy 473.196921 -91.268754)
			(xy 473.212831 -91.380683) (xy 473.220805 -91.493455) (xy 473.221304 -91.549982) (xy 473.220805 -91.606509)
			(xy 473.212831 -91.719281) (xy 473.196921 -91.83121) (xy 473.173156 -91.941737) (xy 473.141653 -92.050313)
			(xy 473.10257 -92.156396) (xy 473.056101 -92.259459) (xy 473.002478 -92.358986) (xy 472.941969 -92.454483)
			(xy 472.874873 -92.545474) (xy 472.801527 -92.631506) (xy 472.722294 -92.712149) (xy 472.63757 -92.787003)
			(xy 472.547778 -92.855694) (xy 472.453363 -92.917879) (xy 472.354798 -92.97325) (xy 472.252572 -93.021531)
			(xy 472.147195 -93.06248) (xy 472.039192 -93.095894) (xy 471.929101 -93.121606) (xy 471.81747 -93.139489)
			(xy 471.704856 -93.149452) (xy 471.59182 -93.151448) (xy 471.478925 -93.145464) (xy 471.366733 -93.131533)
			(xy 471.255803 -93.109722) (xy 471.146688 -93.08014) (xy 471.039932 -93.042935) (xy 470.936065 -92.998293)
			(xy 470.835607 -92.946435) (xy 470.739057 -92.88762) (xy 470.646896 -92.822141) (xy 470.559583 -92.750324)
			(xy 470.477554 -92.672527) (xy 470.401217 -92.589137) (xy 470.330952 -92.500571) (xy 470.26711 -92.407269)
			(xy 470.210008 -92.309696) (xy 470.159931 -92.208338) (xy 470.117128 -92.1037) (xy 470.081814 -91.996303)
			(xy 470.054162 -91.886683) (xy 470.034312 -91.775386) (xy 470.022363 -91.662965) (xy 470.018373 -91.549982)
			(xy 398.65416 -91.549982) (xy 398.65427 -91.559888) (xy 398.653772 -91.604907) (xy 398.645815 -91.694594)
			(xy 398.629962 -91.783226) (xy 398.606338 -91.87011) (xy 398.575127 -91.954566) (xy 398.536574 -92.035933)
			(xy 398.490981 -92.113575) (xy 398.438704 -92.186883) (xy 398.380153 -92.255284) (xy 398.315786 -92.318243)
			(xy 398.246106 -92.375267) (xy 398.171659 -92.425909) (xy 398.093028 -92.469773) (xy 398.010828 -92.506516)
			(xy 397.925702 -92.535851) (xy 397.838317 -92.557547) (xy 397.749356 -92.571436) (xy 397.659515 -92.577407)
			(xy 397.569499 -92.575416) (xy 397.48001 -92.565476) (xy 397.391751 -92.547666) (xy 397.30541 -92.522126)
			(xy 397.221665 -92.489054) (xy 397.141171 -92.448711) (xy 397.064557 -92.401411) (xy 396.992423 -92.347526)
			(xy 396.925334 -92.287476) (xy 396.863814 -92.221731) (xy 396.808346 -92.150807) (xy 396.759363 -92.075258)
			(xy 396.717249 -91.995676) (xy 396.682333 -91.912683) (xy 396.654889 -91.826929) (xy 396.635131 -91.739085)
			(xy 396.623214 -91.649838) (xy 396.619232 -91.559888) (xy 379.09627 -91.559888) (xy 379.095772 -91.604907)
			(xy 379.087815 -91.694594) (xy 379.071962 -91.783226) (xy 379.048338 -91.87011) (xy 379.017127 -91.954566)
			(xy 378.978574 -92.035933) (xy 378.932981 -92.113575) (xy 378.880704 -92.186883) (xy 378.822153 -92.255284)
			(xy 378.757786 -92.318243) (xy 378.688106 -92.375267) (xy 378.613659 -92.425909) (xy 378.535028 -92.469773)
			(xy 378.452828 -92.506516) (xy 378.367702 -92.535851) (xy 378.280317 -92.557547) (xy 378.191356 -92.571436)
			(xy 378.101515 -92.577407) (xy 378.011499 -92.575416) (xy 377.92201 -92.565476) (xy 377.833751 -92.547666)
			(xy 377.74741 -92.522126) (xy 377.663665 -92.489054) (xy 377.583171 -92.448711) (xy 377.506557 -92.401411)
			(xy 377.434423 -92.347526) (xy 377.367334 -92.287476) (xy 377.305814 -92.221731) (xy 377.250346 -92.150807)
			(xy 377.201363 -92.075258) (xy 377.159249 -91.995676) (xy 377.124333 -91.912683) (xy 377.096889 -91.826929)
			(xy 377.077131 -91.739085) (xy 377.065214 -91.649838) (xy 377.061232 -91.559888) (xy 62.93866 -91.559888)
			(xy 62.938162 -91.604907) (xy 62.930205 -91.694594) (xy 62.914352 -91.783226) (xy 62.890728 -91.87011)
			(xy 62.859517 -91.954566) (xy 62.820964 -92.035933) (xy 62.775371 -92.113575) (xy 62.723094 -92.186883)
			(xy 62.664543 -92.255284) (xy 62.600176 -92.318243) (xy 62.530496 -92.375267) (xy 62.456049 -92.425909)
			(xy 62.377418 -92.469773) (xy 62.295218 -92.506516) (xy 62.210092 -92.535851) (xy 62.122707 -92.557547)
			(xy 62.033746 -92.571436) (xy 61.943905 -92.577407) (xy 61.853889 -92.575416) (xy 61.7644 -92.565476)
			(xy 61.676141 -92.547666) (xy 61.5898 -92.522126) (xy 61.506055 -92.489054) (xy 61.425561 -92.448711)
			(xy 61.348947 -92.401411) (xy 61.276813 -92.347526) (xy 61.209724 -92.287476) (xy 61.148204 -92.221731)
			(xy 61.092736 -92.150807) (xy 61.043753 -92.075258) (xy 61.001639 -91.995676) (xy 60.966723 -91.912683)
			(xy 60.939279 -91.826929) (xy 60.919521 -91.739085) (xy 60.907604 -91.649838) (xy 60.903622 -91.559888)
			(xy 43.38066 -91.559888) (xy 43.380162 -91.604907) (xy 43.372205 -91.694594) (xy 43.356352 -91.783226)
			(xy 43.332728 -91.87011) (xy 43.301517 -91.954566) (xy 43.262964 -92.035933) (xy 43.217371 -92.113575)
			(xy 43.165094 -92.186883) (xy 43.106543 -92.255284) (xy 43.042176 -92.318243) (xy 42.972496 -92.375267)
			(xy 42.898049 -92.425909) (xy 42.819418 -92.469773) (xy 42.737218 -92.506516) (xy 42.652092 -92.535851)
			(xy 42.564707 -92.557547) (xy 42.475746 -92.571436) (xy 42.385905 -92.577407) (xy 42.295889 -92.575416)
			(xy 42.2064 -92.565476) (xy 42.118141 -92.547666) (xy 42.0318 -92.522126) (xy 41.948055 -92.489054)
			(xy 41.867561 -92.448711) (xy 41.790947 -92.401411) (xy 41.718813 -92.347526) (xy 41.651724 -92.287476)
			(xy 41.590204 -92.221731) (xy 41.534736 -92.150807) (xy 41.485753 -92.075258) (xy 41.443639 -91.995676)
			(xy 41.408723 -91.912683) (xy 41.381279 -91.826929) (xy 41.361521 -91.739085) (xy 41.349604 -91.649838)
			(xy 41.345622 -91.559888) (xy 0.509016 -91.559888) (xy 0.509016 -96.308361) (xy 157.479742 -96.308361)
			(xy 157.479742 -96.223639) (xy 157.487795 -96.139302) (xy 157.503829 -96.056112) (xy 157.527697 -95.974822)
			(xy 157.559185 -95.89617) (xy 157.598007 -95.820867) (xy 157.64381 -95.749595) (xy 157.696181 -95.682999)
			(xy 157.754646 -95.621684) (xy 157.818674 -95.566203) (xy 157.887686 -95.51706) (xy 157.961056 -95.4747)
			(xy 158.038121 -95.439505) (xy 158.118183 -95.411796) (xy 158.200516 -95.391822) (xy 158.284375 -95.379765)
			(xy 158.369 -95.375734) (xy 158.453625 -95.379765) (xy 158.537484 -95.391822) (xy 158.619817 -95.411796)
			(xy 158.699879 -95.439505) (xy 158.776944 -95.4747) (xy 158.850314 -95.51706) (xy 158.919326 -95.566203)
			(xy 158.983354 -95.621684) (xy 159.041819 -95.682999) (xy 159.09419 -95.749595) (xy 159.139993 -95.820867)
			(xy 159.178815 -95.89617) (xy 159.210303 -95.974822) (xy 159.234171 -96.056112) (xy 159.250205 -96.139302)
			(xy 159.258258 -96.223639) (xy 159.258762 -96.266) (xy 159.258258 -96.308361) (xy 159.250205 -96.392698)
			(xy 159.234171 -96.475888) (xy 159.210303 -96.557178) (xy 159.178815 -96.63583) (xy 159.139993 -96.711133)
			(xy 159.09419 -96.782405) (xy 159.041819 -96.849001) (xy 158.983354 -96.910316) (xy 158.919326 -96.965797)
			(xy 158.850314 -97.01494) (xy 158.776944 -97.0573) (xy 158.699879 -97.092495) (xy 158.619817 -97.120204)
			(xy 158.537484 -97.140178) (xy 158.453625 -97.152235) (xy 158.369 -97.156267) (xy 158.284375 -97.152235)
			(xy 158.200516 -97.140178) (xy 158.118183 -97.120204) (xy 158.038121 -97.092495) (xy 157.961056 -97.0573)
			(xy 157.887686 -97.01494) (xy 157.818674 -96.965797) (xy 157.754646 -96.910316) (xy 157.696181 -96.849001)
			(xy 157.64381 -96.782405) (xy 157.598007 -96.711133) (xy 157.559185 -96.63583) (xy 157.527697 -96.557178)
			(xy 157.503829 -96.475888) (xy 157.487795 -96.392698) (xy 157.479742 -96.308361) (xy 0.509016 -96.308361)
			(xy 0.509016 -99.06) (xy 40.838131 -99.06) (xy 40.842106 -98.949941) (xy 40.854014 -98.840455) (xy 40.87379 -98.732114)
			(xy 40.901333 -98.625483) (xy 40.936498 -98.521117) (xy 40.979102 -98.41956) (xy 41.028923 -98.321343)
			(xy 41.085702 -98.226976) (xy 41.149141 -98.136952) (xy 41.218912 -98.051741) (xy 41.294649 -97.971786)
			(xy 41.375958 -97.897505) (xy 41.462415 -97.829285) (xy 41.553569 -97.76748) (xy 41.648946 -97.712415)
			(xy 41.748047 -97.664375) (xy 41.850356 -97.623611) (xy 41.95534 -97.590336) (xy 42.062451 -97.564723)
			(xy 42.171131 -97.546906) (xy 42.280814 -97.536977) (xy 42.390927 -97.534989) (xy 42.500897 -97.540951)
			(xy 42.61015 -97.554833) (xy 42.718116 -97.576563) (xy 42.824233 -97.606026) (xy 42.927947 -97.643069)
			(xy 43.028718 -97.6875) (xy 43.12602 -97.739087) (xy 43.219346 -97.797559) (xy 43.308209 -97.862614)
			(xy 43.392147 -97.933912) (xy 43.470722 -98.01108) (xy 43.543523 -98.093717) (xy 43.610171 -98.181391)
			(xy 43.67032 -98.273647) (xy 43.723654 -98.370002) (xy 43.769897 -98.469954) (xy 43.808807 -98.572982)
			(xy 43.840181 -98.67855) (xy 43.863856 -98.786106) (xy 43.879708 -98.89509) (xy 43.887655 -99.004934)
			(xy 43.888152 -99.06) (xy 60.396131 -99.06) (xy 60.400106 -98.949941) (xy 60.412014 -98.840455) (xy 60.43179 -98.732114)
			(xy 60.459333 -98.625483) (xy 60.494498 -98.521117) (xy 60.537102 -98.41956) (xy 60.586923 -98.321343)
			(xy 60.643702 -98.226976) (xy 60.707141 -98.136952) (xy 60.776912 -98.051741) (xy 60.852649 -97.971786)
			(xy 60.933958 -97.897505) (xy 61.020415 -97.829285) (xy 61.111569 -97.76748) (xy 61.206946 -97.712415)
			(xy 61.306047 -97.664375) (xy 61.408356 -97.623611) (xy 61.51334 -97.590336) (xy 61.620451 -97.564723)
			(xy 61.729131 -97.546906) (xy 61.838814 -97.536977) (xy 61.948927 -97.534989) (xy 62.058897 -97.540951)
			(xy 62.16815 -97.554833) (xy 62.276116 -97.576563) (xy 62.382233 -97.606026) (xy 62.485947 -97.643069)
			(xy 62.586718 -97.6875) (xy 62.68402 -97.739087) (xy 62.777346 -97.797559) (xy 62.866209 -97.862614)
			(xy 62.950147 -97.933912) (xy 63.028722 -98.01108) (xy 63.101523 -98.093717) (xy 63.168171 -98.181391)
			(xy 63.22832 -98.273647) (xy 63.281654 -98.370002) (xy 63.327897 -98.469954) (xy 63.366807 -98.572982)
			(xy 63.398181 -98.67855) (xy 63.421856 -98.786106) (xy 63.437708 -98.89509) (xy 63.445655 -99.004934)
			(xy 63.446152 -99.06) (xy 376.553741 -99.06) (xy 376.557716 -98.949941) (xy 376.569624 -98.840455)
			(xy 376.5894 -98.732114) (xy 376.616943 -98.625483) (xy 376.652108 -98.521117) (xy 376.694712 -98.41956)
			(xy 376.744533 -98.321343) (xy 376.801312 -98.226976) (xy 376.864751 -98.136952) (xy 376.934522 -98.051741)
			(xy 377.010259 -97.971786) (xy 377.091568 -97.897505) (xy 377.178025 -97.829285) (xy 377.269179 -97.76748)
			(xy 377.364556 -97.712415) (xy 377.463657 -97.664375) (xy 377.565966 -97.623611) (xy 377.67095 -97.590336)
			(xy 377.778061 -97.564723) (xy 377.886741 -97.546906) (xy 377.996424 -97.536977) (xy 378.106537 -97.534989)
			(xy 378.216507 -97.540951) (xy 378.32576 -97.554833) (xy 378.433726 -97.576563) (xy 378.539843 -97.606026)
			(xy 378.643557 -97.643069) (xy 378.744328 -97.6875) (xy 378.84163 -97.739087) (xy 378.934956 -97.797559)
			(xy 379.023819 -97.862614) (xy 379.107757 -97.933912) (xy 379.186332 -98.01108) (xy 379.259133 -98.093717)
			(xy 379.325781 -98.181391) (xy 379.38593 -98.273647) (xy 379.439264 -98.370002) (xy 379.485507 -98.469954)
			(xy 379.524417 -98.572982) (xy 379.555791 -98.67855) (xy 379.579466 -98.786106) (xy 379.595318 -98.89509)
			(xy 379.603265 -99.004934) (xy 379.603762 -99.06) (xy 396.111741 -99.06) (xy 396.115716 -98.949941)
			(xy 396.127624 -98.840455) (xy 396.1474 -98.732114) (xy 396.174943 -98.625483) (xy 396.210108 -98.521117)
			(xy 396.252712 -98.41956) (xy 396.302533 -98.321343) (xy 396.359312 -98.226976) (xy 396.422751 -98.136952)
			(xy 396.492522 -98.051741) (xy 396.568259 -97.971786) (xy 396.649568 -97.897505) (xy 396.736025 -97.829285)
			(xy 396.827179 -97.76748) (xy 396.922556 -97.712415) (xy 397.021657 -97.664375) (xy 397.123966 -97.623611)
			(xy 397.22895 -97.590336) (xy 397.336061 -97.564723) (xy 397.444741 -97.546906) (xy 397.554424 -97.536977)
			(xy 397.664537 -97.534989) (xy 397.774507 -97.540951) (xy 397.88376 -97.554833) (xy 397.991726 -97.576563)
			(xy 398.097843 -97.606026) (xy 398.201557 -97.643069) (xy 398.302328 -97.6875) (xy 398.39963 -97.739087)
			(xy 398.492956 -97.797559) (xy 398.581819 -97.862614) (xy 398.665757 -97.933912) (xy 398.744332 -98.01108)
			(xy 398.817133 -98.093717) (xy 398.883781 -98.181391) (xy 398.94393 -98.273647) (xy 398.997264 -98.370002)
			(xy 399.043507 -98.469954) (xy 399.082417 -98.572982) (xy 399.113791 -98.67855) (xy 399.137466 -98.786106)
			(xy 399.153318 -98.89509) (xy 399.161265 -99.004934) (xy 399.161762 -99.06) (xy 399.161265 -99.115066)
			(xy 399.153318 -99.22491) (xy 399.137466 -99.333894) (xy 399.113791 -99.44145) (xy 399.082417 -99.547018)
			(xy 399.043507 -99.650046) (xy 398.997264 -99.749998) (xy 398.94393 -99.846353) (xy 398.883781 -99.938609)
			(xy 398.817133 -100.026283) (xy 398.744332 -100.10892) (xy 398.665757 -100.186088) (xy 398.581819 -100.257386)
			(xy 398.492956 -100.322441) (xy 398.39963 -100.380913) (xy 398.302328 -100.4325) (xy 398.201557 -100.476931)
			(xy 398.097843 -100.513974) (xy 397.991726 -100.543437) (xy 397.88376 -100.565167) (xy 397.774507 -100.579049)
			(xy 397.664537 -100.585011) (xy 397.554424 -100.583023) (xy 397.444741 -100.573094) (xy 397.336061 -100.555277)
			(xy 397.22895 -100.529664) (xy 397.123966 -100.496389) (xy 397.021657 -100.455625) (xy 396.922556 -100.407585)
			(xy 396.827179 -100.35252) (xy 396.736025 -100.290715) (xy 396.649568 -100.222495) (xy 396.568259 -100.148214)
			(xy 396.492522 -100.068259) (xy 396.422751 -99.983048) (xy 396.359312 -99.893024) (xy 396.302533 -99.798657)
			(xy 396.252712 -99.70044) (xy 396.210108 -99.598883) (xy 396.174943 -99.494517) (xy 396.1474 -99.387886)
			(xy 396.127624 -99.279545) (xy 396.115716 -99.170059) (xy 396.111741 -99.06) (xy 379.603762 -99.06)
			(xy 379.603265 -99.115066) (xy 379.595318 -99.22491) (xy 379.579466 -99.333894) (xy 379.555791 -99.44145)
			(xy 379.524417 -99.547018) (xy 379.485507 -99.650046) (xy 379.439264 -99.749998) (xy 379.38593 -99.846353)
			(xy 379.325781 -99.938609) (xy 379.259133 -100.026283) (xy 379.186332 -100.10892) (xy 379.107757 -100.186088)
			(xy 379.023819 -100.257386) (xy 378.934956 -100.322441) (xy 378.84163 -100.380913) (xy 378.744328 -100.4325)
			(xy 378.643557 -100.476931) (xy 378.539843 -100.513974) (xy 378.433726 -100.543437) (xy 378.32576 -100.565167)
			(xy 378.216507 -100.579049) (xy 378.106537 -100.585011) (xy 377.996424 -100.583023) (xy 377.886741 -100.573094)
			(xy 377.778061 -100.555277) (xy 377.67095 -100.529664) (xy 377.565966 -100.496389) (xy 377.463657 -100.455625)
			(xy 377.364556 -100.407585) (xy 377.269179 -100.35252) (xy 377.178025 -100.290715) (xy 377.091568 -100.222495)
			(xy 377.010259 -100.148214) (xy 376.934522 -100.068259) (xy 376.864751 -99.983048) (xy 376.801312 -99.893024)
			(xy 376.744533 -99.798657) (xy 376.694712 -99.70044) (xy 376.652108 -99.598883) (xy 376.616943 -99.494517)
			(xy 376.5894 -99.387886) (xy 376.569624 -99.279545) (xy 376.557716 -99.170059) (xy 376.553741 -99.06)
			(xy 63.446152 -99.06) (xy 63.445655 -99.115066) (xy 63.437708 -99.22491) (xy 63.421856 -99.333894)
			(xy 63.398181 -99.44145) (xy 63.366807 -99.547018) (xy 63.327897 -99.650046) (xy 63.281654 -99.749998)
			(xy 63.22832 -99.846353) (xy 63.168171 -99.938609) (xy 63.101523 -100.026283) (xy 63.028722 -100.10892)
			(xy 62.950147 -100.186088) (xy 62.866209 -100.257386) (xy 62.777346 -100.322441) (xy 62.68402 -100.380913)
			(xy 62.586718 -100.4325) (xy 62.485947 -100.476931) (xy 62.382233 -100.513974) (xy 62.276116 -100.543437)
			(xy 62.16815 -100.565167) (xy 62.058897 -100.579049) (xy 61.948927 -100.585011) (xy 61.838814 -100.583023)
			(xy 61.729131 -100.573094) (xy 61.620451 -100.555277) (xy 61.51334 -100.529664) (xy 61.408356 -100.496389)
			(xy 61.306047 -100.455625) (xy 61.206946 -100.407585) (xy 61.111569 -100.35252) (xy 61.020415 -100.290715)
			(xy 60.933958 -100.222495) (xy 60.852649 -100.148214) (xy 60.776912 -100.068259) (xy 60.707141 -99.983048)
			(xy 60.643702 -99.893024) (xy 60.586923 -99.798657) (xy 60.537102 -99.70044) (xy 60.494498 -99.598883)
			(xy 60.459333 -99.494517) (xy 60.43179 -99.387886) (xy 60.412014 -99.279545) (xy 60.400106 -99.170059)
			(xy 60.396131 -99.06) (xy 43.888152 -99.06) (xy 43.887655 -99.115066) (xy 43.879708 -99.22491) (xy 43.863856 -99.333894)
			(xy 43.840181 -99.44145) (xy 43.808807 -99.547018) (xy 43.769897 -99.650046) (xy 43.723654 -99.749998)
			(xy 43.67032 -99.846353) (xy 43.610171 -99.938609) (xy 43.543523 -100.026283) (xy 43.470722 -100.10892)
			(xy 43.392147 -100.186088) (xy 43.308209 -100.257386) (xy 43.219346 -100.322441) (xy 43.12602 -100.380913)
			(xy 43.028718 -100.4325) (xy 42.927947 -100.476931) (xy 42.824233 -100.513974) (xy 42.718116 -100.543437)
			(xy 42.61015 -100.565167) (xy 42.500897 -100.579049) (xy 42.390927 -100.585011) (xy 42.280814 -100.583023)
			(xy 42.171131 -100.573094) (xy 42.062451 -100.555277) (xy 41.95534 -100.529664) (xy 41.850356 -100.496389)
			(xy 41.748047 -100.455625) (xy 41.648946 -100.407585) (xy 41.553569 -100.35252) (xy 41.462415 -100.290715)
			(xy 41.375958 -100.222495) (xy 41.294649 -100.148214) (xy 41.218912 -100.068259) (xy 41.149141 -99.983048)
			(xy 41.085702 -99.893024) (xy 41.028923 -99.798657) (xy 40.979102 -99.70044) (xy 40.936498 -99.598883)
			(xy 40.901333 -99.494517) (xy 40.87379 -99.387886) (xy 40.854014 -99.279545) (xy 40.842106 -99.170059)
			(xy 40.838131 -99.06) (xy 0.509016 -99.06) (xy 0.509016 -104.544876) (xy 12.484104 -104.544876) (xy 12.488134 -104.402541)
			(xy 12.500209 -104.260661) (xy 12.520292 -104.119693) (xy 12.548319 -103.980086) (xy 12.584199 -103.842288)
			(xy 12.627817 -103.706741) (xy 12.679034 -103.573879) (xy 12.737685 -103.444127) (xy 12.803583 -103.317901)
			(xy 12.876517 -103.195605) (xy 12.956254 -103.077632) (xy 13.042536 -102.964359) (xy 13.135089 -102.856148)
			(xy 13.233616 -102.753347) (xy 13.337801 -102.656285) (xy 13.44731 -102.565273) (xy 13.561793 -102.480601)
			(xy 13.680883 -102.402543) (xy 13.804198 -102.331347) (xy 13.931344 -102.267241) (xy 14.061913 -102.210432)
			(xy 14.195487 -102.1611) (xy 14.331638 -102.119404) (xy 14.469929 -102.085478) (xy 14.609919 -102.05943)
			(xy 14.751158 -102.041344) (xy 14.893194 -102.031277) (xy 15.035572 -102.029262) (xy 15.177836 -102.035305)
			(xy 15.31953 -102.049387) (xy 15.4602 -102.071463) (xy 15.599397 -102.101463) (xy 15.736673 -102.139289)
			(xy 15.871589 -102.184821) (xy 16.003713 -102.237912) (xy 16.132622 -102.298394) (xy 16.257903 -102.366072)
			(xy 16.379154 -102.440729) (xy 16.495987 -102.522127) (xy 16.608028 -102.610004) (xy 16.714918 -102.704079)
			(xy 16.816315 -102.804051) (xy 16.911893 -102.909599) (xy 17.001347 -103.020385) (xy 17.084389 -103.136054)
			(xy 17.160755 -103.256237) (xy 17.230199 -103.380547) (xy 17.292499 -103.508588) (xy 17.347455 -103.639947)
			(xy 17.394892 -103.774206) (xy 17.434656 -103.910933) (xy 17.466622 -104.049691) (xy 17.490687 -104.190035)
			(xy 17.506773 -104.331516) (xy 17.514828 -104.47368) (xy 17.515332 -104.544876) (xy 17.514828 -104.616072)
			(xy 17.506773 -104.758236) (xy 17.490687 -104.899717) (xy 17.466622 -105.040061) (xy 17.434656 -105.178819)
			(xy 17.394892 -105.315546) (xy 17.347455 -105.449805) (xy 17.292499 -105.581164) (xy 17.230199 -105.709205)
			(xy 17.160755 -105.833515) (xy 17.084389 -105.953698) (xy 17.001347 -106.069367) (xy 16.911893 -106.180153)
			(xy 16.816315 -106.285701) (xy 16.714918 -106.385673) (xy 16.608028 -106.479748) (xy 16.495987 -106.567625)
			(xy 16.379154 -106.649023) (xy 16.257903 -106.72368) (xy 16.132622 -106.791358) (xy 16.003713 -106.85184)
			(xy 15.871589 -106.904931) (xy 15.736673 -106.950463) (xy 15.599397 -106.988289) (xy 15.4602 -107.018289)
			(xy 15.31953 -107.040365) (xy 15.177836 -107.054447) (xy 15.035572 -107.06049) (xy 14.893194 -107.058475)
			(xy 14.751158 -107.048408) (xy 14.609919 -107.030322) (xy 14.469929 -107.004274) (xy 14.331638 -106.970348)
			(xy 14.195487 -106.928652) (xy 14.061913 -106.87932) (xy 13.931344 -106.822511) (xy 13.804198 -106.758405)
			(xy 13.680883 -106.687209) (xy 13.561793 -106.609151) (xy 13.44731 -106.524479) (xy 13.337801 -106.433467)
			(xy 13.233616 -106.336405) (xy 13.135089 -106.233604) (xy 13.042536 -106.125393) (xy 12.956254 -106.01212)
			(xy 12.876517 -105.894147) (xy 12.803583 -105.771851) (xy 12.737685 -105.645625) (xy 12.679034 -105.515873)
			(xy 12.627817 -105.383011) (xy 12.584199 -105.247464) (xy 12.548319 -105.109666) (xy 12.520292 -104.970059)
			(xy 12.500209 -104.829091) (xy 12.488134 -104.687211) (xy 12.484104 -104.544876) (xy 0.509016 -104.544876)
			(xy 0.509016 -111.879888) (xy 41.345622 -111.879888) (xy 41.349604 -111.789938) (xy 41.361521 -111.700691)
			(xy 41.381279 -111.612847) (xy 41.408723 -111.527093) (xy 41.443639 -111.4441) (xy 41.485753 -111.364518)
			(xy 41.534736 -111.288969) (xy 41.590204 -111.218045) (xy 41.651724 -111.1523) (xy 41.718813 -111.09225)
			(xy 41.790947 -111.038365) (xy 41.867561 -110.991065) (xy 41.948055 -110.950722) (xy 42.0318 -110.91765)
			(xy 42.118141 -110.89211) (xy 42.2064 -110.8743) (xy 42.295889 -110.86436) (xy 42.385905 -110.862369)
			(xy 42.475746 -110.86834) (xy 42.564707 -110.882229) (xy 42.652092 -110.903925) (xy 42.737218 -110.93326)
			(xy 42.819418 -110.970003) (xy 42.898049 -111.013867) (xy 42.972496 -111.064509) (xy 43.042176 -111.121533)
			(xy 43.106543 -111.184492) (xy 43.165094 -111.252893) (xy 43.217371 -111.326201) (xy 43.262964 -111.403843)
			(xy 43.301517 -111.48521) (xy 43.332728 -111.569666) (xy 43.356352 -111.65655) (xy 43.372205 -111.745182)
			(xy 43.380162 -111.834869) (xy 43.38066 -111.879888) (xy 60.903622 -111.879888) (xy 60.907604 -111.789938)
			(xy 60.919521 -111.700691) (xy 60.939279 -111.612847) (xy 60.966723 -111.527093) (xy 61.001639 -111.4441)
			(xy 61.043753 -111.364518) (xy 61.092736 -111.288969) (xy 61.148204 -111.218045) (xy 61.209724 -111.1523)
			(xy 61.276813 -111.09225) (xy 61.348947 -111.038365) (xy 61.425561 -110.991065) (xy 61.506055 -110.950722)
			(xy 61.5898 -110.91765) (xy 61.676141 -110.89211) (xy 61.7644 -110.8743) (xy 61.853889 -110.86436)
			(xy 61.943905 -110.862369) (xy 62.033746 -110.86834) (xy 62.122707 -110.882229) (xy 62.210092 -110.903925)
			(xy 62.295218 -110.93326) (xy 62.377418 -110.970003) (xy 62.456049 -111.013867) (xy 62.530496 -111.064509)
			(xy 62.600176 -111.121533) (xy 62.664543 -111.184492) (xy 62.723094 -111.252893) (xy 62.775371 -111.326201)
			(xy 62.820964 -111.403843) (xy 62.859517 -111.48521) (xy 62.890728 -111.569666) (xy 62.914352 -111.65655)
			(xy 62.930205 -111.745182) (xy 62.938162 -111.834869) (xy 62.93866 -111.879888) (xy 62.938162 -111.924907)
			(xy 62.930205 -112.014594) (xy 62.914352 -112.103226) (xy 62.890728 -112.19011) (xy 62.859517 -112.274566)
			(xy 62.820964 -112.355933) (xy 62.775371 -112.433575) (xy 62.723094 -112.506883) (xy 62.664543 -112.575284)
			(xy 62.600176 -112.638243) (xy 62.530496 -112.695267) (xy 62.456049 -112.745909) (xy 62.377418 -112.789773)
			(xy 62.295218 -112.826516) (xy 62.210092 -112.855851) (xy 62.122707 -112.877547) (xy 62.033746 -112.891436)
			(xy 61.943905 -112.897407) (xy 61.853889 -112.895416) (xy 61.7644 -112.885476) (xy 61.676141 -112.867666)
			(xy 61.5898 -112.842126) (xy 61.506055 -112.809054) (xy 61.425561 -112.768711) (xy 61.348947 -112.721411)
			(xy 61.276813 -112.667526) (xy 61.209724 -112.607476) (xy 61.148204 -112.541731) (xy 61.092736 -112.470807)
			(xy 61.043753 -112.395258) (xy 61.001639 -112.315676) (xy 60.966723 -112.232683) (xy 60.939279 -112.146929)
			(xy 60.919521 -112.059085) (xy 60.907604 -111.969838) (xy 60.903622 -111.879888) (xy 43.38066 -111.879888)
			(xy 43.380162 -111.924907) (xy 43.372205 -112.014594) (xy 43.356352 -112.103226) (xy 43.332728 -112.19011)
			(xy 43.301517 -112.274566) (xy 43.262964 -112.355933) (xy 43.217371 -112.433575) (xy 43.165094 -112.506883)
			(xy 43.106543 -112.575284) (xy 43.042176 -112.638243) (xy 42.972496 -112.695267) (xy 42.898049 -112.745909)
			(xy 42.819418 -112.789773) (xy 42.737218 -112.826516) (xy 42.652092 -112.855851) (xy 42.564707 -112.877547)
			(xy 42.475746 -112.891436) (xy 42.385905 -112.897407) (xy 42.295889 -112.895416) (xy 42.2064 -112.885476)
			(xy 42.118141 -112.867666) (xy 42.0318 -112.842126) (xy 41.948055 -112.809054) (xy 41.867561 -112.768711)
			(xy 41.790947 -112.721411) (xy 41.718813 -112.667526) (xy 41.651724 -112.607476) (xy 41.590204 -112.541731)
			(xy 41.534736 -112.470807) (xy 41.485753 -112.395258) (xy 41.443639 -112.315676) (xy 41.408723 -112.232683)
			(xy 41.381279 -112.146929) (xy 41.361521 -112.059085) (xy 41.349604 -111.969838) (xy 41.345622 -111.879888)
			(xy 0.509016 -111.879888) (xy 0.509016 -119.38) (xy 40.838131 -119.38) (xy 40.842106 -119.269941)
			(xy 40.854014 -119.160455) (xy 40.87379 -119.052114) (xy 40.901333 -118.945483) (xy 40.936498 -118.841117)
			(xy 40.979102 -118.73956) (xy 41.028923 -118.641343) (xy 41.085702 -118.546976) (xy 41.149141 -118.456952)
			(xy 41.218912 -118.371741) (xy 41.294649 -118.291786) (xy 41.375958 -118.217505) (xy 41.462415 -118.149285)
			(xy 41.553569 -118.08748) (xy 41.648946 -118.032415) (xy 41.748047 -117.984375) (xy 41.850356 -117.943611)
			(xy 41.95534 -117.910336) (xy 42.062451 -117.884723) (xy 42.171131 -117.866906) (xy 42.280814 -117.856977)
			(xy 42.390927 -117.854989) (xy 42.500897 -117.860951) (xy 42.61015 -117.874833) (xy 42.718116 -117.896563)
			(xy 42.824233 -117.926026) (xy 42.927947 -117.963069) (xy 43.028718 -118.0075) (xy 43.12602 -118.059087)
			(xy 43.219346 -118.117559) (xy 43.308209 -118.182614) (xy 43.392147 -118.253912) (xy 43.470722 -118.33108)
			(xy 43.543523 -118.413717) (xy 43.610171 -118.501391) (xy 43.67032 -118.593647) (xy 43.723654 -118.690002)
			(xy 43.769897 -118.789954) (xy 43.808807 -118.892982) (xy 43.840181 -118.99855) (xy 43.863856 -119.106106)
			(xy 43.879708 -119.21509) (xy 43.887655 -119.324934) (xy 43.888152 -119.38) (xy 60.396131 -119.38)
			(xy 60.400106 -119.269941) (xy 60.412014 -119.160455) (xy 60.43179 -119.052114) (xy 60.459333 -118.945483)
			(xy 60.494498 -118.841117) (xy 60.537102 -118.73956) (xy 60.586923 -118.641343) (xy 60.643702 -118.546976)
			(xy 60.707141 -118.456952) (xy 60.776912 -118.371741) (xy 60.852649 -118.291786) (xy 60.933958 -118.217505)
			(xy 61.020415 -118.149285) (xy 61.111569 -118.08748) (xy 61.206946 -118.032415) (xy 61.306047 -117.984375)
			(xy 61.408356 -117.943611) (xy 61.51334 -117.910336) (xy 61.620451 -117.884723) (xy 61.729131 -117.866906)
			(xy 61.838814 -117.856977) (xy 61.948927 -117.854989) (xy 62.058897 -117.860951) (xy 62.16815 -117.874833)
			(xy 62.276116 -117.896563) (xy 62.382233 -117.926026) (xy 62.485947 -117.963069) (xy 62.586718 -118.0075)
			(xy 62.68402 -118.059087) (xy 62.777346 -118.117559) (xy 62.866209 -118.182614) (xy 62.950147 -118.253912)
			(xy 63.028722 -118.33108) (xy 63.101523 -118.413717) (xy 63.168171 -118.501391) (xy 63.22832 -118.593647)
			(xy 63.281654 -118.690002) (xy 63.327897 -118.789954) (xy 63.366807 -118.892982) (xy 63.398181 -118.99855)
			(xy 63.421856 -119.106106) (xy 63.437708 -119.21509) (xy 63.445655 -119.324934) (xy 63.446152 -119.38)
			(xy 63.445655 -119.435066) (xy 63.437708 -119.54491) (xy 63.421856 -119.653894) (xy 63.398181 -119.76145)
			(xy 63.366807 -119.867018) (xy 63.327897 -119.970046) (xy 63.281654 -120.069998) (xy 63.22832 -120.166353)
			(xy 63.168171 -120.258609) (xy 63.101523 -120.346283) (xy 63.028722 -120.42892) (xy 62.950147 -120.506088)
			(xy 62.866209 -120.577386) (xy 62.777346 -120.642441) (xy 62.68402 -120.700913) (xy 62.586718 -120.7525)
			(xy 62.485947 -120.796931) (xy 62.382233 -120.833974) (xy 62.276116 -120.863437) (xy 62.16815 -120.885167)
			(xy 62.058897 -120.899049) (xy 61.948927 -120.905011) (xy 61.838814 -120.903023) (xy 61.729131 -120.893094)
			(xy 61.620451 -120.875277) (xy 61.51334 -120.849664) (xy 61.408356 -120.816389) (xy 61.306047 -120.775625)
			(xy 61.206946 -120.727585) (xy 61.111569 -120.67252) (xy 61.020415 -120.610715) (xy 60.933958 -120.542495)
			(xy 60.852649 -120.468214) (xy 60.776912 -120.388259) (xy 60.707141 -120.303048) (xy 60.643702 -120.213024)
			(xy 60.586923 -120.118657) (xy 60.537102 -120.02044) (xy 60.494498 -119.918883) (xy 60.459333 -119.814517)
			(xy 60.43179 -119.707886) (xy 60.412014 -119.599545) (xy 60.400106 -119.490059) (xy 60.396131 -119.38)
			(xy 43.888152 -119.38) (xy 43.887655 -119.435066) (xy 43.879708 -119.54491) (xy 43.863856 -119.653894)
			(xy 43.840181 -119.76145) (xy 43.808807 -119.867018) (xy 43.769897 -119.970046) (xy 43.723654 -120.069998)
			(xy 43.67032 -120.166353) (xy 43.610171 -120.258609) (xy 43.543523 -120.346283) (xy 43.470722 -120.42892)
			(xy 43.392147 -120.506088) (xy 43.308209 -120.577386) (xy 43.219346 -120.642441) (xy 43.12602 -120.700913)
			(xy 43.028718 -120.7525) (xy 42.927947 -120.796931) (xy 42.824233 -120.833974) (xy 42.718116 -120.863437)
			(xy 42.61015 -120.885167) (xy 42.500897 -120.899049) (xy 42.390927 -120.905011) (xy 42.280814 -120.903023)
			(xy 42.171131 -120.893094) (xy 42.062451 -120.875277) (xy 41.95534 -120.849664) (xy 41.850356 -120.816389)
			(xy 41.748047 -120.775625) (xy 41.648946 -120.727585) (xy 41.553569 -120.67252) (xy 41.462415 -120.610715)
			(xy 41.375958 -120.542495) (xy 41.294649 -120.468214) (xy 41.218912 -120.388259) (xy 41.149141 -120.303048)
			(xy 41.085702 -120.213024) (xy 41.028923 -120.118657) (xy 40.979102 -120.02044) (xy 40.936498 -119.918883)
			(xy 40.901333 -119.814517) (xy 40.87379 -119.707886) (xy 40.854014 -119.599545) (xy 40.842106 -119.490059)
			(xy 40.838131 -119.38) (xy 0.509016 -119.38) (xy 0.509016 -132.199888) (xy 41.345622 -132.199888)
			(xy 41.349604 -132.109938) (xy 41.361521 -132.020691) (xy 41.381279 -131.932847) (xy 41.408723 -131.847093)
			(xy 41.443639 -131.7641) (xy 41.485753 -131.684518) (xy 41.534736 -131.608969) (xy 41.590204 -131.538045)
			(xy 41.651724 -131.4723) (xy 41.718813 -131.41225) (xy 41.790947 -131.358365) (xy 41.867561 -131.311065)
			(xy 41.948055 -131.270722) (xy 42.0318 -131.23765) (xy 42.118141 -131.21211) (xy 42.2064 -131.1943)
			(xy 42.295889 -131.18436) (xy 42.385905 -131.182369) (xy 42.475746 -131.18834) (xy 42.564707 -131.202229)
			(xy 42.652092 -131.223925) (xy 42.737218 -131.25326) (xy 42.819418 -131.290003) (xy 42.898049 -131.333867)
			(xy 42.972496 -131.384509) (xy 43.042176 -131.441533) (xy 43.106543 -131.504492) (xy 43.165094 -131.572893)
			(xy 43.217371 -131.646201) (xy 43.262964 -131.723843) (xy 43.301517 -131.80521) (xy 43.332728 -131.889666)
			(xy 43.356352 -131.97655) (xy 43.372205 -132.065182) (xy 43.380162 -132.154869) (xy 43.38066 -132.199888)
			(xy 60.903622 -132.199888) (xy 60.907604 -132.109938) (xy 60.919521 -132.020691) (xy 60.939279 -131.932847)
			(xy 60.966723 -131.847093) (xy 61.001639 -131.7641) (xy 61.043753 -131.684518) (xy 61.092736 -131.608969)
			(xy 61.148204 -131.538045) (xy 61.209724 -131.4723) (xy 61.276813 -131.41225) (xy 61.348947 -131.358365)
			(xy 61.425561 -131.311065) (xy 61.506055 -131.270722) (xy 61.5898 -131.23765) (xy 61.676141 -131.21211)
			(xy 61.7644 -131.1943) (xy 61.853889 -131.18436) (xy 61.943905 -131.182369) (xy 62.033746 -131.18834)
			(xy 62.122707 -131.202229) (xy 62.210092 -131.223925) (xy 62.295218 -131.25326) (xy 62.377418 -131.290003)
			(xy 62.456049 -131.333867) (xy 62.530496 -131.384509) (xy 62.600176 -131.441533) (xy 62.664543 -131.504492)
			(xy 62.723094 -131.572893) (xy 62.775371 -131.646201) (xy 62.820964 -131.723843) (xy 62.859517 -131.80521)
			(xy 62.890728 -131.889666) (xy 62.914352 -131.97655) (xy 62.930205 -132.065182) (xy 62.938162 -132.154869)
			(xy 62.93866 -132.199888) (xy 62.938162 -132.244907) (xy 62.930205 -132.334594) (xy 62.914352 -132.423226)
			(xy 62.890728 -132.51011) (xy 62.859517 -132.594566) (xy 62.820964 -132.675933) (xy 62.775371 -132.753575)
			(xy 62.723094 -132.826883) (xy 62.664543 -132.895284) (xy 62.600176 -132.958243) (xy 62.530496 -133.015267)
			(xy 62.456049 -133.065909) (xy 62.377418 -133.109773) (xy 62.295218 -133.146516) (xy 62.210092 -133.175851)
			(xy 62.122707 -133.197547) (xy 62.033746 -133.211436) (xy 61.943905 -133.217407) (xy 61.853889 -133.215416)
			(xy 61.7644 -133.205476) (xy 61.676141 -133.187666) (xy 61.5898 -133.162126) (xy 61.506055 -133.129054)
			(xy 61.425561 -133.088711) (xy 61.348947 -133.041411) (xy 61.276813 -132.987526) (xy 61.209724 -132.927476)
			(xy 61.148204 -132.861731) (xy 61.092736 -132.790807) (xy 61.043753 -132.715258) (xy 61.001639 -132.635676)
			(xy 60.966723 -132.552683) (xy 60.939279 -132.466929) (xy 60.919521 -132.379085) (xy 60.907604 -132.289838)
			(xy 60.903622 -132.199888) (xy 43.38066 -132.199888) (xy 43.380162 -132.244907) (xy 43.372205 -132.334594)
			(xy 43.356352 -132.423226) (xy 43.332728 -132.51011) (xy 43.301517 -132.594566) (xy 43.262964 -132.675933)
			(xy 43.217371 -132.753575) (xy 43.165094 -132.826883) (xy 43.106543 -132.895284) (xy 43.042176 -132.958243)
			(xy 42.972496 -133.015267) (xy 42.898049 -133.065909) (xy 42.819418 -133.109773) (xy 42.737218 -133.146516)
			(xy 42.652092 -133.175851) (xy 42.564707 -133.197547) (xy 42.475746 -133.211436) (xy 42.385905 -133.217407)
			(xy 42.295889 -133.215416) (xy 42.2064 -133.205476) (xy 42.118141 -133.187666) (xy 42.0318 -133.162126)
			(xy 41.948055 -133.129054) (xy 41.867561 -133.088711) (xy 41.790947 -133.041411) (xy 41.718813 -132.987526)
			(xy 41.651724 -132.927476) (xy 41.590204 -132.861731) (xy 41.534736 -132.790807) (xy 41.485753 -132.715258)
			(xy 41.443639 -132.635676) (xy 41.408723 -132.552683) (xy 41.381279 -132.466929) (xy 41.361521 -132.379085)
			(xy 41.349604 -132.289838) (xy 41.345622 -132.199888) (xy 0.509016 -132.199888) (xy 0.509016 -139.7)
			(xy 40.838131 -139.7) (xy 40.842106 -139.589941) (xy 40.854014 -139.480455) (xy 40.87379 -139.372114)
			(xy 40.901333 -139.265483) (xy 40.936498 -139.161117) (xy 40.979102 -139.05956) (xy 41.028923 -138.961343)
			(xy 41.085702 -138.866976) (xy 41.149141 -138.776952) (xy 41.218912 -138.691741) (xy 41.294649 -138.611786)
			(xy 41.375958 -138.537505) (xy 41.462415 -138.469285) (xy 41.553569 -138.40748) (xy 41.648946 -138.352415)
			(xy 41.748047 -138.304375) (xy 41.850356 -138.263611) (xy 41.95534 -138.230336) (xy 42.062451 -138.204723)
			(xy 42.171131 -138.186906) (xy 42.280814 -138.176977) (xy 42.390927 -138.174989) (xy 42.500897 -138.180951)
			(xy 42.61015 -138.194833) (xy 42.718116 -138.216563) (xy 42.824233 -138.246026) (xy 42.927947 -138.283069)
			(xy 43.028718 -138.3275) (xy 43.12602 -138.379087) (xy 43.219346 -138.437559) (xy 43.308209 -138.502614)
			(xy 43.392147 -138.573912) (xy 43.470722 -138.65108) (xy 43.543523 -138.733717) (xy 43.610171 -138.821391)
			(xy 43.67032 -138.913647) (xy 43.723654 -139.010002) (xy 43.769897 -139.109954) (xy 43.808807 -139.212982)
			(xy 43.840181 -139.31855) (xy 43.863856 -139.426106) (xy 43.879708 -139.53509) (xy 43.887655 -139.644934)
			(xy 43.888152 -139.7) (xy 60.396131 -139.7) (xy 60.400106 -139.589941) (xy 60.412014 -139.480455)
			(xy 60.43179 -139.372114) (xy 60.459333 -139.265483) (xy 60.494498 -139.161117) (xy 60.537102 -139.05956)
			(xy 60.586923 -138.961343) (xy 60.643702 -138.866976) (xy 60.707141 -138.776952) (xy 60.776912 -138.691741)
			(xy 60.852649 -138.611786) (xy 60.933958 -138.537505) (xy 61.020415 -138.469285) (xy 61.111569 -138.40748)
			(xy 61.206946 -138.352415) (xy 61.306047 -138.304375) (xy 61.408356 -138.263611) (xy 61.51334 -138.230336)
			(xy 61.620451 -138.204723) (xy 61.729131 -138.186906) (xy 61.838814 -138.176977) (xy 61.948927 -138.174989)
			(xy 62.058897 -138.180951) (xy 62.16815 -138.194833) (xy 62.276116 -138.216563) (xy 62.382233 -138.246026)
			(xy 62.485947 -138.283069) (xy 62.586718 -138.3275) (xy 62.68402 -138.379087) (xy 62.777346 -138.437559)
			(xy 62.866209 -138.502614) (xy 62.950147 -138.573912) (xy 63.028722 -138.65108) (xy 63.101523 -138.733717)
			(xy 63.168171 -138.821391) (xy 63.22832 -138.913647) (xy 63.281654 -139.010002) (xy 63.327897 -139.109954)
			(xy 63.366807 -139.212982) (xy 63.398181 -139.31855) (xy 63.421856 -139.426106) (xy 63.437708 -139.53509)
			(xy 63.445655 -139.644934) (xy 63.446152 -139.7) (xy 63.445655 -139.755066) (xy 63.437708 -139.86491)
			(xy 63.421856 -139.973894) (xy 63.398181 -140.08145) (xy 63.366807 -140.187018) (xy 63.327897 -140.290046)
			(xy 63.281654 -140.389998) (xy 63.22832 -140.486353) (xy 63.168171 -140.578609) (xy 63.101523 -140.666283)
			(xy 63.028722 -140.74892) (xy 62.950147 -140.826088) (xy 62.866209 -140.897386) (xy 62.777346 -140.962441)
			(xy 62.68402 -141.020913) (xy 62.586718 -141.0725) (xy 62.485947 -141.116931) (xy 62.382233 -141.153974)
			(xy 62.276116 -141.183437) (xy 62.16815 -141.205167) (xy 62.058897 -141.219049) (xy 61.948927 -141.225011)
			(xy 61.838814 -141.223023) (xy 61.729131 -141.213094) (xy 61.620451 -141.195277) (xy 61.51334 -141.169664)
			(xy 61.408356 -141.136389) (xy 61.306047 -141.095625) (xy 61.206946 -141.047585) (xy 61.111569 -140.99252)
			(xy 61.020415 -140.930715) (xy 60.933958 -140.862495) (xy 60.852649 -140.788214) (xy 60.776912 -140.708259)
			(xy 60.707141 -140.623048) (xy 60.643702 -140.533024) (xy 60.586923 -140.438657) (xy 60.537102 -140.34044)
			(xy 60.494498 -140.238883) (xy 60.459333 -140.134517) (xy 60.43179 -140.027886) (xy 60.412014 -139.919545)
			(xy 60.400106 -139.810059) (xy 60.396131 -139.7) (xy 43.888152 -139.7) (xy 43.887655 -139.755066)
			(xy 43.879708 -139.86491) (xy 43.863856 -139.973894) (xy 43.840181 -140.08145) (xy 43.808807 -140.187018)
			(xy 43.769897 -140.290046) (xy 43.723654 -140.389998) (xy 43.67032 -140.486353) (xy 43.610171 -140.578609)
			(xy 43.543523 -140.666283) (xy 43.470722 -140.74892) (xy 43.392147 -140.826088) (xy 43.308209 -140.897386)
			(xy 43.219346 -140.962441) (xy 43.12602 -141.020913) (xy 43.028718 -141.0725) (xy 42.927947 -141.116931)
			(xy 42.824233 -141.153974) (xy 42.718116 -141.183437) (xy 42.61015 -141.205167) (xy 42.500897 -141.219049)
			(xy 42.390927 -141.225011) (xy 42.280814 -141.223023) (xy 42.171131 -141.213094) (xy 42.062451 -141.195277)
			(xy 41.95534 -141.169664) (xy 41.850356 -141.136389) (xy 41.748047 -141.095625) (xy 41.648946 -141.047585)
			(xy 41.553569 -140.99252) (xy 41.462415 -140.930715) (xy 41.375958 -140.862495) (xy 41.294649 -140.788214)
			(xy 41.218912 -140.708259) (xy 41.149141 -140.623048) (xy 41.085702 -140.533024) (xy 41.028923 -140.438657)
			(xy 40.979102 -140.34044) (xy 40.936498 -140.238883) (xy 40.901333 -140.134517) (xy 40.87379 -140.027886)
			(xy 40.854014 -139.919545) (xy 40.842106 -139.810059) (xy 40.838131 -139.7) (xy 0.509016 -139.7)
			(xy 0.509016 -153.299922) (xy 0.509522 -153.395255) (xy 0.517614 -153.58575) (xy 0.533784 -153.77573)
			(xy 0.558002 -153.964852) (xy 0.590225 -154.152777) (xy 0.630395 -154.339164) (xy 0.678438 -154.523678)
			(xy 0.73427 -154.705987) (xy 0.797789 -154.885763) (xy 0.86888 -155.06268) (xy 0.947416 -155.236421)
			(xy 1.033255 -155.406672) (xy 1.126242 -155.573127) (xy 1.22621 -155.735485) (xy 1.332979 -155.893455)
			(xy 1.446356 -156.04675) (xy 1.566136 -156.195096) (xy 1.692105 -156.338224) (xy 1.824035 -156.475877)
			(xy 1.961688 -156.607806) (xy 2.104816 -156.733775) (xy 2.253162 -156.853556) (xy 2.406457 -156.966932)
			(xy 2.564426 -157.073701) (xy 2.726785 -157.173669) (xy 2.893239 -157.266656) (xy 3.063491 -157.352495)
			(xy 3.237232 -157.431031) (xy 3.414149 -157.502122) (xy 3.593924 -157.565641) (xy 3.776234 -157.621472)
			(xy 3.960748 -157.669516) (xy 4.147135 -157.709685) (xy 4.335059 -157.741908) (xy 4.524182 -157.766126)
			(xy 4.714162 -157.782296) (xy 4.904657 -157.790388) (xy 4.99999 -157.790896) (xy 25.999948 -157.790896)
			(xy 26.105482 -157.791395) (xy 26.316396 -157.79948) (xy 26.526845 -157.815637) (xy 26.73652 -157.839843)
			(xy 26.945115 -157.872062) (xy 27.152323 -157.912248) (xy 27.357839 -157.96034) (xy 27.561362 -158.016269)
			(xy 27.762594 -158.079953) (xy 27.961239 -158.151298) (xy 28.157005 -158.230198) (xy 28.349606 -158.31654)
			(xy 28.538758 -158.410195) (xy 28.724184 -158.511027) (xy 28.905612 -158.618886) (xy 29.082776 -158.733616)
			(xy 29.255415 -158.855048) (xy 29.423276 -158.983003) (xy 29.586113 -159.117293) (xy 29.743686 -159.257723)
			(xy 29.895766 -159.404084) (xy 30.042127 -159.556164) (xy 30.182557 -159.713737) (xy 30.316847 -159.876574)
			(xy 30.444802 -160.044435) (xy 30.566234 -160.217074) (xy 30.680964 -160.394238) (xy 30.788823 -160.575666)
			(xy 30.889655 -160.761092) (xy 30.98331 -160.950244) (xy 31.069652 -161.142845) (xy 31.148552 -161.338611)
			(xy 31.219897 -161.537256) (xy 31.283581 -161.738488) (xy 31.33951 -161.942011) (xy 31.387602 -162.147527)
			(xy 31.427788 -162.354735) (xy 31.460007 -162.56333) (xy 31.484213 -162.773005) (xy 31.50037 -162.983454)
			(xy 31.508455 -163.194368) (xy 31.508954 -163.299902) (xy 31.508954 -166.649908) (xy 31.50946 -166.745241)
			(xy 31.517552 -166.935736) (xy 31.533721 -167.125716) (xy 31.557939 -167.314839) (xy 31.590162 -167.502763)
			(xy 31.630332 -167.689151) (xy 31.678375 -167.873665) (xy 31.734207 -168.055975) (xy 31.797726 -168.23575)
			(xy 31.868817 -168.412668) (xy 31.947353 -168.586409) (xy 32.033192 -168.75666) (xy 32.074156 -168.82999)
			(xy 33.661096 -168.82999) (xy 33.661535 -168.782327) (xy 33.669022 -168.687296) (xy 33.683942 -168.593144)
			(xy 33.706203 -168.500454) (xy 33.735667 -168.409796) (xy 33.772152 -168.321729) (xy 33.815435 -168.236795)
			(xy 33.865248 -168.15552) (xy 33.921283 -168.078402) (xy 33.983196 -168.005919) (xy 34.050605 -167.938517)
			(xy 34.086546 -167.907208) (xy 34.094571 -167.899638) (xy 34.103786 -167.879619) (xy 34.104326 -167.8686)
			(xy 34.104326 -167.791384) (xy 34.103789 -167.780365) (xy 34.094568 -167.760349) (xy 34.086546 -167.752776)
			(xy 34.050612 -167.721463) (xy 33.983218 -167.654051) (xy 33.921318 -167.581561) (xy 33.865293 -167.504441)
			(xy 33.815489 -167.423164) (xy 33.772212 -167.338232) (xy 33.735729 -167.250168) (xy 33.706265 -167.159514)
			(xy 33.684 -167.066828) (xy 33.669073 -166.972682) (xy 33.661575 -166.877655) (xy 33.661096 -166.829994)
			(xy 33.661537 -166.782331) (xy 33.669025 -166.6873) (xy 33.683944 -166.593149) (xy 33.706205 -166.500458)
			(xy 33.735668 -166.4098) (xy 33.772154 -166.321733) (xy 33.815436 -166.2368) (xy 33.865249 -166.155524)
			(xy 33.921284 -166.078407) (xy 33.983197 -166.005923) (xy 34.050605 -165.938521) (xy 34.086546 -165.907212)
			(xy 34.094569 -165.89964) (xy 34.103786 -165.879623) (xy 34.104326 -165.868604) (xy 34.104326 -165.791388)
			(xy 34.103786 -165.78037) (xy 34.094567 -165.760354) (xy 34.086546 -165.75278) (xy 34.050614 -165.721464)
			(xy 33.98322 -165.654053) (xy 33.92132 -165.581563) (xy 33.865295 -165.504443) (xy 33.815491 -165.423167)
			(xy 33.772214 -165.338235) (xy 33.735731 -165.250171) (xy 33.706266 -165.159517) (xy 33.684001 -165.066832)
			(xy 33.669073 -164.972686) (xy 33.661575 -164.877659) (xy 33.661096 -164.829998) (xy 33.66154 -164.782335)
			(xy 33.669027 -164.687304) (xy 33.683947 -164.593153) (xy 33.706207 -164.500463) (xy 33.73567 -164.409804)
			(xy 33.772155 -164.321737) (xy 33.815437 -164.236804) (xy 33.865249 -164.155528) (xy 33.921284 -164.078411)
			(xy 33.983197 -164.005927) (xy 34.050606 -163.938525) (xy 34.086546 -163.907216) (xy 34.094567 -163.899643)
			(xy 34.103785 -163.879626) (xy 34.104326 -163.868608) (xy 34.104326 -163.791392) (xy 34.103784 -163.780374)
			(xy 34.094567 -163.760358) (xy 34.086546 -163.752784) (xy 34.050616 -163.721466) (xy 33.983221 -163.654055)
			(xy 33.921321 -163.581566) (xy 33.865297 -163.504446) (xy 33.815492 -163.42317) (xy 33.772215 -163.338238)
			(xy 33.735732 -163.250174) (xy 33.706267 -163.15952) (xy 33.684002 -163.066835) (xy 33.669074 -162.972689)
			(xy 33.661575 -162.877663) (xy 33.661096 -162.830002) (xy 33.661543 -162.782339) (xy 33.66903 -162.687308)
			(xy 33.683949 -162.593157) (xy 33.706209 -162.500467) (xy 33.735672 -162.409809) (xy 33.772157 -162.321741)
			(xy 33.815438 -162.236808) (xy 33.86525 -162.155532) (xy 33.921285 -162.078415) (xy 33.983197 -162.005932)
			(xy 34.050606 -161.938529) (xy 34.086546 -161.90722) (xy 34.094565 -161.899645) (xy 34.103784 -161.87963)
			(xy 34.104326 -161.868612) (xy 34.104326 -161.791396) (xy 34.103782 -161.780378) (xy 34.094566 -161.760362)
			(xy 34.086546 -161.752788) (xy 34.050618 -161.721468) (xy 33.983223 -161.654057) (xy 33.921323 -161.581568)
			(xy 33.865298 -161.504448) (xy 33.815494 -161.423172) (xy 33.772217 -161.338241) (xy 33.735733 -161.250177)
			(xy 33.706268 -161.159524) (xy 33.684002 -161.066839) (xy 33.669074 -160.972693) (xy 33.661575 -160.877667)
			(xy 33.661096 -160.830006) (xy 33.661546 -160.782343) (xy 33.669032 -160.687312) (xy 33.683951 -160.593161)
			(xy 33.70621 -160.500471) (xy 33.735673 -160.409813) (xy 33.772158 -160.321746) (xy 33.815439 -160.236812)
			(xy 33.865251 -160.155537) (xy 33.921286 -160.078419) (xy 33.983198 -160.005936) (xy 34.050606 -159.938533)
			(xy 34.086546 -159.907224) (xy 34.094563 -159.899647) (xy 34.103783 -159.879633) (xy 34.104326 -159.868616)
			(xy 34.104326 -159.7914) (xy 34.10378 -159.780382) (xy 34.094565 -159.760366) (xy 34.086546 -159.752792)
			(xy 34.05062 -159.72147) (xy 33.983225 -159.654059) (xy 33.921325 -159.58157) (xy 33.8653 -159.504451)
			(xy 33.815495 -159.423175) (xy 33.772218 -159.338244) (xy 33.735734 -159.250181) (xy 33.706269 -159.159527)
			(xy 33.684003 -159.066842) (xy 33.669075 -158.972697) (xy 33.661575 -158.877671) (xy 33.661096 -158.83001)
			(xy 33.661549 -158.782347) (xy 33.669035 -158.687316) (xy 33.683953 -158.593165) (xy 33.706212 -158.500475)
			(xy 33.735675 -158.409817) (xy 33.772159 -158.32175) (xy 33.815441 -158.236817) (xy 33.865252 -158.155541)
			(xy 33.921286 -158.078423) (xy 33.983198 -158.00594) (xy 34.050606 -157.938537) (xy 34.086546 -157.907228)
			(xy 34.094562 -157.89965) (xy 34.103782 -157.879637) (xy 34.104326 -157.86862) (xy 34.104326 -157.791404)
			(xy 34.103778 -157.780387) (xy 34.094565 -157.76037) (xy 34.086546 -157.752796) (xy 34.050621 -157.721472)
			(xy 33.983227 -157.654061) (xy 33.921327 -157.581573) (xy 33.865302 -157.504453) (xy 33.815497 -157.423178)
			(xy 33.772219 -157.338247) (xy 33.735735 -157.250184) (xy 33.70627 -157.159531) (xy 33.684004 -157.066846)
			(xy 33.669075 -156.972701) (xy 33.661575 -156.877675) (xy 33.661096 -156.830014) (xy 33.661552 -156.782351)
			(xy 33.669037 -156.68732) (xy 33.683956 -156.59317) (xy 33.706214 -156.50048) (xy 33.735677 -156.409821)
			(xy 33.772161 -156.321754) (xy 33.815442 -156.236821) (xy 33.865253 -156.155545) (xy 33.921287 -156.078428)
			(xy 33.983198 -156.005944) (xy 34.050606 -155.938541) (xy 34.086546 -155.907232) (xy 34.09456 -155.899652)
			(xy 34.103782 -155.879641) (xy 34.104326 -155.868624) (xy 34.104326 -155.791408) (xy 34.103776 -155.780391)
			(xy 34.094564 -155.760375) (xy 34.086546 -155.7528) (xy 34.050623 -155.721473) (xy 33.983229 -155.654063)
			(xy 33.921329 -155.581575) (xy 33.865303 -155.504456) (xy 33.815499 -155.423181) (xy 33.772221 -155.33825)
			(xy 33.735736 -155.250187) (xy 33.706271 -155.159534) (xy 33.684005 -155.06685) (xy 33.669076 -154.972705)
			(xy 33.661575 -154.877679) (xy 33.661096 -154.830018) (xy 33.661555 -154.782355) (xy 33.66904 -154.687325)
			(xy 33.683958 -154.593174) (xy 33.706216 -154.500484) (xy 33.735678 -154.409826) (xy 33.772162 -154.321759)
			(xy 33.815443 -154.236825) (xy 33.865254 -154.155549) (xy 33.921287 -154.078432) (xy 33.983199 -154.005948)
			(xy 34.050606 -153.938545) (xy 34.086546 -153.907236) (xy 34.094558 -153.899654) (xy 34.103781 -153.879644)
			(xy 34.104326 -153.868628) (xy 34.104326 -153.791412) (xy 34.103773 -153.780395) (xy 34.094564 -153.760379)
			(xy 34.086546 -153.752804) (xy 34.050625 -153.721475) (xy 33.983231 -153.654065) (xy 33.92133 -153.581577)
			(xy 33.865305 -153.504458) (xy 33.8155 -153.423183) (xy 33.772222 -153.338253) (xy 33.735738 -153.25019)
			(xy 33.706272 -153.159538) (xy 33.684005 -153.066853) (xy 33.669076 -152.972708) (xy 33.661576 -152.877683)
			(xy 33.661096 -152.830022) (xy 33.661673 -152.779839) (xy 33.66996 -152.679815) (xy 33.686478 -152.580818)
			(xy 33.711114 -152.483522) (xy 33.743701 -152.388593) (xy 33.784016 -152.29668) (xy 33.831783 -152.208409)
			(xy 33.886676 -152.124385) (xy 33.94832 -152.04518) (xy 34.016294 -151.971337) (xy 34.090135 -151.903359)
			(xy 34.169336 -151.841711) (xy 34.253358 -151.786813) (xy 34.341626 -151.739042) (xy 34.433537 -151.698723)
			(xy 34.528465 -151.666131) (xy 34.625759 -151.64149) (xy 34.724756 -151.624967) (xy 34.824779 -151.616676)
			(xy 34.874962 -151.616156) (xy 34.922624 -151.616643) (xy 35.017654 -151.624127) (xy 35.111803 -151.639042)
			(xy 35.204493 -151.661299) (xy 35.29515 -151.690758) (xy 35.383217 -151.727239) (xy 35.468151 -151.770517)
			(xy 35.549427 -151.820325) (xy 35.626545 -151.876355) (xy 35.69903 -151.938264) (xy 35.766434 -152.005668)
			(xy 35.797744 -152.041606) (xy 35.80534 -152.049603) (xy 35.825339 -152.058836) (xy 35.836352 -152.059386)
			(xy 35.913568 -152.059386) (xy 35.924585 -152.058835) (xy 35.944602 -152.049625) (xy 35.952176 -152.041606)
			(xy 35.983506 -152.005687) (xy 36.050917 -151.938293) (xy 36.123405 -151.876393) (xy 36.200524 -151.820369)
			(xy 36.281799 -151.770564) (xy 36.366729 -151.727286) (xy 36.454792 -151.690802) (xy 36.545444 -151.661335)
			(xy 36.638128 -151.639068) (xy 36.732272 -151.624138) (xy 36.827298 -151.616636) (xy 36.874958 -151.616156)
			(xy 36.925143 -151.616679) (xy 37.02517 -151.624964) (xy 37.124172 -151.641481) (xy 37.221471 -151.666118)
			(xy 37.316403 -151.698706) (xy 37.40832 -151.739022) (xy 37.496594 -151.786792) (xy 37.580621 -151.841687)
			(xy 37.659828 -151.903335) (xy 37.733673 -151.971313) (xy 37.801652 -152.045157) (xy 37.863301 -152.124363)
			(xy 37.918198 -152.208389) (xy 37.965969 -152.296662) (xy 38.006287 -152.388578) (xy 38.038876 -152.48351)
			(xy 38.063514 -152.580809) (xy 38.080034 -152.67981) (xy 38.08832 -152.779837) (xy 38.088824 -152.830022)
			(xy 38.088387 -152.877685) (xy 38.080899 -152.972716) (xy 38.065978 -153.066867) (xy 38.043717 -153.159558)
			(xy 38.014253 -153.250216) (xy 37.977767 -153.338283) (xy 37.934484 -153.423216) (xy 37.884671 -153.504492)
			(xy 37.828636 -153.581609) (xy 37.766723 -153.654092) (xy 37.699315 -153.721495) (xy 37.663374 -153.752804)
			(xy 37.655347 -153.760372) (xy 37.646132 -153.780392) (xy 37.645594 -153.791412) (xy 37.645594 -153.868628)
			(xy 37.646118 -153.879648) (xy 37.655348 -153.899665) (xy 37.663374 -153.907236) (xy 37.699318 -153.938538)
			(xy 37.766712 -154.005952) (xy 37.828611 -154.078443) (xy 37.884634 -154.155565) (xy 37.934437 -154.236842)
			(xy 37.977713 -154.321776) (xy 38.014195 -154.409841) (xy 38.043659 -154.500496) (xy 38.065922 -154.593182)
			(xy 38.080849 -154.687329) (xy 38.088346 -154.782357) (xy 38.088824 -154.830018) (xy 38.088384 -154.877681)
			(xy 38.080896 -154.972712) (xy 38.065976 -155.066863) (xy 38.043715 -155.159553) (xy 38.014251 -155.250211)
			(xy 37.977765 -155.338278) (xy 37.934483 -155.423212) (xy 37.884671 -155.504487) (xy 37.828635 -155.581605)
			(xy 37.766723 -155.654088) (xy 37.699314 -155.721491) (xy 37.663374 -155.7528) (xy 37.655349 -155.76037)
			(xy 37.646132 -155.780389) (xy 37.645594 -155.791408) (xy 37.645594 -155.868624) (xy 37.64612 -155.879644)
			(xy 37.655348 -155.89966) (xy 37.663374 -155.907232) (xy 37.699316 -155.938536) (xy 37.76671 -156.00595)
			(xy 37.828609 -156.07844) (xy 37.884632 -156.155562) (xy 37.934436 -156.23684) (xy 37.977712 -156.321773)
			(xy 38.014194 -156.409838) (xy 38.043658 -156.500492) (xy 38.065921 -156.593179) (xy 38.080848 -156.687325)
			(xy 38.088346 -156.782353) (xy 38.088824 -156.830014) (xy 38.088381 -156.877677) (xy 38.080894 -156.972708)
			(xy 38.065974 -157.066859) (xy 38.043713 -157.159549) (xy 38.014249 -157.250207) (xy 37.977764 -157.338274)
			(xy 37.934482 -157.423207) (xy 37.88467 -157.504483) (xy 37.828635 -157.581601) (xy 37.766722 -157.654084)
			(xy 37.699314 -157.721487) (xy 37.663374 -157.752796) (xy 37.65535 -157.760367) (xy 37.646133 -157.780385)
			(xy 37.645594 -157.791404) (xy 37.645594 -157.86862) (xy 37.646123 -157.87964) (xy 37.655349 -157.899656)
			(xy 37.663374 -157.907228) (xy 37.699314 -157.938534) (xy 37.766708 -158.005947) (xy 37.828607 -158.078438)
			(xy 37.884631 -158.155559) (xy 37.934434 -158.236837) (xy 37.97771 -158.32177) (xy 38.014193 -158.409834)
			(xy 38.043657 -158.500489) (xy 38.065921 -158.593175) (xy 38.080848 -158.687322) (xy 38.088346 -158.782349)
			(xy 38.088824 -158.830006) (xy 47.585872 -158.830006) (xy 47.589977 -158.730238) (xy 47.602263 -158.631145)
			(xy 47.62265 -158.533395) (xy 47.650997 -158.437651) (xy 47.687114 -158.344559) (xy 47.730757 -158.254749)
			(xy 47.781631 -158.168828) (xy 47.839391 -158.087377) (xy 47.903647 -158.010946) (xy 47.973966 -157.940053)
			(xy 48.011588 -157.907228) (xy 48.019595 -157.899641) (xy 48.028823 -157.879635) (xy 48.029368 -157.86862)
			(xy 48.029368 -157.791404) (xy 48.028838 -157.780384) (xy 48.019614 -157.760367) (xy 48.011588 -157.752796)
			(xy 47.975656 -157.721488) (xy 47.908285 -157.654066) (xy 47.846409 -157.581568) (xy 47.790409 -157.504442)
			(xy 47.74063 -157.423161) (xy 47.697378 -157.338227) (xy 47.660919 -157.250163) (xy 47.631479 -157.159511)
			(xy 47.609239 -157.06683) (xy 47.594335 -156.972689) (xy 47.586859 -156.87767) (xy 47.586392 -156.830014)
			(xy 47.586965 -156.779838) (xy 47.59525 -156.679827) (xy 47.611764 -156.580842) (xy 47.636395 -156.483559)
			(xy 47.668973 -156.388642) (xy 47.709278 -156.296738) (xy 47.757033 -156.208477) (xy 47.811913 -156.124459)
			(xy 47.873542 -156.04526) (xy 47.9415 -155.97142) (xy 48.015323 -155.903443) (xy 48.094507 -155.841793)
			(xy 48.17851 -155.786892) (xy 48.26676 -155.739114) (xy 48.358653 -155.698786) (xy 48.453562 -155.666183)
			(xy 48.550839 -155.641528) (xy 48.64982 -155.624989) (xy 48.749828 -155.616678) (xy 48.800004 -155.616148)
			(xy 48.847666 -155.616608) (xy 48.942697 -155.624094) (xy 49.036847 -155.639013) (xy 49.129537 -155.661272)
			(xy 49.220195 -155.690735) (xy 49.308261 -155.727219) (xy 49.393195 -155.770499) (xy 49.474471 -155.820309)
			(xy 49.551588 -155.876342) (xy 49.624073 -155.938253) (xy 49.691476 -156.005659) (xy 49.722786 -156.041598)
			(xy 49.730366 -156.049613) (xy 49.750377 -156.058836) (xy 49.761394 -156.059378) (xy 49.83861 -156.059378)
			(xy 49.849631 -156.058852) (xy 49.869647 -156.049625) (xy 49.877218 -156.041598) (xy 49.908523 -156.005656)
			(xy 49.975937 -155.938264) (xy 50.048428 -155.876365) (xy 50.12555 -155.820342) (xy 50.206827 -155.770539)
			(xy 50.29176 -155.727263) (xy 50.379825 -155.690781) (xy 50.470479 -155.661317) (xy 50.563165 -155.639053)
			(xy 50.657312 -155.624125) (xy 50.752339 -155.616627) (xy 50.8 -155.616148) (xy 50.850166 -155.616706)
			(xy 50.950156 -155.62499) (xy 51.04912 -155.641502) (xy 51.146384 -155.666128) (xy 51.241281 -155.698701)
			(xy 51.333166 -155.738998) (xy 51.421409 -155.786744) (xy 51.505409 -155.841614) (xy 51.584592 -155.903231)
			(xy 51.658416 -155.971176) (xy 51.726379 -156.044984) (xy 51.788016 -156.124152) (xy 51.842905 -156.208138)
			(xy 51.890673 -156.29637) (xy 51.930992 -156.388245) (xy 51.963588 -156.483134) (xy 51.988238 -156.580392)
			(xy 52.004774 -156.679352) (xy 52.013082 -156.77934) (xy 52.013612 -156.829506) (xy 52.013612 -156.830014)
			(xy 52.013125 -156.87767) (xy 52.005656 -156.972689) (xy 51.990757 -157.06683) (xy 51.968521 -157.159512)
			(xy 51.939083 -157.250164) (xy 51.902626 -157.338228) (xy 51.859375 -157.423162) (xy 51.809594 -157.504441)
			(xy 51.753592 -157.581566) (xy 51.691714 -157.65406) (xy 51.62434 -157.721478) (xy 51.588416 -157.752796)
			(xy 51.580399 -157.760374) (xy 51.571177 -157.780386) (xy 51.570636 -157.791404) (xy 51.570636 -157.86862)
			(xy 51.571152 -157.879642) (xy 51.580386 -157.899659) (xy 51.588416 -157.907228) (xy 51.626049 -157.940041)
			(xy 51.696367 -158.010936) (xy 51.760624 -158.087368) (xy 51.818385 -158.16882) (xy 51.869259 -158.254742)
			(xy 51.912903 -158.344553) (xy 51.94902 -158.437646) (xy 51.977368 -158.533392) (xy 51.997754 -158.631142)
			(xy 52.010041 -158.730237) (xy 52.014146 -158.830007) (xy 52.01004 -158.929776) (xy 51.997752 -159.028871)
			(xy 51.977365 -159.126621) (xy 51.949016 -159.222366) (xy 51.912897 -159.315459) (xy 51.869253 -159.405269)
			(xy 51.818378 -159.491191) (xy 51.760616 -159.572642) (xy 51.696359 -159.649074) (xy 51.626039 -159.719967)
			(xy 51.588416 -159.752792) (xy 51.580401 -159.760372) (xy 51.571178 -159.780383) (xy 51.570636 -159.7914)
			(xy 51.570636 -159.868616) (xy 51.571154 -159.879638) (xy 51.580386 -159.899655) (xy 51.588416 -159.907224)
			(xy 51.624359 -159.93852) (xy 51.691729 -160.005944) (xy 51.753604 -160.078442) (xy 51.809604 -160.15557)
			(xy 51.859382 -160.236852) (xy 51.902633 -160.321787) (xy 51.939091 -160.409853) (xy 51.96853 -160.500506)
			(xy 51.990769 -160.593188) (xy 52.005671 -160.687329) (xy 52.013145 -160.782349) (xy 52.013612 -160.830006)
			(xy 52.013509 -160.852379) (xy 52.011856 -160.897094) (xy 52.01031 -160.919414) (xy 52.01031 -160.919668)
			(xy 52.010063 -160.928551) (xy 52.014939 -160.945628) (xy 52.025303 -160.960049) (xy 52.032408 -160.965388)
			(xy 52.10556 -161.014664) (xy 52.113141 -161.019381) (xy 52.130424 -161.023806) (xy 52.148176 -161.022038)
			(xy 52.15636 -161.018474) (xy 52.156614 -161.01822) (xy 52.206696 -160.994237) (xy 52.309828 -160.953049)
			(xy 52.415788 -160.919811) (xy 52.523967 -160.894713) (xy 52.633739 -160.877899) (xy 52.74447 -160.869468)
			(xy 52.855522 -160.869468) (xy 52.966253 -160.877899) (xy 53.076025 -160.894713) (xy 53.184204 -160.919811)
			(xy 53.290164 -160.953049) (xy 53.393296 -160.994237) (xy 53.443378 -161.01822) (xy 53.443632 -161.018474)
			(xy 53.451831 -161.022014) (xy 53.469582 -161.023818) (xy 53.486874 -161.019416) (xy 53.494432 -161.014664)
			(xy 53.567584 -160.965388) (xy 53.574788 -160.960147) (xy 53.585215 -160.945714) (xy 53.590029 -160.928571)
			(xy 53.589682 -160.919668) (xy 53.589682 -160.919414) (xy 53.588137 -160.897094) (xy 53.586483 -160.852379)
			(xy 53.58638 -160.830006) (xy 53.58685 -160.782349) (xy 53.594318 -160.687329) (xy 53.609216 -160.593187)
			(xy 53.631453 -160.500504) (xy 53.660891 -160.409851) (xy 53.69735 -160.321786) (xy 53.740604 -160.236853)
			(xy 53.790387 -160.155574) (xy 53.846391 -160.07845) (xy 53.908273 -160.005957) (xy 53.975651 -159.938541)
			(xy 54.011576 -159.907224) (xy 54.019598 -159.899652) (xy 54.028814 -159.879634) (xy 54.029356 -159.868616)
			(xy 54.029356 -159.7914) (xy 54.028832 -159.780379) (xy 54.019604 -159.760362) (xy 54.011576 -159.752792)
			(xy 53.973961 -159.719958) (xy 53.903637 -159.649067) (xy 53.839375 -159.572639) (xy 53.78161 -159.491189)
			(xy 53.730732 -159.405269) (xy 53.687085 -159.315459) (xy 53.650964 -159.222367) (xy 53.622613 -159.126622)
			(xy 53.602224 -159.028872) (xy 53.589935 -158.929776) (xy 53.585829 -158.830006) (xy 53.589934 -158.730237)
			(xy 53.602222 -158.631141) (xy 53.62261 -158.533391) (xy 53.650959 -158.437645) (xy 53.68708 -158.344553)
			(xy 53.730726 -158.254743) (xy 53.781603 -158.168822) (xy 53.839368 -158.087371) (xy 53.903628 -158.010942)
			(xy 53.973951 -157.940051) (xy 54.011576 -157.907228) (xy 54.019596 -157.899654) (xy 54.028813 -157.879638)
			(xy 54.029356 -157.86862) (xy 54.029356 -157.791404) (xy 54.02883 -157.780383) (xy 54.019604 -157.760366)
			(xy 54.011576 -157.752796) (xy 53.975641 -157.721491) (xy 53.908271 -157.654068) (xy 53.846396 -157.58157)
			(xy 53.790396 -157.504443) (xy 53.740617 -157.423162) (xy 53.697365 -157.338228) (xy 53.660907 -157.250164)
			(xy 53.631467 -157.159512) (xy 53.609227 -157.06683) (xy 53.594323 -156.97269) (xy 53.586847 -156.87767)
			(xy 53.58638 -156.830014) (xy 53.586866 -156.779835) (xy 53.595151 -156.67982) (xy 53.611667 -156.580831)
			(xy 53.636299 -156.483544) (xy 53.668881 -156.388622) (xy 53.709189 -156.296715) (xy 53.756949 -156.208451)
			(xy 53.811833 -156.124431) (xy 53.873468 -156.04523) (xy 53.941431 -155.971389) (xy 54.01526 -155.903411)
			(xy 54.09445 -155.841762) (xy 54.17846 -155.786862) (xy 54.266716 -155.739087) (xy 54.358615 -155.698762)
			(xy 54.453531 -155.666163) (xy 54.550814 -155.641512) (xy 54.6498 -155.624979) (xy 54.749813 -155.616675)
			(xy 54.799992 -155.616148) (xy 54.847654 -155.616616) (xy 54.942685 -155.624102) (xy 55.036835 -155.63902)
			(xy 55.129524 -155.661278) (xy 55.220182 -155.69074) (xy 55.308249 -155.727223) (xy 55.393182 -155.770502)
			(xy 55.474458 -155.820312) (xy 55.551576 -155.876344) (xy 55.62406 -155.938254) (xy 55.691464 -156.005659)
			(xy 55.722774 -156.041598) (xy 55.730359 -156.049607) (xy 55.750366 -156.058833) (xy 55.761382 -156.059378)
			(xy 55.838598 -156.059378) (xy 55.849618 -156.058846) (xy 55.869635 -156.049623) (xy 55.877206 -156.041598)
			(xy 55.908518 -156.005662) (xy 55.975931 -155.93827) (xy 56.048421 -155.876371) (xy 56.125542 -155.820347)
			(xy 56.206819 -155.770544) (xy 56.291751 -155.727267) (xy 56.379815 -155.690784) (xy 56.470469 -155.66132)
			(xy 56.563154 -155.639055) (xy 56.6573 -155.624127) (xy 56.752327 -155.616627) (xy 56.799988 -155.616148)
			(xy 56.850154 -155.616717) (xy 56.950144 -155.625) (xy 57.049108 -155.641511) (xy 57.146371 -155.666137)
			(xy 57.241269 -155.698709) (xy 57.333153 -155.739005) (xy 57.421396 -155.786751) (xy 57.505396 -155.841619)
			(xy 57.584579 -155.903236) (xy 57.658404 -155.97118) (xy 57.726366 -156.044988) (xy 57.788003 -156.124155)
			(xy 57.842893 -156.208141) (xy 57.89066 -156.296372) (xy 57.93098 -156.388246) (xy 57.963576 -156.483136)
			(xy 57.988226 -156.580393) (xy 58.004762 -156.679353) (xy 58.01307 -156.77934) (xy 58.0136 -156.829506)
			(xy 58.0136 -156.830014) (xy 58.013117 -156.87767) (xy 58.005648 -156.97269) (xy 57.990749 -157.06683)
			(xy 57.968513 -157.159512) (xy 57.939075 -157.250165) (xy 57.902617 -157.338229) (xy 57.859365 -157.423163)
			(xy 57.809584 -157.504442) (xy 57.753582 -157.581567) (xy 57.691703 -157.654061) (xy 57.624328 -157.721478)
			(xy 57.588404 -157.752796) (xy 57.580385 -157.760372) (xy 57.571164 -157.780386) (xy 57.570624 -157.791404)
			(xy 57.570624 -157.86862) (xy 57.571143 -157.879641) (xy 57.580375 -157.899658) (xy 57.588404 -157.907228)
			(xy 57.626037 -157.940041) (xy 57.696356 -158.010935) (xy 57.760614 -158.087367) (xy 57.818375 -158.168819)
			(xy 57.86925 -158.254741) (xy 57.912894 -158.344552) (xy 57.949012 -158.437645) (xy 57.97736 -158.533391)
			(xy 57.997746 -158.631142) (xy 58.010033 -158.730237) (xy 58.014138 -158.830006) (xy 61.785988 -158.830006)
			(xy 61.790092 -158.730238) (xy 61.802379 -158.631144) (xy 61.822766 -158.533394) (xy 61.851114 -158.437649)
			(xy 61.887232 -158.344557) (xy 61.930876 -158.254747) (xy 61.981751 -158.168826) (xy 62.039512 -158.087375)
			(xy 62.10377 -158.010945) (xy 62.174089 -157.940052) (xy 62.211712 -157.907228) (xy 62.219722 -157.899645)
			(xy 62.228947 -157.879636) (xy 62.229492 -157.86862) (xy 62.229492 -157.791404) (xy 62.228954 -157.780385)
			(xy 62.219735 -157.760368) (xy 62.211712 -157.752796) (xy 62.175785 -157.721482) (xy 62.108414 -157.654061)
			(xy 62.046537 -157.581565) (xy 61.990536 -157.504439) (xy 61.940756 -157.423159) (xy 61.897503 -157.338226)
			(xy 61.861045 -157.250162) (xy 61.831604 -157.15951) (xy 61.809363 -157.066829) (xy 61.794459 -156.972689)
			(xy 61.786983 -156.87767) (xy 61.786516 -156.830014) (xy 61.787065 -156.779837) (xy 61.79535 -156.679825)
			(xy 61.811865 -156.580839) (xy 61.836496 -156.483555) (xy 61.869075 -156.388636) (xy 61.909381 -156.296732)
			(xy 61.957137 -156.20847) (xy 62.012018 -156.124451) (xy 62.073649 -156.045252) (xy 62.141609 -155.971411)
			(xy 62.215433 -155.903434) (xy 62.294619 -155.841785) (xy 62.378624 -155.786884) (xy 62.466875 -155.739107)
			(xy 62.55877 -155.698779) (xy 62.653681 -155.666178) (xy 62.750959 -155.641524) (xy 62.849941 -155.624986)
			(xy 62.949951 -155.616677) (xy 63.000128 -155.616148) (xy 63.047791 -155.61659) (xy 63.142822 -155.624079)
			(xy 63.236972 -155.639) (xy 63.329662 -155.661261) (xy 63.42032 -155.690725) (xy 63.508387 -155.72721)
			(xy 63.59332 -155.770492) (xy 63.674596 -155.820304) (xy 63.751713 -155.876339) (xy 63.824197 -155.938251)
			(xy 63.891601 -156.005658) (xy 63.92291 -156.041598) (xy 63.93048 -156.049623) (xy 63.950499 -156.058841)
			(xy 63.961518 -156.059378) (xy 64.038734 -156.059378) (xy 64.049756 -156.058866) (xy 64.069773 -156.049629)
			(xy 64.077342 -156.041598) (xy 64.108634 -156.005645) (xy 64.176049 -155.938253) (xy 64.248542 -155.876355)
			(xy 64.325665 -155.820332) (xy 64.406944 -155.77053) (xy 64.491878 -155.727255) (xy 64.579944 -155.690774)
			(xy 64.6706 -155.661311) (xy 64.763287 -155.639048) (xy 64.857434 -155.624123) (xy 64.952462 -155.616626)
			(xy 65.000124 -155.616148) (xy 65.050291 -155.616683) (xy 65.150281 -155.624969) (xy 65.249246 -155.641482)
			(xy 65.346509 -155.666111) (xy 65.441407 -155.698685) (xy 65.533292 -155.738984) (xy 65.621535 -155.786732)
			(xy 65.705535 -155.841602) (xy 65.784717 -155.903221) (xy 65.858542 -155.971167) (xy 65.926504 -156.044977)
			(xy 65.988141 -156.124145) (xy 66.04303 -156.208133) (xy 66.090797 -156.296366) (xy 66.131116 -156.388241)
			(xy 66.163712 -156.483132) (xy 66.188362 -156.58039) (xy 66.204898 -156.679351) (xy 66.213206 -156.77934)
			(xy 66.213736 -156.829506) (xy 66.213736 -156.830014) (xy 66.213275 -156.877671) (xy 66.205806 -156.972691)
			(xy 66.190906 -157.066833) (xy 66.168668 -157.159516) (xy 66.139228 -157.250169) (xy 66.102769 -157.338234)
			(xy 66.059514 -157.423167) (xy 66.009731 -157.504446) (xy 65.953726 -157.58157) (xy 65.891843 -157.654063)
			(xy 65.824465 -157.721479) (xy 65.78854 -157.752796) (xy 65.780512 -157.760363) (xy 65.771299 -157.780384)
			(xy 65.77076 -157.791404) (xy 65.77076 -157.86862) (xy 65.771299 -157.879638) (xy 65.780519 -157.899654)
			(xy 65.78854 -157.907228) (xy 65.826175 -157.94004) (xy 65.896498 -158.010933) (xy 65.960758 -158.087363)
			(xy 66.018523 -158.168815) (xy 66.0694 -158.254736) (xy 66.113046 -158.344548) (xy 66.149166 -158.437641)
			(xy 66.177516 -158.533388) (xy 66.197904 -158.631139) (xy 66.210191 -158.730236) (xy 66.214296 -158.830006)
			(xy 67.78598 -158.830006) (xy 67.790084 -158.730238) (xy 67.802371 -158.631144) (xy 67.822758 -158.533394)
			(xy 67.851106 -158.43765) (xy 67.887223 -158.344558) (xy 67.930867 -158.254748) (xy 67.981741 -158.168827)
			(xy 68.039502 -158.087376) (xy 68.103758 -158.010946) (xy 68.174077 -157.940052) (xy 68.2117 -157.907228)
			(xy 68.219709 -157.899643) (xy 68.228935 -157.879636) (xy 68.22948 -157.86862) (xy 68.22948 -157.791404)
			(xy 68.228946 -157.780384) (xy 68.219725 -157.760368) (xy 68.2117 -157.752796) (xy 68.17577 -157.721485)
			(xy 68.108399 -157.654063) (xy 68.046523 -157.581566) (xy 67.990523 -157.50444) (xy 67.940743 -157.42316)
			(xy 67.897491 -157.338227) (xy 67.861032 -157.250163) (xy 67.831592 -157.159511) (xy 67.809351 -157.066829)
			(xy 67.794447 -156.972689) (xy 67.786971 -156.87767) (xy 67.786504 -156.830014) (xy 67.787065 -156.779837)
			(xy 67.79535 -156.679826) (xy 67.811864 -156.580841) (xy 67.836495 -156.483557) (xy 67.869074 -156.388639)
			(xy 67.90938 -156.296735) (xy 67.957135 -156.208473) (xy 68.012016 -156.124455) (xy 68.073646 -156.045256)
			(xy 68.141605 -155.971415) (xy 68.215428 -155.903438) (xy 68.294613 -155.841789) (xy 68.378617 -155.786888)
			(xy 68.466867 -155.73911) (xy 68.558761 -155.698783) (xy 68.653671 -155.66618) (xy 68.750949 -155.641526)
			(xy 68.84993 -155.624987) (xy 68.949939 -155.616678) (xy 69.000116 -155.616148) (xy 69.047779 -155.616599)
			(xy 69.142809 -155.624087) (xy 69.23696 -155.639006) (xy 69.32965 -155.661267) (xy 69.420307 -155.69073)
			(xy 69.508374 -155.727214) (xy 69.593307 -155.770496) (xy 69.674583 -155.820307) (xy 69.751701 -155.87634)
			(xy 69.824185 -155.938252) (xy 69.891588 -156.005658) (xy 69.922898 -156.041598) (xy 69.930473 -156.049618)
			(xy 69.950488 -156.058838) (xy 69.961506 -156.059378) (xy 70.038722 -156.059378) (xy 70.049743 -156.058859)
			(xy 70.06976 -156.049627) (xy 70.07733 -156.041598) (xy 70.108628 -156.005651) (xy 70.176043 -155.938258)
			(xy 70.248535 -155.87636) (xy 70.325657 -155.820337) (xy 70.406936 -155.770534) (xy 70.491869 -155.727259)
			(xy 70.579934 -155.690777) (xy 70.67059 -155.661314) (xy 70.763276 -155.639051) (xy 70.857423 -155.624124)
			(xy 70.952451 -155.616626) (xy 71.000112 -155.616148) (xy 71.050278 -155.616694) (xy 71.150268 -155.624979)
			(xy 71.249233 -155.641492) (xy 71.346496 -155.666119) (xy 71.441394 -155.698693) (xy 71.533279 -155.738991)
			(xy 71.621522 -155.786738) (xy 71.705522 -155.841608) (xy 71.784704 -155.903226) (xy 71.858529 -155.971171)
			(xy 71.926492 -156.04498) (xy 71.988128 -156.124149) (xy 72.043017 -156.208136) (xy 72.090785 -156.296368)
			(xy 72.131104 -156.388243) (xy 72.1637 -156.483133) (xy 72.18835 -156.580391) (xy 72.204886 -156.679352)
			(xy 72.213194 -156.77934) (xy 72.213724 -156.829506) (xy 72.213724 -156.830014) (xy 72.213267 -156.877671)
			(xy 72.205798 -156.972692) (xy 72.190898 -157.066833) (xy 72.16866 -157.159517) (xy 72.13922 -157.25017)
			(xy 72.10276 -157.338235) (xy 72.059505 -157.423168) (xy 72.009721 -157.504447) (xy 71.953715 -157.581571)
			(xy 71.891832 -157.654064) (xy 71.824454 -157.721479) (xy 71.788528 -157.752796) (xy 71.780497 -157.760361)
			(xy 71.771286 -157.780384) (xy 71.770748 -157.791404) (xy 71.770748 -157.86862) (xy 71.77126 -157.879642)
			(xy 71.780496 -157.89966) (xy 71.788528 -157.907228) (xy 71.826961 -157.940728) (xy 71.898668 -158.013216)
			(xy 71.964043 -158.091463) (xy 72.022625 -158.174917) (xy 72.074 -158.26299) (xy 72.096376 -158.308802)
			(xy 72.100948 -158.318454) (xy 72.11695 -158.332424) (xy 72.199246 -158.357316) (xy 72.209509 -158.35998)
			(xy 72.230544 -158.357501) (xy 72.239886 -158.35249) (xy 72.285848 -158.325685) (xy 72.380951 -158.27795)
			(xy 72.479225 -158.237137) (xy 72.580165 -158.203457) (xy 72.683255 -158.17708) (xy 72.787967 -158.158142)
			(xy 72.893765 -158.146741) (xy 73.000108 -158.142934) (xy 73.106451 -158.146741) (xy 73.212249 -158.158142)
			(xy 73.316961 -158.17708) (xy 73.420051 -158.203457) (xy 73.520991 -158.237137) (xy 73.619265 -158.27795)
			(xy 73.714368 -158.325685) (xy 73.76033 -158.35249) (xy 73.769716 -158.357372) (xy 73.790702 -158.359866)
			(xy 73.80097 -158.357316) (xy 73.883266 -158.332424) (xy 73.899268 -158.318454) (xy 73.90384 -158.308802)
			(xy 73.92622 -158.262993) (xy 73.97759 -158.174915) (xy 74.036169 -158.09146) (xy 74.101545 -158.013214)
			(xy 74.173257 -157.940731) (xy 74.211688 -157.907228) (xy 74.219695 -157.899641) (xy 74.228923 -157.879635)
			(xy 74.229468 -157.86862) (xy 74.229468 -157.791404) (xy 74.228938 -157.780384) (xy 74.219714 -157.760367)
			(xy 74.211688 -157.752796) (xy 74.175756 -157.721488) (xy 74.108385 -157.654066) (xy 74.046509 -157.581568)
			(xy 73.990509 -157.504442) (xy 73.94073 -157.423161) (xy 73.897478 -157.338227) (xy 73.861019 -157.250163)
			(xy 73.831579 -157.159511) (xy 73.809339 -157.06683) (xy 73.794435 -156.972689) (xy 73.786959 -156.87767)
			(xy 73.786492 -156.830014) (xy 73.787065 -156.779838) (xy 73.79535 -156.679827) (xy 73.811864 -156.580842)
			(xy 73.836495 -156.483559) (xy 73.869073 -156.388642) (xy 73.909378 -156.296738) (xy 73.957133 -156.208477)
			(xy 74.012013 -156.124459) (xy 74.073642 -156.04526) (xy 74.1416 -155.97142) (xy 74.215423 -155.903443)
			(xy 74.294607 -155.841793) (xy 74.37861 -155.786892) (xy 74.46686 -155.739114) (xy 74.558753 -155.698786)
			(xy 74.653662 -155.666183) (xy 74.750939 -155.641528) (xy 74.84992 -155.624989) (xy 74.949928 -155.616678)
			(xy 75.000104 -155.616148) (xy 75.047766 -155.616608) (xy 75.142797 -155.624094) (xy 75.236947 -155.639013)
			(xy 75.329637 -155.661272) (xy 75.420295 -155.690735) (xy 75.508361 -155.727219) (xy 75.593295 -155.770499)
			(xy 75.674571 -155.820309) (xy 75.751688 -155.876342) (xy 75.824173 -155.938253) (xy 75.891576 -156.005659)
			(xy 75.922886 -156.041598) (xy 75.930466 -156.049613) (xy 75.950477 -156.058836) (xy 75.961494 -156.059378)
			(xy 76.03871 -156.059378) (xy 76.049731 -156.058852) (xy 76.069747 -156.049625) (xy 76.077318 -156.041598)
			(xy 76.108623 -156.005656) (xy 76.176037 -155.938264) (xy 76.248528 -155.876365) (xy 76.32565 -155.820342)
			(xy 76.406927 -155.770539) (xy 76.49186 -155.727263) (xy 76.579925 -155.690781) (xy 76.670579 -155.661317)
			(xy 76.763265 -155.639053) (xy 76.857412 -155.624125) (xy 76.952439 -155.616627) (xy 77.0001 -155.616148)
			(xy 77.050266 -155.616706) (xy 77.150256 -155.62499) (xy 77.24922 -155.641502) (xy 77.346484 -155.666128)
			(xy 77.441381 -155.698701) (xy 77.533266 -155.738998) (xy 77.621509 -155.786744) (xy 77.705509 -155.841614)
			(xy 77.784692 -155.903231) (xy 77.858516 -155.971176) (xy 77.926479 -156.044984) (xy 77.988116 -156.124152)
			(xy 78.043005 -156.208138) (xy 78.090773 -156.29637) (xy 78.131092 -156.388245) (xy 78.163688 -156.483134)
			(xy 78.188338 -156.580392) (xy 78.204874 -156.679352) (xy 78.213182 -156.77934) (xy 78.213712 -156.829506)
			(xy 78.213712 -156.830014) (xy 78.213225 -156.87767) (xy 78.205756 -156.972689) (xy 78.190857 -157.06683)
			(xy 78.168621 -157.159512) (xy 78.139183 -157.250164) (xy 78.102726 -157.338228) (xy 78.059475 -157.423162)
			(xy 78.009694 -157.504441) (xy 77.953692 -157.581566) (xy 77.891814 -157.65406) (xy 77.82444 -157.721478)
			(xy 77.788516 -157.752796) (xy 77.780499 -157.760374) (xy 77.771277 -157.780386) (xy 77.770736 -157.791404)
			(xy 77.770736 -157.86862) (xy 77.771252 -157.879642) (xy 77.780486 -157.899659) (xy 77.788516 -157.907228)
			(xy 77.826149 -157.940041) (xy 77.896467 -158.010936) (xy 77.960724 -158.087368) (xy 78.018485 -158.16882)
			(xy 78.069359 -158.254742) (xy 78.113003 -158.344553) (xy 78.14912 -158.437646) (xy 78.177468 -158.533392)
			(xy 78.197854 -158.631142) (xy 78.210141 -158.730237) (xy 78.214246 -158.830007) (xy 78.21014 -158.929776)
			(xy 78.197852 -159.028871) (xy 78.177465 -159.126621) (xy 78.149116 -159.222366) (xy 78.112997 -159.315459)
			(xy 78.069353 -159.405269) (xy 78.018478 -159.491191) (xy 77.960716 -159.572642) (xy 77.896459 -159.649074)
			(xy 77.826139 -159.719967) (xy 77.788516 -159.752792) (xy 77.780501 -159.760372) (xy 77.771278 -159.780383)
			(xy 77.770736 -159.7914) (xy 77.770736 -159.868616) (xy 77.771254 -159.879638) (xy 77.780486 -159.899655)
			(xy 77.788516 -159.907224) (xy 77.824459 -159.93852) (xy 77.891829 -160.005944) (xy 77.953704 -160.078442)
			(xy 78.009704 -160.15557) (xy 78.059482 -160.236852) (xy 78.102733 -160.321787) (xy 78.139191 -160.409853)
			(xy 78.16863 -160.500506) (xy 78.190869 -160.593188) (xy 78.205771 -160.687329) (xy 78.213245 -160.782349)
			(xy 78.213712 -160.830006) (xy 78.213154 -160.880183) (xy 78.204867 -160.980193) (xy 78.188352 -161.079178)
			(xy 78.16372 -161.176461) (xy 78.13114 -161.271379) (xy 78.090834 -161.363282) (xy 78.043078 -161.451544)
			(xy 77.988197 -161.535561) (xy 77.926567 -161.61476) (xy 77.858608 -161.6886) (xy 77.784785 -161.756577)
			(xy 77.7056 -161.818226) (xy 77.621596 -161.873127) (xy 77.533346 -161.920905) (xy 77.441453 -161.961233)
			(xy 77.346543 -161.993836) (xy 77.249266 -162.018492) (xy 77.150285 -162.035031) (xy 77.050276 -162.043342)
			(xy 77.0001 -162.043872) (xy 76.952438 -162.043402) (xy 76.857408 -162.035916) (xy 76.763258 -162.020998)
			(xy 76.670569 -161.998739) (xy 76.579911 -161.969278) (xy 76.491844 -161.932795) (xy 76.406911 -161.889516)
			(xy 76.325635 -161.839706) (xy 76.248517 -161.783675) (xy 76.176032 -161.721766) (xy 76.108628 -161.654361)
			(xy 76.077318 -161.618422) (xy 76.069749 -161.610397) (xy 76.049729 -161.601183) (xy 76.03871 -161.600642)
			(xy 75.961494 -161.600642) (xy 75.950473 -161.601163) (xy 75.930456 -161.610393) (xy 75.922886 -161.618422)
			(xy 75.891584 -161.654366) (xy 75.824169 -161.721758) (xy 75.751678 -161.783656) (xy 75.674555 -161.839679)
			(xy 75.593277 -161.889481) (xy 75.508344 -161.932757) (xy 75.420279 -161.969239) (xy 75.329625 -161.998703)
			(xy 75.236939 -162.020967) (xy 75.142792 -162.035894) (xy 75.047765 -162.043393) (xy 75.000104 -162.043872)
			(xy 74.950123 -162.043374) (xy 74.8505 -162.035138) (xy 74.751892 -162.018736) (xy 74.654967 -161.994281)
			(xy 74.560381 -161.961938) (xy 74.468775 -161.921925) (xy 74.380771 -161.874515) (xy 74.296963 -161.820029)
			(xy 74.21792 -161.758834) (xy 74.144177 -161.691347) (xy 74.076234 -161.618024) (xy 74.014551 -161.539362)
			(xy 73.959545 -161.455893) (xy 73.911591 -161.368184) (xy 73.871011 -161.276829) (xy 73.838082 -161.182445)
			(xy 73.813027 -161.085673) (xy 73.804018 -161.036508) (xy 73.801427 -161.024877) (xy 73.787397 -161.005661)
			(xy 73.777094 -160.999678) (xy 73.693528 -160.957514) (xy 73.669906 -160.95726) (xy 73.658984 -160.962594)
			(xy 73.611709 -160.985464) (xy 73.514509 -161.025256) (xy 73.414743 -161.058087) (xy 73.312908 -161.083794)
			(xy 73.209512 -161.102248) (xy 73.105072 -161.113358) (xy 73.000108 -161.117067) (xy 72.895144 -161.113358)
			(xy 72.790704 -161.102248) (xy 72.687308 -161.083794) (xy 72.585473 -161.058087) (xy 72.485707 -161.025256)
			(xy 72.388507 -160.985464) (xy 72.341232 -160.962594) (xy 72.330331 -160.957905) (xy 72.306624 -160.958056)
			(xy 72.295766 -160.962848) (xy 72.223122 -160.999678) (xy 72.212846 -161.005698) (xy 72.198797 -161.024888)
			(xy 72.196198 -161.036508) (xy 72.187209 -161.085679) (xy 72.162169 -161.18246) (xy 72.129253 -161.276853)
			(xy 72.088683 -161.368219) (xy 72.040735 -161.455937) (xy 71.985733 -161.539413) (xy 71.924051 -161.618083)
			(xy 71.856106 -161.691411) (xy 71.78236 -161.758901) (xy 71.703311 -161.820096) (xy 71.619496 -161.874581)
			(xy 71.531484 -161.921986) (xy 71.439869 -161.961991) (xy 71.345275 -161.994323) (xy 71.248341 -162.018765)
			(xy 71.149725 -162.035149) (xy 71.050096 -162.043365) (xy 71.000112 -162.043872) (xy 70.95245 -162.043394)
			(xy 70.85742 -162.035909) (xy 70.76327 -162.020991) (xy 70.670581 -161.998734) (xy 70.579924 -161.969273)
			(xy 70.491857 -161.932791) (xy 70.406924 -161.889512) (xy 70.325648 -161.839704) (xy 70.248529 -161.783673)
			(xy 70.176045 -161.721764) (xy 70.10864 -161.65436) (xy 70.07733 -161.618422) (xy 70.069756 -161.610402)
			(xy 70.04974 -161.601185) (xy 70.038722 -161.600642) (xy 69.961506 -161.600642) (xy 69.950486 -161.60117)
			(xy 69.930468 -161.610395) (xy 69.922898 -161.618422) (xy 69.891589 -161.65436) (xy 69.824175 -161.721752)
			(xy 69.751684 -161.78365) (xy 69.674563 -161.839674) (xy 69.593286 -161.889477) (xy 69.508353 -161.932753)
			(xy 69.420289 -161.969235) (xy 69.329635 -161.9987) (xy 69.23695 -162.020965) (xy 69.142804 -162.035893)
			(xy 69.047777 -162.043393) (xy 69.000116 -162.043872) (xy 68.949948 -162.043379) (xy 68.849954 -162.035095)
			(xy 68.750986 -162.018583) (xy 68.653719 -161.993956) (xy 68.558818 -161.961382) (xy 68.466931 -161.921082)
			(xy 68.378685 -161.873333) (xy 68.294683 -161.818461) (xy 68.215498 -161.756839) (xy 68.141672 -161.68889)
			(xy 68.073709 -161.615077) (xy 68.012073 -161.535905) (xy 67.957185 -161.451913) (xy 67.909419 -161.363676)
			(xy 67.869102 -161.271796) (xy 67.836509 -161.176901) (xy 67.811864 -161.079639) (xy 67.795333 -160.980674)
			(xy 67.787031 -160.880682) (xy 67.786504 -160.830514) (xy 67.786504 -160.830006) (xy 67.787 -160.78235)
			(xy 67.794468 -160.687331) (xy 67.809365 -160.593191) (xy 67.8316 -160.500509) (xy 67.861037 -160.409856)
			(xy 67.897493 -160.321792) (xy 67.940744 -160.236858) (xy 67.990524 -160.155579) (xy 68.046525 -160.078454)
			(xy 68.108403 -160.00596) (xy 68.175777 -159.938542) (xy 68.2117 -159.907224) (xy 68.21971 -159.89964)
			(xy 68.228936 -159.879632) (xy 68.22948 -159.868616) (xy 68.22948 -159.7914) (xy 68.228948 -159.78038)
			(xy 68.219725 -159.760363) (xy 68.2117 -159.752792) (xy 68.174087 -159.719957) (xy 68.103767 -159.649064)
			(xy 68.039509 -159.572634) (xy 67.981748 -159.491184) (xy 67.930873 -159.405263) (xy 67.887228 -159.315454)
			(xy 67.85111 -159.222362) (xy 67.822761 -159.126618) (xy 67.802374 -159.028869) (xy 67.790086 -158.929775)
			(xy 67.78598 -158.830006) (xy 66.214296 -158.830006) (xy 66.21019 -158.929777) (xy 66.197902 -159.028873)
			(xy 66.177513 -159.126625) (xy 66.149162 -159.222371) (xy 66.113041 -159.315464) (xy 66.069394 -159.405275)
			(xy 66.018516 -159.491196) (xy 65.96075 -159.572647) (xy 65.896489 -159.649077) (xy 65.826165 -159.719969)
			(xy 65.78854 -159.752792) (xy 65.780513 -159.76036) (xy 65.771299 -159.780381) (xy 65.77076 -159.7914)
			(xy 65.77076 -159.868616) (xy 65.771302 -159.879634) (xy 65.78052 -159.89965) (xy 65.78854 -159.907224)
			(xy 65.824488 -159.938515) (xy 65.891857 -160.005939) (xy 65.953732 -160.078439) (xy 66.009731 -160.155567)
			(xy 66.059509 -160.23685) (xy 66.102759 -160.321786) (xy 66.139216 -160.409851) (xy 66.168654 -160.500505)
			(xy 66.190893 -160.593188) (xy 66.205795 -160.687329) (xy 66.213269 -160.782349) (xy 66.213736 -160.830006)
			(xy 66.213254 -160.880185) (xy 66.204967 -160.980199) (xy 66.18845 -161.079188) (xy 66.163816 -161.176475)
			(xy 66.131233 -161.271396) (xy 66.090925 -161.363302) (xy 66.043165 -161.451566) (xy 65.98828 -161.535585)
			(xy 65.926645 -161.614786) (xy 65.858681 -161.688627) (xy 65.784852 -161.756604) (xy 65.705663 -161.818253)
			(xy 65.621653 -161.873153) (xy 65.533398 -161.920929) (xy 65.441499 -161.961254) (xy 65.346584 -161.993854)
			(xy 65.249301 -162.018505) (xy 65.150316 -162.03504) (xy 65.050303 -162.043345) (xy 65.000124 -162.043872)
			(xy 64.952462 -162.043385) (xy 64.857433 -162.035901) (xy 64.763283 -162.020984) (xy 64.670594 -161.998728)
			(xy 64.579937 -161.969268) (xy 64.49187 -161.932787) (xy 64.406937 -161.889509) (xy 64.32566 -161.839701)
			(xy 64.248542 -161.783671) (xy 64.176057 -161.721763) (xy 64.108652 -161.65436) (xy 64.077342 -161.618422)
			(xy 64.069763 -161.610408) (xy 64.049751 -161.601187) (xy 64.038734 -161.600642) (xy 63.961518 -161.600642)
			(xy 63.950498 -161.601177) (xy 63.930481 -161.610397) (xy 63.92291 -161.618422) (xy 63.891594 -161.654354)
			(xy 63.824181 -161.721746) (xy 63.751691 -161.783645) (xy 63.674571 -161.839668) (xy 63.593294 -161.889472)
			(xy 63.508362 -161.932748) (xy 63.420299 -161.969232) (xy 63.329645 -161.998697) (xy 63.23696 -162.020963)
			(xy 63.142815 -162.035892) (xy 63.047789 -162.043392) (xy 63.000128 -162.043872) (xy 62.94996 -162.043367)
			(xy 62.849967 -162.035085) (xy 62.750999 -162.018574) (xy 62.653732 -161.993947) (xy 62.558831 -161.961374)
			(xy 62.466944 -161.921075) (xy 62.378698 -161.873327) (xy 62.294695 -161.818455) (xy 62.215511 -161.756835)
			(xy 62.141685 -161.688886) (xy 62.073722 -161.615074) (xy 62.012086 -161.535902) (xy 61.957197 -161.45191)
			(xy 61.909431 -161.363674) (xy 61.869114 -161.271795) (xy 61.836522 -161.1769) (xy 61.811876 -161.079638)
			(xy 61.795345 -160.980673) (xy 61.787043 -160.880682) (xy 61.786516 -160.830514) (xy 61.786516 -160.830006)
			(xy 61.787008 -160.78235) (xy 61.794476 -160.687331) (xy 61.809373 -160.59319) (xy 61.831609 -160.500508)
			(xy 61.861045 -160.409855) (xy 61.897502 -160.321791) (xy 61.940753 -160.236858) (xy 61.990533 -160.155578)
			(xy 62.046535 -160.078454) (xy 62.108414 -160.005959) (xy 62.175788 -159.938542) (xy 62.211712 -159.907224)
			(xy 62.219724 -159.899642) (xy 62.228948 -159.879632) (xy 62.229492 -159.868616) (xy 62.229492 -159.7914)
			(xy 62.228956 -159.780381) (xy 62.219736 -159.760364) (xy 62.211712 -159.752792) (xy 62.174098 -159.719957)
			(xy 62.103778 -159.649065) (xy 62.03952 -159.572635) (xy 61.981758 -159.491185) (xy 61.930882 -159.405264)
			(xy 61.887237 -159.315455) (xy 61.851118 -159.222363) (xy 61.822769 -159.126619) (xy 61.802382 -159.028869)
			(xy 61.790093 -158.929775) (xy 61.785988 -158.830006) (xy 58.014138 -158.830006) (xy 58.014138 -158.830007)
			(xy 58.010032 -158.929776) (xy 57.997744 -159.028871) (xy 57.977357 -159.126622) (xy 57.949007 -159.222367)
			(xy 57.912888 -159.315459) (xy 57.869244 -159.40527) (xy 57.818368 -159.491192) (xy 57.760606 -159.572643)
			(xy 57.696348 -159.649074) (xy 57.626027 -159.719968) (xy 57.588404 -159.752792) (xy 57.580387 -159.76037)
			(xy 57.571165 -159.780382) (xy 57.570624 -159.7914) (xy 57.570624 -159.868616) (xy 57.571146 -159.879637)
			(xy 57.580376 -159.899654) (xy 57.588404 -159.907224) (xy 57.624344 -159.938523) (xy 57.691715 -160.005946)
			(xy 57.753591 -160.078444) (xy 57.80959 -160.155572) (xy 57.859369 -160.236853) (xy 57.902621 -160.321788)
			(xy 57.939078 -160.409853) (xy 57.968517 -160.500506) (xy 57.990757 -160.593189) (xy 58.005659 -160.68733)
			(xy 58.013133 -160.782349) (xy 58.0136 -160.830006) (xy 58.013054 -160.880183) (xy 58.004767 -160.980194)
			(xy 57.988252 -161.07918) (xy 57.963619 -161.176464) (xy 57.931039 -161.271382) (xy 57.890733 -161.363285)
			(xy 57.842976 -161.451547) (xy 57.788095 -161.535565) (xy 57.726464 -161.614764) (xy 57.658504 -161.688604)
			(xy 57.584679 -161.756581) (xy 57.505494 -161.818231) (xy 57.42149 -161.873131) (xy 57.333239 -161.920909)
			(xy 57.241344 -161.961236) (xy 57.146434 -161.993839) (xy 57.049156 -162.018494) (xy 56.950174 -162.035032)
			(xy 56.850165 -162.043342) (xy 56.799988 -162.043872) (xy 56.752326 -162.043411) (xy 56.657295 -162.035924)
			(xy 56.563145 -162.021005) (xy 56.470456 -161.998745) (xy 56.379798 -161.969283) (xy 56.291731 -161.932799)
			(xy 56.206798 -161.889519) (xy 56.125522 -161.839709) (xy 56.048404 -161.783676) (xy 55.97592 -161.721767)
			(xy 55.908516 -161.654361) (xy 55.877206 -161.618422) (xy 55.869641 -161.610391) (xy 55.849618 -161.60118)
			(xy 55.838598 -161.600642) (xy 55.761382 -161.600642) (xy 55.75036 -161.601157) (xy 55.730343 -161.610391)
			(xy 55.722774 -161.618422) (xy 55.691478 -161.654372) (xy 55.624063 -161.721763) (xy 55.551571 -161.783661)
			(xy 55.474448 -161.839684) (xy 55.393169 -161.889486) (xy 55.308235 -161.932761) (xy 55.22017 -161.969242)
			(xy 55.129515 -161.998706) (xy 55.036828 -162.020969) (xy 54.942681 -162.035896) (xy 54.847653 -162.043394)
			(xy 54.799992 -162.043872) (xy 54.745712 -162.043259) (xy 54.637587 -162.033538) (xy 54.530764 -162.014191)
			(xy 54.426097 -161.985373) (xy 54.37505 -161.96691) (xy 54.362096 -161.962084) (xy 54.33568 -161.966656)
			(xy 54.246526 -162.040316) (xy 54.237128 -162.06597) (xy 54.239414 -162.079432) (xy 54.248227 -162.132911)
			(xy 54.25886 -162.240785) (xy 54.26147 -162.34915) (xy 54.256041 -162.457411) (xy 54.242604 -162.564971)
			(xy 54.221232 -162.67124) (xy 54.192043 -162.775633) (xy 54.155197 -162.877575) (xy 54.110898 -162.976507)
			(xy 54.059389 -163.071883) (xy 54.000952 -163.163179) (xy 53.935911 -163.249894) (xy 53.864621 -163.331549)
			(xy 53.787476 -163.407697) (xy 53.7049 -163.477918) (xy 53.617346 -163.541825) (xy 53.525297 -163.599069)
			(xy 53.429259 -163.649333) (xy 53.329759 -163.692341) (xy 53.227346 -163.727856) (xy 53.122582 -163.755684)
			(xy 53.016044 -163.775672) (xy 52.908318 -163.787708) (xy 52.799996 -163.791727) (xy 52.691674 -163.787708)
			(xy 52.583948 -163.775672) (xy 52.47741 -163.755684) (xy 52.372646 -163.727856) (xy 52.270233 -163.692341)
			(xy 52.170733 -163.649333) (xy 52.074695 -163.599069) (xy 51.982646 -163.541825) (xy 51.895092 -163.477918)
			(xy 51.812516 -163.407697) (xy 51.735371 -163.331549) (xy 51.664081 -163.249894) (xy 51.59904 -163.163179)
			(xy 51.540603 -163.071883) (xy 51.489094 -162.976507) (xy 51.444795 -162.877575) (xy 51.407949 -162.775633)
			(xy 51.37876 -162.67124) (xy 51.357388 -162.564971) (xy 51.343951 -162.457411) (xy 51.338522 -162.34915)
			(xy 51.341132 -162.240785) (xy 51.351765 -162.132911) (xy 51.360578 -162.079432) (xy 51.362864 -162.06597)
			(xy 51.353466 -162.040316) (xy 51.264312 -161.966656) (xy 51.237896 -161.962084) (xy 51.224942 -161.96691)
			(xy 51.173891 -161.985361) (xy 51.069222 -162.01416) (xy 50.962401 -162.033507) (xy 50.854279 -162.043245)
			(xy 50.8 -162.043872) (xy 50.752338 -162.043402) (xy 50.657308 -162.035916) (xy 50.563158 -162.020998)
			(xy 50.470469 -161.998739) (xy 50.379811 -161.969278) (xy 50.291744 -161.932795) (xy 50.206811 -161.889516)
			(xy 50.125535 -161.839706) (xy 50.048417 -161.783675) (xy 49.975932 -161.721766) (xy 49.908528 -161.654361)
			(xy 49.877218 -161.618422) (xy 49.869649 -161.610397) (xy 49.849629 -161.601183) (xy 49.83861 -161.600642)
			(xy 49.761394 -161.600642) (xy 49.750373 -161.601163) (xy 49.730356 -161.610393) (xy 49.722786 -161.618422)
			(xy 49.691484 -161.654366) (xy 49.624069 -161.721758) (xy 49.551578 -161.783656) (xy 49.474455 -161.839679)
			(xy 49.393177 -161.889481) (xy 49.308244 -161.932757) (xy 49.220179 -161.969239) (xy 49.129525 -161.998703)
			(xy 49.036839 -162.020967) (xy 48.942692 -162.035894) (xy 48.847665 -162.043393) (xy 48.800004 -162.043872)
			(xy 48.749836 -162.04339) (xy 48.649842 -162.035106) (xy 48.550873 -162.018593) (xy 48.453607 -161.993965)
			(xy 48.358705 -161.961389) (xy 48.266818 -161.921089) (xy 48.178572 -161.873339) (xy 48.09457 -161.818466)
			(xy 48.015385 -161.756844) (xy 47.94156 -161.688895) (xy 47.873597 -161.615081) (xy 47.811961 -161.535908)
			(xy 47.757072 -161.451916) (xy 47.709307 -161.363678) (xy 47.66899 -161.271798) (xy 47.636397 -161.176903)
			(xy 47.611752 -161.07964) (xy 47.595221 -160.980675) (xy 47.586919 -160.880682) (xy 47.586392 -160.830514)
			(xy 47.586392 -160.830006) (xy 47.586892 -160.78235) (xy 47.59436 -160.687331) (xy 47.609257 -160.593191)
			(xy 47.631492 -160.500509) (xy 47.660928 -160.409857) (xy 47.697384 -160.321793) (xy 47.740635 -160.236859)
			(xy 47.790414 -160.15558) (xy 47.846414 -160.078455) (xy 47.908292 -160.00596) (xy 47.975665 -159.938542)
			(xy 48.011588 -159.907224) (xy 48.019597 -159.899639) (xy 48.028824 -159.879632) (xy 48.029368 -159.868616)
			(xy 48.029368 -159.7914) (xy 48.02884 -159.78038) (xy 48.019615 -159.760363) (xy 48.011588 -159.752792)
			(xy 47.973975 -159.719956) (xy 47.903656 -159.649064) (xy 47.839399 -159.572633) (xy 47.781638 -159.491183)
			(xy 47.730764 -159.405262) (xy 47.68712 -159.315453) (xy 47.651001 -159.222361) (xy 47.622653 -159.126618)
			(xy 47.602266 -159.028868) (xy 47.589978 -158.929775) (xy 47.585872 -158.830006) (xy 38.088824 -158.830006)
			(xy 38.088824 -158.83001) (xy 38.088378 -158.877673) (xy 38.080891 -158.972704) (xy 38.065971 -159.066855)
			(xy 38.043711 -159.159545) (xy 38.014248 -159.250203) (xy 37.977763 -159.33827) (xy 37.934481 -159.423203)
			(xy 37.884669 -159.504479) (xy 37.828634 -159.581596) (xy 37.766722 -159.65408) (xy 37.699314 -159.721483)
			(xy 37.663374 -159.752792) (xy 37.655352 -159.760365) (xy 37.646134 -159.780381) (xy 37.645594 -159.7914)
			(xy 37.645594 -159.868616) (xy 37.646125 -159.879636) (xy 37.655349 -159.899652) (xy 37.663374 -159.907224)
			(xy 37.699313 -159.938533) (xy 37.766706 -160.005945) (xy 37.828605 -160.078436) (xy 37.884629 -160.155557)
			(xy 37.934433 -160.236834) (xy 37.977709 -160.321767) (xy 38.014192 -160.409831) (xy 38.043656 -160.500486)
			(xy 38.06592 -160.593171) (xy 38.080847 -160.687318) (xy 38.088345 -160.782345) (xy 38.088824 -160.830006)
			(xy 38.088376 -160.877669) (xy 38.080889 -160.9727) (xy 38.065969 -161.066851) (xy 38.043709 -161.159541)
			(xy 38.014246 -161.250199) (xy 37.977761 -161.338266) (xy 37.93448 -161.423199) (xy 37.884668 -161.504475)
			(xy 37.828634 -161.581592) (xy 37.766722 -161.654076) (xy 37.699314 -161.721479) (xy 37.663374 -161.752788)
			(xy 37.655354 -161.760363) (xy 37.646135 -161.780378) (xy 37.645594 -161.791396) (xy 37.645594 -161.868612)
			(xy 37.646127 -161.879631) (xy 37.65535 -161.899648) (xy 37.663374 -161.90722) (xy 37.699311 -161.938531)
			(xy 37.766704 -162.005943) (xy 37.828603 -162.078433) (xy 37.884627 -162.155554) (xy 37.934431 -162.236831)
			(xy 37.977708 -162.321764) (xy 38.01419 -162.409828) (xy 38.043655 -162.500482) (xy 38.065919 -162.593168)
			(xy 38.080847 -162.687314) (xy 38.088345 -162.782341) (xy 38.088824 -162.830002) (xy 38.088373 -162.877665)
			(xy 38.080886 -162.972696) (xy 38.065967 -163.066846) (xy 38.043707 -163.159536) (xy 38.014244 -163.250194)
			(xy 37.97776 -163.338261) (xy 37.934478 -163.423195) (xy 37.884667 -163.504471) (xy 37.828633 -163.581588)
			(xy 37.766721 -163.654072) (xy 37.699314 -163.721475) (xy 37.663374 -163.752784) (xy 37.655356 -163.76036)
			(xy 37.646136 -163.780374) (xy 37.645594 -163.791392) (xy 37.645594 -163.868608) (xy 37.646129 -163.879627)
			(xy 37.655351 -163.899644) (xy 37.663374 -163.907216) (xy 37.699309 -163.938529) (xy 37.766702 -164.005941)
			(xy 37.828602 -164.078431) (xy 37.884626 -164.155552) (xy 37.93443 -164.236829) (xy 37.977706 -164.321761)
			(xy 38.014189 -164.409825) (xy 38.043654 -164.500479) (xy 38.065919 -164.593164) (xy 38.080846 -164.68731)
			(xy 38.088345 -164.782337) (xy 38.088824 -164.829998) (xy 38.08837 -164.877661) (xy 38.080883 -164.972691)
			(xy 38.065965 -165.066842) (xy 38.043705 -165.159532) (xy 38.014243 -165.25019) (xy 37.977758 -165.338257)
			(xy 37.934477 -165.42319) (xy 37.884666 -165.504466) (xy 37.828632 -165.581584) (xy 37.766721 -165.654068)
			(xy 37.699314 -165.721471) (xy 37.663374 -165.75278) (xy 37.655358 -165.760358) (xy 37.646136 -165.780371)
			(xy 37.645594 -165.791388) (xy 37.645594 -165.868604) (xy 37.646131 -165.879623) (xy 37.655351 -165.899639)
			(xy 37.663374 -165.907212) (xy 37.699307 -165.938527) (xy 37.7667 -166.005939) (xy 37.8286 -166.078429)
			(xy 37.884624 -166.155549) (xy 37.934428 -166.236826) (xy 37.977705 -166.321758) (xy 38.014188 -166.409822)
			(xy 38.043653 -166.500475) (xy 38.065918 -166.593161) (xy 38.080846 -166.687307) (xy 38.088345 -166.782333)
			(xy 38.088824 -166.829994) (xy 38.088367 -166.877657) (xy 38.080881 -166.972687) (xy 38.065962 -167.066838)
			(xy 38.043703 -167.159528) (xy 38.014241 -167.250186) (xy 37.977757 -167.338253) (xy 37.934476 -167.423186)
			(xy 37.884665 -167.504462) (xy 37.828632 -167.58158) (xy 37.766721 -167.654063) (xy 37.736366 -167.684417)
			(xy 65.5137 -167.684417) (xy 65.5137 -167.575771) (xy 65.521631 -167.467414) (xy 65.53745 -167.359925)
			(xy 65.561073 -167.253878) (xy 65.592374 -167.149838) (xy 65.631186 -167.04836) (xy 65.677301 -166.949986)
			(xy 65.730475 -166.855241) (xy 65.790423 -166.76463) (xy 65.856825 -166.678636) (xy 65.929327 -166.597719)
			(xy 66.007542 -166.522311) (xy 66.091053 -166.452812) (xy 66.179414 -166.389595) (xy 66.272154 -166.332997)
			(xy 66.368778 -166.283319) (xy 66.46877 -166.240827) (xy 66.571598 -166.205747) (xy 66.676712 -166.178267)
			(xy 66.783551 -166.158532) (xy 66.891546 -166.146649) (xy 67.00012 -166.142682) (xy 67.108694 -166.146649)
			(xy 67.216689 -166.158532) (xy 67.323528 -166.178267) (xy 67.428642 -166.205747) (xy 67.53147 -166.240827)
			(xy 67.631462 -166.283319) (xy 67.728086 -166.332997) (xy 67.820826 -166.389595) (xy 67.909187 -166.452812)
			(xy 67.992698 -166.522311) (xy 68.070913 -166.597719) (xy 68.143415 -166.678636) (xy 68.209817 -166.76463)
			(xy 68.269765 -166.855241) (xy 68.322939 -166.949986) (xy 68.369054 -167.04836) (xy 68.407866 -167.149838)
			(xy 68.439167 -167.253878) (xy 68.46279 -167.359925) (xy 68.478609 -167.467414) (xy 68.48654 -167.575771)
			(xy 68.487036 -167.630094) (xy 68.48654 -167.684417) (xy 68.478609 -167.792774) (xy 68.46279 -167.900263)
			(xy 68.439167 -168.00631) (xy 68.407866 -168.11035) (xy 68.369054 -168.211828) (xy 68.322939 -168.310202)
			(xy 68.269765 -168.404947) (xy 68.209817 -168.495558) (xy 68.143415 -168.581552) (xy 68.070913 -168.662469)
			(xy 67.992698 -168.737877) (xy 67.909187 -168.807376) (xy 67.820826 -168.870593) (xy 67.728086 -168.927191)
			(xy 67.631462 -168.976869) (xy 67.53147 -169.019361) (xy 67.428642 -169.054441) (xy 67.323528 -169.081921)
			(xy 67.216689 -169.101656) (xy 67.108694 -169.113539) (xy 67.00012 -169.117507) (xy 66.891546 -169.113539)
			(xy 66.783551 -169.101656) (xy 66.676712 -169.081921) (xy 66.571598 -169.054441) (xy 66.46877 -169.019361)
			(xy 66.368778 -168.976869) (xy 66.272154 -168.927191) (xy 66.179414 -168.870593) (xy 66.091053 -168.807376)
			(xy 66.007542 -168.737877) (xy 65.929327 -168.662469) (xy 65.856825 -168.581552) (xy 65.790423 -168.495558)
			(xy 65.730475 -168.404947) (xy 65.677301 -168.310202) (xy 65.631186 -168.211828) (xy 65.592374 -168.11035)
			(xy 65.561073 -168.00631) (xy 65.53745 -167.900263) (xy 65.521631 -167.792774) (xy 65.5137 -167.684417)
			(xy 37.736366 -167.684417) (xy 37.699314 -167.721467) (xy 37.663374 -167.752776) (xy 37.655359 -167.760356)
			(xy 37.646137 -167.780367) (xy 37.645594 -167.791384) (xy 37.645594 -167.8686) (xy 37.646134 -167.879619)
			(xy 37.655352 -167.899635) (xy 37.663374 -167.907208) (xy 37.699305 -167.938525) (xy 37.766698 -168.005937)
			(xy 37.828598 -168.078427) (xy 37.884622 -168.155547) (xy 37.934426 -168.236823) (xy 37.977703 -168.321755)
			(xy 38.014187 -168.409818) (xy 38.043652 -168.500472) (xy 38.065917 -168.593157) (xy 38.080845 -168.687303)
			(xy 38.088345 -168.782329) (xy 38.088824 -168.82999) (xy 38.088352 -168.880176) (xy 38.080064 -168.980205)
			(xy 38.063544 -169.079208) (xy 38.038904 -169.176509) (xy 38.006313 -169.271442) (xy 37.965994 -169.36336)
			(xy 37.918222 -169.451634) (xy 37.863323 -169.535662) (xy 37.801672 -169.614869) (xy 37.733691 -169.688714)
			(xy 37.659844 -169.756693) (xy 37.580636 -169.818341) (xy 37.496607 -169.873238) (xy 37.408331 -169.921008)
			(xy 37.316412 -169.961325) (xy 37.221478 -169.993913) (xy 37.124177 -170.01855) (xy 37.025173 -170.035068)
			(xy 36.925144 -170.043353) (xy 36.874958 -170.043856) (xy 36.827296 -170.04335) (xy 36.732267 -170.035868)
			(xy 36.638118 -170.020954) (xy 36.545429 -169.9987) (xy 36.454772 -169.969242) (xy 36.366705 -169.932763)
			(xy 36.281772 -169.889487) (xy 36.200495 -169.839681) (xy 36.123377 -169.783652) (xy 36.050891 -169.721746)
			(xy 35.983486 -169.654343) (xy 35.952176 -169.618406) (xy 35.944611 -169.610375) (xy 35.924589 -169.601161)
			(xy 35.913568 -169.600626) (xy 35.836352 -169.600626) (xy 35.825335 -169.601184) (xy 35.805318 -169.610389)
			(xy 35.797744 -169.618406) (xy 35.766406 -169.654318) (xy 35.698996 -169.721711) (xy 35.626508 -169.783611)
			(xy 35.54939 -169.839636) (xy 35.468116 -169.889441) (xy 35.383187 -169.93272) (xy 35.295125 -169.969205)
			(xy 35.204474 -169.998672) (xy 35.111791 -170.02094) (xy 35.017647 -170.035872) (xy 34.922622 -170.043375)
			(xy 34.874962 -170.043856) (xy 34.824777 -170.043384) (xy 34.724749 -170.035093) (xy 34.625748 -170.018569)
			(xy 34.52845 -169.993927) (xy 34.433518 -169.961334) (xy 34.341603 -169.921014) (xy 34.253331 -169.87324)
			(xy 34.169305 -169.818341) (xy 34.0901 -169.75669) (xy 34.016256 -169.68871) (xy 33.948279 -169.614863)
			(xy 33.886631 -169.535656) (xy 33.831735 -169.451628) (xy 33.783965 -169.363354) (xy 33.743648 -169.271437)
			(xy 33.711059 -169.176504) (xy 33.686421 -169.079205) (xy 33.669902 -168.980203) (xy 33.661614 -168.880175)
			(xy 33.661096 -168.82999) (xy 32.074156 -168.82999) (xy 32.126179 -168.923115) (xy 32.226147 -169.085474)
			(xy 32.332915 -169.243443) (xy 32.446292 -169.396739) (xy 32.566073 -169.545084) (xy 32.692041 -169.688213)
			(xy 32.823971 -169.825866) (xy 32.961624 -169.957796) (xy 33.104753 -170.083765) (xy 33.253098 -170.203545)
			(xy 33.406394 -170.316922) (xy 33.564363 -170.423691) (xy 33.726721 -170.523659) (xy 33.893176 -170.616647)
			(xy 34.063427 -170.702486) (xy 34.237168 -170.781022) (xy 34.414086 -170.852113) (xy 34.593862 -170.915632)
			(xy 34.776171 -170.971463) (xy 34.960685 -171.019507) (xy 35.147073 -171.059677) (xy 35.334997 -171.0919)
			(xy 35.52412 -171.116118) (xy 35.7141 -171.132288) (xy 35.904595 -171.14038) (xy 35.999928 -171.140882)
		)
		(stroke
			(width 0)
			(type solid)
		)
		(fill yes)
		(layer "In8.Cu")
		(net "GND")
	)
	(gr_circle
		(center 34.874962 -168.82999)
		(end 36.088066 -168.82999)
		(stroke
			(width 0.2)
			(type default)
		)
		(fill no)
		(layer "In8.Cu")
	)
	(gr_circle
		(center 34.874962 -166.829994)
		(end 36.088066 -166.829994)
		(stroke
			(width 0.2)
			(type default)
		)
		(fill no)
		(layer "In8.Cu")
	)
	(gr_circle
		(center 34.874962 -164.829998)
		(end 36.088066 -164.829998)
		(stroke
			(width 0.2)
			(type default)
		)
		(fill no)
		(layer "In8.Cu")
	)
	(gr_circle
		(center 34.874962 -162.830002)
		(end 36.088066 -162.830002)
		(stroke
			(width 0.2)
			(type default)
		)
		(fill no)
		(layer "In8.Cu")
	)
	(gr_circle
		(center 34.874962 -160.830006)
		(end 36.088066 -160.830006)
		(stroke
			(width 0.2)
			(type default)
		)
		(fill no)
		(layer "In8.Cu")
	)
	(gr_circle
		(center 34.874962 -158.83001)
		(end 36.088066 -158.83001)
		(stroke
			(width 0.2)
			(type default)
		)
		(fill no)
		(layer "In8.Cu")
	)
	(gr_circle
		(center 34.874962 -156.830014)
		(end 36.088066 -156.830014)
		(stroke
			(width 0.2)
			(type default)
		)
		(fill no)
		(layer "In8.Cu")
	)
	(gr_circle
		(center 34.874962 -154.830018)
		(end 36.088066 -154.830018)
		(stroke
			(width 0.2)
			(type default)
		)
		(fill no)
		(layer "In8.Cu")
	)
	(gr_circle
		(center 34.874962 -152.830022)
		(end 36.088066 -152.830022)
		(stroke
			(width 0.2)
			(type default)
		)
		(fill no)
		(layer "In8.Cu")
	)
	(gr_circle
		(center 35.985958 -167.566594)
		(end 37.199062 -167.566594)
		(stroke
			(width 0.2)
			(type default)
		)
		(fill no)
		(layer "In8.Cu")
	)
	(gr_circle
		(center 35.985958 -165.566598)
		(end 37.199062 -165.566598)
		(stroke
			(width 0.2)
			(type default)
		)
		(fill no)
		(layer "In8.Cu")
	)
	(gr_circle
		(center 35.985958 -163.566602)
		(end 37.199062 -163.566602)
		(stroke
			(width 0.2)
			(type default)
		)
		(fill no)
		(layer "In8.Cu")
	)
	(gr_circle
		(center 35.985958 -161.566606)
		(end 37.199062 -161.566606)
		(stroke
			(width 0.2)
			(type default)
		)
		(fill no)
		(layer "In8.Cu")
	)
	(gr_circle
		(center 35.985958 -159.56661)
		(end 37.199062 -159.56661)
		(stroke
			(width 0.2)
			(type default)
		)
		(fill no)
		(layer "In8.Cu")
	)
	(gr_circle
		(center 35.985958 -157.566614)
		(end 37.199062 -157.566614)
		(stroke
			(width 0.2)
			(type default)
		)
		(fill no)
		(layer "In8.Cu")
	)
	(gr_circle
		(center 35.985958 -155.566618)
		(end 37.199062 -155.566618)
		(stroke
			(width 0.2)
			(type default)
		)
		(fill no)
		(layer "In8.Cu")
	)
	(gr_circle
		(center 35.985958 -153.566622)
		(end 37.199062 -153.566622)
		(stroke
			(width 0.2)
			(type default)
		)
		(fill no)
		(layer "In8.Cu")
	)
	(gr_circle
		(center 36.874958 -168.82999)
		(end 38.088062 -168.82999)
		(stroke
			(width 0.2)
			(type default)
		)
		(fill no)
		(layer "In8.Cu")
	)
	(gr_circle
		(center 36.874958 -166.829994)
		(end 38.088062 -166.829994)
		(stroke
			(width 0.2)
			(type default)
		)
		(fill no)
		(layer "In8.Cu")
	)
	(gr_circle
		(center 36.874958 -164.829998)
		(end 38.088062 -164.829998)
		(stroke
			(width 0.2)
			(type default)
		)
		(fill no)
		(layer "In8.Cu")
	)
	(gr_circle
		(center 36.874958 -162.830002)
		(end 38.088062 -162.830002)
		(stroke
			(width 0.2)
			(type default)
		)
		(fill no)
		(layer "In8.Cu")
	)
	(gr_circle
		(center 36.874958 -160.830006)
		(end 38.088062 -160.830006)
		(stroke
			(width 0.2)
			(type default)
		)
		(fill no)
		(layer "In8.Cu")
	)
	(gr_circle
		(center 36.874958 -158.83001)
		(end 38.088062 -158.83001)
		(stroke
			(width 0.2)
			(type default)
		)
		(fill no)
		(layer "In8.Cu")
	)
	(gr_circle
		(center 36.874958 -156.830014)
		(end 38.088062 -156.830014)
		(stroke
			(width 0.2)
			(type default)
		)
		(fill no)
		(layer "In8.Cu")
	)
	(gr_circle
		(center 36.874958 -154.830018)
		(end 38.088062 -154.830018)
		(stroke
			(width 0.2)
			(type default)
		)
		(fill no)
		(layer "In8.Cu")
	)
	(gr_circle
		(center 36.874958 -152.830022)
		(end 38.088062 -152.830022)
		(stroke
			(width 0.2)
			(type default)
		)
		(fill no)
		(layer "In8.Cu")
	)
	(gr_circle
		(center 42.36339 -139.7)
		(end 43.88739 -139.7)
		(stroke
			(width 0.2)
			(type default)
		)
		(fill no)
		(layer "In8.Cu")
	)
	(gr_circle
		(center 42.36339 -119.38)
		(end 43.88739 -119.38)
		(stroke
			(width 0.2)
			(type default)
		)
		(fill no)
		(layer "In8.Cu")
	)
	(gr_circle
		(center 42.36339 -99.06)
		(end 43.88739 -99.06)
		(stroke
			(width 0.2)
			(type default)
		)
		(fill no)
		(layer "In8.Cu")
	)
	(gr_circle
		(center 42.36339 -78.74)
		(end 43.88739 -78.74)
		(stroke
			(width 0.2)
			(type default)
		)
		(fill no)
		(layer "In8.Cu")
	)
	(gr_circle
		(center 42.36339 -58.42)
		(end 43.88739 -58.42)
		(stroke
			(width 0.2)
			(type default)
		)
		(fill no)
		(layer "In8.Cu")
	)
	(gr_circle
		(center 48.800004 -160.830006)
		(end 50.013108 -160.830006)
		(stroke
			(width 0.2)
			(type default)
		)
		(fill no)
		(layer "In8.Cu")
	)
	(gr_circle
		(center 48.800004 -158.83001)
		(end 50.013108 -158.83001)
		(stroke
			(width 0.2)
			(type default)
		)
		(fill no)
		(layer "In8.Cu")
	)
	(gr_circle
		(center 48.800004 -156.830014)
		(end 50.013108 -156.830014)
		(stroke
			(width 0.2)
			(type default)
		)
		(fill no)
		(layer "In8.Cu")
	)
	(gr_circle
		(center 49.9491 -159.99841)
		(end 51.162204 -159.99841)
		(stroke
			(width 0.2)
			(type default)
		)
		(fill no)
		(layer "In8.Cu")
	)
	(gr_circle
		(center 49.9491 -157.998414)
		(end 51.162204 -157.998414)
		(stroke
			(width 0.2)
			(type default)
		)
		(fill no)
		(layer "In8.Cu")
	)
	(gr_circle
		(center 50.8 -160.830006)
		(end 52.013104 -160.830006)
		(stroke
			(width 0.2)
			(type default)
		)
		(fill no)
		(layer "In8.Cu")
	)
	(gr_circle
		(center 50.8 -158.83001)
		(end 52.013104 -158.83001)
		(stroke
			(width 0.2)
			(type default)
		)
		(fill no)
		(layer "In8.Cu")
	)
	(gr_circle
		(center 50.8 -156.830014)
		(end 52.013104 -156.830014)
		(stroke
			(width 0.2)
			(type default)
		)
		(fill no)
		(layer "In8.Cu")
	)
	(gr_circle
		(center 54.799992 -160.830006)
		(end 56.013096 -160.830006)
		(stroke
			(width 0.2)
			(type default)
		)
		(fill no)
		(layer "In8.Cu")
	)
	(gr_circle
		(center 54.799992 -158.83001)
		(end 56.013096 -158.83001)
		(stroke
			(width 0.2)
			(type default)
		)
		(fill no)
		(layer "In8.Cu")
	)
	(gr_circle
		(center 54.799992 -156.830014)
		(end 56.013096 -156.830014)
		(stroke
			(width 0.2)
			(type default)
		)
		(fill no)
		(layer "In8.Cu")
	)
	(gr_circle
		(center 55.5625 -159.84601)
		(end 56.775604 -159.84601)
		(stroke
			(width 0.2)
			(type default)
		)
		(fill no)
		(layer "In8.Cu")
	)
	(gr_circle
		(center 55.5625 -157.846014)
		(end 56.775604 -157.846014)
		(stroke
			(width 0.2)
			(type default)
		)
		(fill no)
		(layer "In8.Cu")
	)
	(gr_circle
		(center 56.799988 -160.830006)
		(end 58.013092 -160.830006)
		(stroke
			(width 0.2)
			(type default)
		)
		(fill no)
		(layer "In8.Cu")
	)
	(gr_circle
		(center 56.799988 -158.83001)
		(end 58.013092 -158.83001)
		(stroke
			(width 0.2)
			(type default)
		)
		(fill no)
		(layer "In8.Cu")
	)
	(gr_circle
		(center 56.799988 -156.830014)
		(end 58.013092 -156.830014)
		(stroke
			(width 0.2)
			(type default)
		)
		(fill no)
		(layer "In8.Cu")
	)
	(gr_circle
		(center 61.92139 -139.7)
		(end 63.44539 -139.7)
		(stroke
			(width 0.2)
			(type default)
		)
		(fill no)
		(layer "In8.Cu")
	)
	(gr_circle
		(center 61.92139 -119.38)
		(end 63.44539 -119.38)
		(stroke
			(width 0.2)
			(type default)
		)
		(fill no)
		(layer "In8.Cu")
	)
	(gr_circle
		(center 61.92139 -99.06)
		(end 63.44539 -99.06)
		(stroke
			(width 0.2)
			(type default)
		)
		(fill no)
		(layer "In8.Cu")
	)
	(gr_circle
		(center 61.92139 -78.74)
		(end 63.44539 -78.74)
		(stroke
			(width 0.2)
			(type default)
		)
		(fill no)
		(layer "In8.Cu")
	)
	(gr_circle
		(center 61.92139 -58.42)
		(end 63.44539 -58.42)
		(stroke
			(width 0.2)
			(type default)
		)
		(fill no)
		(layer "In8.Cu")
	)
	(gr_circle
		(center 63.000128 -160.830006)
		(end 64.213232 -160.830006)
		(stroke
			(width 0.2)
			(type default)
		)
		(fill no)
		(layer "In8.Cu")
	)
	(gr_circle
		(center 63.000128 -158.83001)
		(end 64.213232 -158.83001)
		(stroke
			(width 0.2)
			(type default)
		)
		(fill no)
		(layer "In8.Cu")
	)
	(gr_circle
		(center 63.000128 -156.830014)
		(end 64.213232 -156.830014)
		(stroke
			(width 0.2)
			(type default)
		)
		(fill no)
		(layer "In8.Cu")
	)
	(gr_circle
		(center 63.719964 -2.590038)
		(end 64.933068 -2.590038)
		(stroke
			(width 0.2)
			(type default)
		)
		(fill no)
		(layer "In8.Cu")
	)
	(gr_circle
		(center 63.9699 -159.89681)
		(end 65.183004 -159.89681)
		(stroke
			(width 0.2)
			(type default)
		)
		(fill no)
		(layer "In8.Cu")
	)
	(gr_circle
		(center 63.9699 -157.896814)
		(end 65.183004 -157.896814)
		(stroke
			(width 0.2)
			(type default)
		)
		(fill no)
		(layer "In8.Cu")
	)
	(gr_circle
		(center 65.000124 -160.830006)
		(end 66.213228 -160.830006)
		(stroke
			(width 0.2)
			(type default)
		)
		(fill no)
		(layer "In8.Cu")
	)
	(gr_circle
		(center 65.000124 -158.83001)
		(end 66.213228 -158.83001)
		(stroke
			(width 0.2)
			(type default)
		)
		(fill no)
		(layer "In8.Cu")
	)
	(gr_circle
		(center 65.000124 -156.830014)
		(end 66.213228 -156.830014)
		(stroke
			(width 0.2)
			(type default)
		)
		(fill no)
		(layer "In8.Cu")
	)
	(gr_circle
		(center 66.259964 -2.590038)
		(end 67.473068 -2.590038)
		(stroke
			(width 0.2)
			(type default)
		)
		(fill no)
		(layer "In8.Cu")
	)
	(gr_circle
		(center 69.000116 -160.830006)
		(end 70.21322 -160.830006)
		(stroke
			(width 0.2)
			(type default)
		)
		(fill no)
		(layer "In8.Cu")
	)
	(gr_circle
		(center 69.000116 -158.83001)
		(end 70.21322 -158.83001)
		(stroke
			(width 0.2)
			(type default)
		)
		(fill no)
		(layer "In8.Cu")
	)
	(gr_circle
		(center 69.000116 -156.830014)
		(end 70.21322 -156.830014)
		(stroke
			(width 0.2)
			(type default)
		)
		(fill no)
		(layer "In8.Cu")
	)
	(gr_circle
		(center 69.8881 -159.79521)
		(end 71.101204 -159.79521)
		(stroke
			(width 0.2)
			(type default)
		)
		(fill no)
		(layer "In8.Cu")
	)
	(gr_circle
		(center 69.8881 -157.795214)
		(end 71.101204 -157.795214)
		(stroke
			(width 0.2)
			(type default)
		)
		(fill no)
		(layer "In8.Cu")
	)
	(gr_circle
		(center 71.000112 -160.830006)
		(end 72.213216 -160.830006)
		(stroke
			(width 0.2)
			(type default)
		)
		(fill no)
		(layer "In8.Cu")
	)
	(gr_circle
		(center 71.000112 -158.83001)
		(end 72.213216 -158.83001)
		(stroke
			(width 0.2)
			(type default)
		)
		(fill no)
		(layer "In8.Cu")
	)
	(gr_circle
		(center 71.000112 -156.830014)
		(end 72.213216 -156.830014)
		(stroke
			(width 0.2)
			(type default)
		)
		(fill no)
		(layer "In8.Cu")
	)
	(gr_circle
		(center 75.000104 -160.830006)
		(end 76.213208 -160.830006)
		(stroke
			(width 0.2)
			(type default)
		)
		(fill no)
		(layer "In8.Cu")
	)
	(gr_circle
		(center 75.000104 -158.83001)
		(end 76.213208 -158.83001)
		(stroke
			(width 0.2)
			(type default)
		)
		(fill no)
		(layer "In8.Cu")
	)
	(gr_circle
		(center 75.000104 -156.830014)
		(end 76.213208 -156.830014)
		(stroke
			(width 0.2)
			(type default)
		)
		(fill no)
		(layer "In8.Cu")
	)
	(gr_circle
		(center 75.8571 -159.74441)
		(end 77.070204 -159.74441)
		(stroke
			(width 0.2)
			(type default)
		)
		(fill no)
		(layer "In8.Cu")
	)
	(gr_circle
		(center 75.8571 -157.744414)
		(end 77.070204 -157.744414)
		(stroke
			(width 0.2)
			(type default)
		)
		(fill no)
		(layer "In8.Cu")
	)
	(gr_circle
		(center 77.0001 -160.830006)
		(end 78.213204 -160.830006)
		(stroke
			(width 0.2)
			(type default)
		)
		(fill no)
		(layer "In8.Cu")
	)
	(gr_circle
		(center 77.0001 -158.83001)
		(end 78.213204 -158.83001)
		(stroke
			(width 0.2)
			(type default)
		)
		(fill no)
		(layer "In8.Cu")
	)
	(gr_circle
		(center 77.0001 -156.830014)
		(end 78.213204 -156.830014)
		(stroke
			(width 0.2)
			(type default)
		)
		(fill no)
		(layer "In8.Cu")
	)
	(gr_circle
		(center 82.677 -5.334)
		(end 83.566 -5.334)
		(stroke
			(width 0.2)
			(type default)
		)
		(fill no)
		(layer "In8.Cu")
	)
	(gr_circle
		(center 82.677 -4.572)
		(end 83.566 -4.572)
		(stroke
			(width 0.2)
			(type default)
		)
		(fill no)
		(layer "In8.Cu")
	)
	(gr_circle
		(center 82.677 -3.81)
		(end 83.566 -3.81)
		(stroke
			(width 0.2)
			(type default)
		)
		(fill no)
		(layer "In8.Cu")
	)
	(gr_circle
		(center 83.439 -5.334)
		(end 84.328 -5.334)
		(stroke
			(width 0.2)
			(type default)
		)
		(fill no)
		(layer "In8.Cu")
	)
	(gr_circle
		(center 83.439 -4.572)
		(end 84.328 -4.572)
		(stroke
			(width 0.2)
			(type default)
		)
		(fill no)
		(layer "In8.Cu")
	)
	(gr_circle
		(center 83.439 -3.81)
		(end 84.328 -3.81)
		(stroke
			(width 0.2)
			(type default)
		)
		(fill no)
		(layer "In8.Cu")
	)
	(gr_circle
		(center 84.201 -5.334)
		(end 85.09 -5.334)
		(stroke
			(width 0.2)
			(type default)
		)
		(fill no)
		(layer "In8.Cu")
	)
	(gr_circle
		(center 84.201 -4.572)
		(end 85.09 -4.572)
		(stroke
			(width 0.2)
			(type default)
		)
		(fill no)
		(layer "In8.Cu")
	)
	(gr_circle
		(center 84.201 -3.81)
		(end 85.09 -3.81)
		(stroke
			(width 0.2)
			(type default)
		)
		(fill no)
		(layer "In8.Cu")
	)
	(gr_circle
		(center 84.963 -5.334)
		(end 85.852 -5.334)
		(stroke
			(width 0.2)
			(type default)
		)
		(fill no)
		(layer "In8.Cu")
	)
	(gr_circle
		(center 84.963 -4.572)
		(end 85.852 -4.572)
		(stroke
			(width 0.2)
			(type default)
		)
		(fill no)
		(layer "In8.Cu")
	)
	(gr_circle
		(center 84.963 -3.81)
		(end 85.852 -3.81)
		(stroke
			(width 0.2)
			(type default)
		)
		(fill no)
		(layer "In8.Cu")
	)
	(gr_circle
		(center 85.725 -5.334)
		(end 86.614 -5.334)
		(stroke
			(width 0.2)
			(type default)
		)
		(fill no)
		(layer "In8.Cu")
	)
	(gr_circle
		(center 85.725 -4.572)
		(end 86.614 -4.572)
		(stroke
			(width 0.2)
			(type default)
		)
		(fill no)
		(layer "In8.Cu")
	)
	(gr_circle
		(center 85.725 -3.81)
		(end 86.614 -3.81)
		(stroke
			(width 0.2)
			(type default)
		)
		(fill no)
		(layer "In8.Cu")
	)
	(gr_circle
		(center 86.487 -5.334)
		(end 87.376 -5.334)
		(stroke
			(width 0.2)
			(type default)
		)
		(fill no)
		(layer "In8.Cu")
	)
	(gr_circle
		(center 86.487 -4.572)
		(end 87.376 -4.572)
		(stroke
			(width 0.2)
			(type default)
		)
		(fill no)
		(layer "In8.Cu")
	)
	(gr_circle
		(center 86.487 -3.81)
		(end 87.376 -3.81)
		(stroke
			(width 0.2)
			(type default)
		)
		(fill no)
		(layer "In8.Cu")
	)
	(gr_circle
		(center 108.782358 -42.432224)
		(end 109.671358 -42.432224)
		(stroke
			(width 0.2)
			(type default)
		)
		(fill no)
		(layer "In8.Cu")
	)
	(gr_circle
		(center 109.374432 -53.692806)
		(end 110.263432 -53.692806)
		(stroke
			(width 0.2)
			(type default)
		)
		(fill no)
		(layer "In8.Cu")
	)
	(gr_circle
		(center 111.2774 -54.483)
		(end 112.1664 -54.483)
		(stroke
			(width 0.2)
			(type default)
		)
		(fill no)
		(layer "In8.Cu")
	)
	(gr_circle
		(center 111.2774 -43.18)
		(end 112.1664 -43.18)
		(stroke
			(width 0.2)
			(type default)
		)
		(fill no)
		(layer "In8.Cu")
	)
	(gr_circle
		(center 112.252252 -78.6638)
		(end 113.141252 -78.6638)
		(stroke
			(width 0.2)
			(type default)
		)
		(fill no)
		(layer "In8.Cu")
	)
	(gr_circle
		(center 112.252252 -67.3862)
		(end 113.141252 -67.3862)
		(stroke
			(width 0.2)
			(type default)
		)
		(fill no)
		(layer "In8.Cu")
	)
	(gr_circle
		(center 112.252252 -56.1086)
		(end 113.141252 -56.1086)
		(stroke
			(width 0.2)
			(type default)
		)
		(fill no)
		(layer "In8.Cu")
	)
	(gr_circle
		(center 112.252252 -44.831)
		(end 113.141252 -44.831)
		(stroke
			(width 0.2)
			(type default)
		)
		(fill no)
		(layer "In8.Cu")
	)
	(gr_circle
		(center 112.252252 -33.5534)
		(end 113.141252 -33.5534)
		(stroke
			(width 0.2)
			(type default)
		)
		(fill no)
		(layer "In8.Cu")
	)
	(gr_circle
		(center 112.252252 -22.2758)
		(end 113.141252 -22.2758)
		(stroke
			(width 0.2)
			(type default)
		)
		(fill no)
		(layer "In8.Cu")
	)
	(gr_circle
		(center 112.455452 -73.66)
		(end 113.344452 -73.66)
		(stroke
			(width 0.2)
			(type default)
		)
		(fill no)
		(layer "In8.Cu")
	)
	(gr_circle
		(center 112.455452 -72.898)
		(end 113.344452 -72.898)
		(stroke
			(width 0.2)
			(type default)
		)
		(fill no)
		(layer "In8.Cu")
	)
	(gr_circle
		(center 112.455452 -72.136)
		(end 113.344452 -72.136)
		(stroke
			(width 0.2)
			(type default)
		)
		(fill no)
		(layer "In8.Cu")
	)
	(gr_circle
		(center 112.455452 -71.374)
		(end 113.344452 -71.374)
		(stroke
			(width 0.2)
			(type default)
		)
		(fill no)
		(layer "In8.Cu")
	)
	(gr_circle
		(center 112.455452 -70.612)
		(end 113.344452 -70.612)
		(stroke
			(width 0.2)
			(type default)
		)
		(fill no)
		(layer "In8.Cu")
	)
	(gr_circle
		(center 112.455452 -62.3824)
		(end 113.344452 -62.3824)
		(stroke
			(width 0.2)
			(type default)
		)
		(fill no)
		(layer "In8.Cu")
	)
	(gr_circle
		(center 112.455452 -61.6204)
		(end 113.344452 -61.6204)
		(stroke
			(width 0.2)
			(type default)
		)
		(fill no)
		(layer "In8.Cu")
	)
	(gr_circle
		(center 112.455452 -60.8584)
		(end 113.344452 -60.8584)
		(stroke
			(width 0.2)
			(type default)
		)
		(fill no)
		(layer "In8.Cu")
	)
	(gr_circle
		(center 112.455452 -60.0964)
		(end 113.344452 -60.0964)
		(stroke
			(width 0.2)
			(type default)
		)
		(fill no)
		(layer "In8.Cu")
	)
	(gr_circle
		(center 112.455452 -59.3344)
		(end 113.344452 -59.3344)
		(stroke
			(width 0.2)
			(type default)
		)
		(fill no)
		(layer "In8.Cu")
	)
	(gr_circle
		(center 112.455452 -51.1048)
		(end 113.344452 -51.1048)
		(stroke
			(width 0.2)
			(type default)
		)
		(fill no)
		(layer "In8.Cu")
	)
	(gr_circle
		(center 112.455452 -50.3428)
		(end 113.344452 -50.3428)
		(stroke
			(width 0.2)
			(type default)
		)
		(fill no)
		(layer "In8.Cu")
	)
	(gr_circle
		(center 112.455452 -49.5808)
		(end 113.344452 -49.5808)
		(stroke
			(width 0.2)
			(type default)
		)
		(fill no)
		(layer "In8.Cu")
	)
	(gr_circle
		(center 112.455452 -48.8188)
		(end 113.344452 -48.8188)
		(stroke
			(width 0.2)
			(type default)
		)
		(fill no)
		(layer "In8.Cu")
	)
	(gr_circle
		(center 112.455452 -48.0568)
		(end 113.344452 -48.0568)
		(stroke
			(width 0.2)
			(type default)
		)
		(fill no)
		(layer "In8.Cu")
	)
	(gr_circle
		(center 112.455452 -39.8272)
		(end 113.344452 -39.8272)
		(stroke
			(width 0.2)
			(type default)
		)
		(fill no)
		(layer "In8.Cu")
	)
	(gr_circle
		(center 112.455452 -39.0652)
		(end 113.344452 -39.0652)
		(stroke
			(width 0.2)
			(type default)
		)
		(fill no)
		(layer "In8.Cu")
	)
	(gr_circle
		(center 112.455452 -38.3032)
		(end 113.344452 -38.3032)
		(stroke
			(width 0.2)
			(type default)
		)
		(fill no)
		(layer "In8.Cu")
	)
	(gr_circle
		(center 112.455452 -37.5412)
		(end 113.344452 -37.5412)
		(stroke
			(width 0.2)
			(type default)
		)
		(fill no)
		(layer "In8.Cu")
	)
	(gr_circle
		(center 112.455452 -36.7792)
		(end 113.344452 -36.7792)
		(stroke
			(width 0.2)
			(type default)
		)
		(fill no)
		(layer "In8.Cu")
	)
	(gr_circle
		(center 112.455452 -28.5496)
		(end 113.344452 -28.5496)
		(stroke
			(width 0.2)
			(type default)
		)
		(fill no)
		(layer "In8.Cu")
	)
	(gr_circle
		(center 112.455452 -27.7876)
		(end 113.344452 -27.7876)
		(stroke
			(width 0.2)
			(type default)
		)
		(fill no)
		(layer "In8.Cu")
	)
	(gr_circle
		(center 112.455452 -27.0256)
		(end 113.344452 -27.0256)
		(stroke
			(width 0.2)
			(type default)
		)
		(fill no)
		(layer "In8.Cu")
	)
	(gr_circle
		(center 112.455452 -26.2636)
		(end 113.344452 -26.2636)
		(stroke
			(width 0.2)
			(type default)
		)
		(fill no)
		(layer "In8.Cu")
	)
	(gr_circle
		(center 112.455452 -25.5016)
		(end 113.344452 -25.5016)
		(stroke
			(width 0.2)
			(type default)
		)
		(fill no)
		(layer "In8.Cu")
	)
	(gr_circle
		(center 112.455452 -17.272)
		(end 113.344452 -17.272)
		(stroke
			(width 0.2)
			(type default)
		)
		(fill no)
		(layer "In8.Cu")
	)
	(gr_circle
		(center 112.455452 -16.51)
		(end 113.344452 -16.51)
		(stroke
			(width 0.2)
			(type default)
		)
		(fill no)
		(layer "In8.Cu")
	)
	(gr_circle
		(center 112.455452 -15.748)
		(end 113.344452 -15.748)
		(stroke
			(width 0.2)
			(type default)
		)
		(fill no)
		(layer "In8.Cu")
	)
	(gr_circle
		(center 112.455452 -14.986)
		(end 113.344452 -14.986)
		(stroke
			(width 0.2)
			(type default)
		)
		(fill no)
		(layer "In8.Cu")
	)
	(gr_circle
		(center 112.455452 -14.224)
		(end 113.344452 -14.224)
		(stroke
			(width 0.2)
			(type default)
		)
		(fill no)
		(layer "In8.Cu")
	)
	(gr_circle
		(center 113.217452 -73.66)
		(end 114.106452 -73.66)
		(stroke
			(width 0.2)
			(type default)
		)
		(fill no)
		(layer "In8.Cu")
	)
	(gr_circle
		(center 113.217452 -72.898)
		(end 114.106452 -72.898)
		(stroke
			(width 0.2)
			(type default)
		)
		(fill no)
		(layer "In8.Cu")
	)
	(gr_circle
		(center 113.217452 -72.136)
		(end 114.106452 -72.136)
		(stroke
			(width 0.2)
			(type default)
		)
		(fill no)
		(layer "In8.Cu")
	)
	(gr_circle
		(center 113.217452 -71.374)
		(end 114.106452 -71.374)
		(stroke
			(width 0.2)
			(type default)
		)
		(fill no)
		(layer "In8.Cu")
	)
	(gr_circle
		(center 113.217452 -70.612)
		(end 114.106452 -70.612)
		(stroke
			(width 0.2)
			(type default)
		)
		(fill no)
		(layer "In8.Cu")
	)
	(gr_circle
		(center 113.217452 -62.3824)
		(end 114.106452 -62.3824)
		(stroke
			(width 0.2)
			(type default)
		)
		(fill no)
		(layer "In8.Cu")
	)
	(gr_circle
		(center 113.217452 -61.6204)
		(end 114.106452 -61.6204)
		(stroke
			(width 0.2)
			(type default)
		)
		(fill no)
		(layer "In8.Cu")
	)
	(gr_circle
		(center 113.217452 -60.8584)
		(end 114.106452 -60.8584)
		(stroke
			(width 0.2)
			(type default)
		)
		(fill no)
		(layer "In8.Cu")
	)
	(gr_circle
		(center 113.217452 -60.0964)
		(end 114.106452 -60.0964)
		(stroke
			(width 0.2)
			(type default)
		)
		(fill no)
		(layer "In8.Cu")
	)
	(gr_circle
		(center 113.217452 -59.3344)
		(end 114.106452 -59.3344)
		(stroke
			(width 0.2)
			(type default)
		)
		(fill no)
		(layer "In8.Cu")
	)
	(gr_circle
		(center 113.217452 -51.1048)
		(end 114.106452 -51.1048)
		(stroke
			(width 0.2)
			(type default)
		)
		(fill no)
		(layer "In8.Cu")
	)
	(gr_circle
		(center 113.217452 -50.3428)
		(end 114.106452 -50.3428)
		(stroke
			(width 0.2)
			(type default)
		)
		(fill no)
		(layer "In8.Cu")
	)
	(gr_circle
		(center 113.217452 -49.5808)
		(end 114.106452 -49.5808)
		(stroke
			(width 0.2)
			(type default)
		)
		(fill no)
		(layer "In8.Cu")
	)
	(gr_circle
		(center 113.217452 -48.8188)
		(end 114.106452 -48.8188)
		(stroke
			(width 0.2)
			(type default)
		)
		(fill no)
		(layer "In8.Cu")
	)
	(gr_circle
		(center 113.217452 -48.0568)
		(end 114.106452 -48.0568)
		(stroke
			(width 0.2)
			(type default)
		)
		(fill no)
		(layer "In8.Cu")
	)
	(gr_circle
		(center 113.217452 -39.8272)
		(end 114.106452 -39.8272)
		(stroke
			(width 0.2)
			(type default)
		)
		(fill no)
		(layer "In8.Cu")
	)
	(gr_circle
		(center 113.217452 -39.0652)
		(end 114.106452 -39.0652)
		(stroke
			(width 0.2)
			(type default)
		)
		(fill no)
		(layer "In8.Cu")
	)
	(gr_circle
		(center 113.217452 -38.3032)
		(end 114.106452 -38.3032)
		(stroke
			(width 0.2)
			(type default)
		)
		(fill no)
		(layer "In8.Cu")
	)
	(gr_circle
		(center 113.217452 -37.5412)
		(end 114.106452 -37.5412)
		(stroke
			(width 0.2)
			(type default)
		)
		(fill no)
		(layer "In8.Cu")
	)
	(gr_circle
		(center 113.217452 -36.7792)
		(end 114.106452 -36.7792)
		(stroke
			(width 0.2)
			(type default)
		)
		(fill no)
		(layer "In8.Cu")
	)
	(gr_circle
		(center 113.217452 -28.5496)
		(end 114.106452 -28.5496)
		(stroke
			(width 0.2)
			(type default)
		)
		(fill no)
		(layer "In8.Cu")
	)
	(gr_circle
		(center 113.217452 -27.7876)
		(end 114.106452 -27.7876)
		(stroke
			(width 0.2)
			(type default)
		)
		(fill no)
		(layer "In8.Cu")
	)
	(gr_circle
		(center 113.217452 -27.0256)
		(end 114.106452 -27.0256)
		(stroke
			(width 0.2)
			(type default)
		)
		(fill no)
		(layer "In8.Cu")
	)
	(gr_circle
		(center 113.217452 -26.2636)
		(end 114.106452 -26.2636)
		(stroke
			(width 0.2)
			(type default)
		)
		(fill no)
		(layer "In8.Cu")
	)
	(gr_circle
		(center 113.217452 -25.5016)
		(end 114.106452 -25.5016)
		(stroke
			(width 0.2)
			(type default)
		)
		(fill no)
		(layer "In8.Cu")
	)
	(gr_circle
		(center 113.217452 -17.272)
		(end 114.106452 -17.272)
		(stroke
			(width 0.2)
			(type default)
		)
		(fill no)
		(layer "In8.Cu")
	)
	(gr_circle
		(center 113.217452 -16.51)
		(end 114.106452 -16.51)
		(stroke
			(width 0.2)
			(type default)
		)
		(fill no)
		(layer "In8.Cu")
	)
	(gr_circle
		(center 113.217452 -15.748)
		(end 114.106452 -15.748)
		(stroke
			(width 0.2)
			(type default)
		)
		(fill no)
		(layer "In8.Cu")
	)
	(gr_circle
		(center 113.217452 -14.986)
		(end 114.106452 -14.986)
		(stroke
			(width 0.2)
			(type default)
		)
		(fill no)
		(layer "In8.Cu")
	)
	(gr_circle
		(center 113.217452 -14.224)
		(end 114.106452 -14.224)
		(stroke
			(width 0.2)
			(type default)
		)
		(fill no)
		(layer "In8.Cu")
	)
	(gr_circle
		(center 113.979452 -73.66)
		(end 114.868452 -73.66)
		(stroke
			(width 0.2)
			(type default)
		)
		(fill no)
		(layer "In8.Cu")
	)
	(gr_circle
		(center 113.979452 -72.898)
		(end 114.868452 -72.898)
		(stroke
			(width 0.2)
			(type default)
		)
		(fill no)
		(layer "In8.Cu")
	)
	(gr_circle
		(center 113.979452 -72.136)
		(end 114.868452 -72.136)
		(stroke
			(width 0.2)
			(type default)
		)
		(fill no)
		(layer "In8.Cu")
	)
	(gr_circle
		(center 113.979452 -71.374)
		(end 114.868452 -71.374)
		(stroke
			(width 0.2)
			(type default)
		)
		(fill no)
		(layer "In8.Cu")
	)
	(gr_circle
		(center 113.979452 -70.612)
		(end 114.868452 -70.612)
		(stroke
			(width 0.2)
			(type default)
		)
		(fill no)
		(layer "In8.Cu")
	)
	(gr_circle
		(center 113.979452 -62.3824)
		(end 114.868452 -62.3824)
		(stroke
			(width 0.2)
			(type default)
		)
		(fill no)
		(layer "In8.Cu")
	)
	(gr_circle
		(center 113.979452 -61.6204)
		(end 114.868452 -61.6204)
		(stroke
			(width 0.2)
			(type default)
		)
		(fill no)
		(layer "In8.Cu")
	)
	(gr_circle
		(center 113.979452 -60.8584)
		(end 114.868452 -60.8584)
		(stroke
			(width 0.2)
			(type default)
		)
		(fill no)
		(layer "In8.Cu")
	)
	(gr_circle
		(center 113.979452 -60.0964)
		(end 114.868452 -60.0964)
		(stroke
			(width 0.2)
			(type default)
		)
		(fill no)
		(layer "In8.Cu")
	)
	(gr_circle
		(center 113.979452 -59.3344)
		(end 114.868452 -59.3344)
		(stroke
			(width 0.2)
			(type default)
		)
		(fill no)
		(layer "In8.Cu")
	)
	(gr_circle
		(center 113.979452 -51.1048)
		(end 114.868452 -51.1048)
		(stroke
			(width 0.2)
			(type default)
		)
		(fill no)
		(layer "In8.Cu")
	)
	(gr_circle
		(center 113.979452 -50.3428)
		(end 114.868452 -50.3428)
		(stroke
			(width 0.2)
			(type default)
		)
		(fill no)
		(layer "In8.Cu")
	)
	(gr_circle
		(center 113.979452 -49.5808)
		(end 114.868452 -49.5808)
		(stroke
			(width 0.2)
			(type default)
		)
		(fill no)
		(layer "In8.Cu")
	)
	(gr_circle
		(center 113.979452 -48.8188)
		(end 114.868452 -48.8188)
		(stroke
			(width 0.2)
			(type default)
		)
		(fill no)
		(layer "In8.Cu")
	)
	(gr_circle
		(center 113.979452 -48.0568)
		(end 114.868452 -48.0568)
		(stroke
			(width 0.2)
			(type default)
		)
		(fill no)
		(layer "In8.Cu")
	)
	(gr_circle
		(center 113.979452 -39.8272)
		(end 114.868452 -39.8272)
		(stroke
			(width 0.2)
			(type default)
		)
		(fill no)
		(layer "In8.Cu")
	)
	(gr_circle
		(center 113.979452 -39.0652)
		(end 114.868452 -39.0652)
		(stroke
			(width 0.2)
			(type default)
		)
		(fill no)
		(layer "In8.Cu")
	)
	(gr_circle
		(center 113.979452 -38.3032)
		(end 114.868452 -38.3032)
		(stroke
			(width 0.2)
			(type default)
		)
		(fill no)
		(layer "In8.Cu")
	)
	(gr_circle
		(center 113.979452 -37.5412)
		(end 114.868452 -37.5412)
		(stroke
			(width 0.2)
			(type default)
		)
		(fill no)
		(layer "In8.Cu")
	)
	(gr_circle
		(center 113.979452 -36.7792)
		(end 114.868452 -36.7792)
		(stroke
			(width 0.2)
			(type default)
		)
		(fill no)
		(layer "In8.Cu")
	)
	(gr_circle
		(center 113.979452 -28.5496)
		(end 114.868452 -28.5496)
		(stroke
			(width 0.2)
			(type default)
		)
		(fill no)
		(layer "In8.Cu")
	)
	(gr_circle
		(center 113.979452 -27.7876)
		(end 114.868452 -27.7876)
		(stroke
			(width 0.2)
			(type default)
		)
		(fill no)
		(layer "In8.Cu")
	)
	(gr_circle
		(center 113.979452 -27.0256)
		(end 114.868452 -27.0256)
		(stroke
			(width 0.2)
			(type default)
		)
		(fill no)
		(layer "In8.Cu")
	)
	(gr_circle
		(center 113.979452 -26.2636)
		(end 114.868452 -26.2636)
		(stroke
			(width 0.2)
			(type default)
		)
		(fill no)
		(layer "In8.Cu")
	)
	(gr_circle
		(center 113.979452 -25.5016)
		(end 114.868452 -25.5016)
		(stroke
			(width 0.2)
			(type default)
		)
		(fill no)
		(layer "In8.Cu")
	)
	(gr_circle
		(center 113.979452 -17.272)
		(end 114.868452 -17.272)
		(stroke
			(width 0.2)
			(type default)
		)
		(fill no)
		(layer "In8.Cu")
	)
	(gr_circle
		(center 113.979452 -16.51)
		(end 114.868452 -16.51)
		(stroke
			(width 0.2)
			(type default)
		)
		(fill no)
		(layer "In8.Cu")
	)
	(gr_circle
		(center 113.979452 -15.748)
		(end 114.868452 -15.748)
		(stroke
			(width 0.2)
			(type default)
		)
		(fill no)
		(layer "In8.Cu")
	)
	(gr_circle
		(center 113.979452 -14.986)
		(end 114.868452 -14.986)
		(stroke
			(width 0.2)
			(type default)
		)
		(fill no)
		(layer "In8.Cu")
	)
	(gr_circle
		(center 113.979452 -14.224)
		(end 114.868452 -14.224)
		(stroke
			(width 0.2)
			(type default)
		)
		(fill no)
		(layer "In8.Cu")
	)
	(gr_circle
		(center 114.741452 -73.66)
		(end 115.630452 -73.66)
		(stroke
			(width 0.2)
			(type default)
		)
		(fill no)
		(layer "In8.Cu")
	)
	(gr_circle
		(center 114.741452 -72.898)
		(end 115.630452 -72.898)
		(stroke
			(width 0.2)
			(type default)
		)
		(fill no)
		(layer "In8.Cu")
	)
	(gr_circle
		(center 114.741452 -72.136)
		(end 115.630452 -72.136)
		(stroke
			(width 0.2)
			(type default)
		)
		(fill no)
		(layer "In8.Cu")
	)
	(gr_circle
		(center 114.741452 -71.374)
		(end 115.630452 -71.374)
		(stroke
			(width 0.2)
			(type default)
		)
		(fill no)
		(layer "In8.Cu")
	)
	(gr_circle
		(center 114.741452 -70.612)
		(end 115.630452 -70.612)
		(stroke
			(width 0.2)
			(type default)
		)
		(fill no)
		(layer "In8.Cu")
	)
	(gr_circle
		(center 114.741452 -62.3824)
		(end 115.630452 -62.3824)
		(stroke
			(width 0.2)
			(type default)
		)
		(fill no)
		(layer "In8.Cu")
	)
	(gr_circle
		(center 114.741452 -61.6204)
		(end 115.630452 -61.6204)
		(stroke
			(width 0.2)
			(type default)
		)
		(fill no)
		(layer "In8.Cu")
	)
	(gr_circle
		(center 114.741452 -60.8584)
		(end 115.630452 -60.8584)
		(stroke
			(width 0.2)
			(type default)
		)
		(fill no)
		(layer "In8.Cu")
	)
	(gr_circle
		(center 114.741452 -60.0964)
		(end 115.630452 -60.0964)
		(stroke
			(width 0.2)
			(type default)
		)
		(fill no)
		(layer "In8.Cu")
	)
	(gr_circle
		(center 114.741452 -59.3344)
		(end 115.630452 -59.3344)
		(stroke
			(width 0.2)
			(type default)
		)
		(fill no)
		(layer "In8.Cu")
	)
	(gr_circle
		(center 114.741452 -51.1048)
		(end 115.630452 -51.1048)
		(stroke
			(width 0.2)
			(type default)
		)
		(fill no)
		(layer "In8.Cu")
	)
	(gr_circle
		(center 114.741452 -50.3428)
		(end 115.630452 -50.3428)
		(stroke
			(width 0.2)
			(type default)
		)
		(fill no)
		(layer "In8.Cu")
	)
	(gr_circle
		(center 114.741452 -49.5808)
		(end 115.630452 -49.5808)
		(stroke
			(width 0.2)
			(type default)
		)
		(fill no)
		(layer "In8.Cu")
	)
	(gr_circle
		(center 114.741452 -48.8188)
		(end 115.630452 -48.8188)
		(stroke
			(width 0.2)
			(type default)
		)
		(fill no)
		(layer "In8.Cu")
	)
	(gr_circle
		(center 114.741452 -48.0568)
		(end 115.630452 -48.0568)
		(stroke
			(width 0.2)
			(type default)
		)
		(fill no)
		(layer "In8.Cu")
	)
	(gr_circle
		(center 114.741452 -39.8272)
		(end 115.630452 -39.8272)
		(stroke
			(width 0.2)
			(type default)
		)
		(fill no)
		(layer "In8.Cu")
	)
	(gr_circle
		(center 114.741452 -39.0652)
		(end 115.630452 -39.0652)
		(stroke
			(width 0.2)
			(type default)
		)
		(fill no)
		(layer "In8.Cu")
	)
	(gr_circle
		(center 114.741452 -38.3032)
		(end 115.630452 -38.3032)
		(stroke
			(width 0.2)
			(type default)
		)
		(fill no)
		(layer "In8.Cu")
	)
	(gr_circle
		(center 114.741452 -37.5412)
		(end 115.630452 -37.5412)
		(stroke
			(width 0.2)
			(type default)
		)
		(fill no)
		(layer "In8.Cu")
	)
	(gr_circle
		(center 114.741452 -36.7792)
		(end 115.630452 -36.7792)
		(stroke
			(width 0.2)
			(type default)
		)
		(fill no)
		(layer "In8.Cu")
	)
	(gr_circle
		(center 114.741452 -28.5496)
		(end 115.630452 -28.5496)
		(stroke
			(width 0.2)
			(type default)
		)
		(fill no)
		(layer "In8.Cu")
	)
	(gr_circle
		(center 114.741452 -27.7876)
		(end 115.630452 -27.7876)
		(stroke
			(width 0.2)
			(type default)
		)
		(fill no)
		(layer "In8.Cu")
	)
	(gr_circle
		(center 114.741452 -27.0256)
		(end 115.630452 -27.0256)
		(stroke
			(width 0.2)
			(type default)
		)
		(fill no)
		(layer "In8.Cu")
	)
	(gr_circle
		(center 114.741452 -26.2636)
		(end 115.630452 -26.2636)
		(stroke
			(width 0.2)
			(type default)
		)
		(fill no)
		(layer "In8.Cu")
	)
	(gr_circle
		(center 114.741452 -25.5016)
		(end 115.630452 -25.5016)
		(stroke
			(width 0.2)
			(type default)
		)
		(fill no)
		(layer "In8.Cu")
	)
	(gr_circle
		(center 114.741452 -17.272)
		(end 115.630452 -17.272)
		(stroke
			(width 0.2)
			(type default)
		)
		(fill no)
		(layer "In8.Cu")
	)
	(gr_circle
		(center 114.741452 -16.51)
		(end 115.630452 -16.51)
		(stroke
			(width 0.2)
			(type default)
		)
		(fill no)
		(layer "In8.Cu")
	)
	(gr_circle
		(center 114.741452 -15.748)
		(end 115.630452 -15.748)
		(stroke
			(width 0.2)
			(type default)
		)
		(fill no)
		(layer "In8.Cu")
	)
	(gr_circle
		(center 114.741452 -14.986)
		(end 115.630452 -14.986)
		(stroke
			(width 0.2)
			(type default)
		)
		(fill no)
		(layer "In8.Cu")
	)
	(gr_circle
		(center 114.741452 -14.224)
		(end 115.630452 -14.224)
		(stroke
			(width 0.2)
			(type default)
		)
		(fill no)
		(layer "In8.Cu")
	)
	(gr_circle
		(center 115.503452 -73.66)
		(end 116.392452 -73.66)
		(stroke
			(width 0.2)
			(type default)
		)
		(fill no)
		(layer "In8.Cu")
	)
	(gr_circle
		(center 115.503452 -72.898)
		(end 116.392452 -72.898)
		(stroke
			(width 0.2)
			(type default)
		)
		(fill no)
		(layer "In8.Cu")
	)
	(gr_circle
		(center 115.503452 -72.136)
		(end 116.392452 -72.136)
		(stroke
			(width 0.2)
			(type default)
		)
		(fill no)
		(layer "In8.Cu")
	)
	(gr_circle
		(center 115.503452 -71.374)
		(end 116.392452 -71.374)
		(stroke
			(width 0.2)
			(type default)
		)
		(fill no)
		(layer "In8.Cu")
	)
	(gr_circle
		(center 115.503452 -70.612)
		(end 116.392452 -70.612)
		(stroke
			(width 0.2)
			(type default)
		)
		(fill no)
		(layer "In8.Cu")
	)
	(gr_circle
		(center 115.503452 -62.3824)
		(end 116.392452 -62.3824)
		(stroke
			(width 0.2)
			(type default)
		)
		(fill no)
		(layer "In8.Cu")
	)
	(gr_circle
		(center 115.503452 -61.6204)
		(end 116.392452 -61.6204)
		(stroke
			(width 0.2)
			(type default)
		)
		(fill no)
		(layer "In8.Cu")
	)
	(gr_circle
		(center 115.503452 -60.8584)
		(end 116.392452 -60.8584)
		(stroke
			(width 0.2)
			(type default)
		)
		(fill no)
		(layer "In8.Cu")
	)
	(gr_circle
		(center 115.503452 -60.0964)
		(end 116.392452 -60.0964)
		(stroke
			(width 0.2)
			(type default)
		)
		(fill no)
		(layer "In8.Cu")
	)
	(gr_circle
		(center 115.503452 -59.3344)
		(end 116.392452 -59.3344)
		(stroke
			(width 0.2)
			(type default)
		)
		(fill no)
		(layer "In8.Cu")
	)
	(gr_circle
		(center 115.503452 -51.1048)
		(end 116.392452 -51.1048)
		(stroke
			(width 0.2)
			(type default)
		)
		(fill no)
		(layer "In8.Cu")
	)
	(gr_circle
		(center 115.503452 -50.3428)
		(end 116.392452 -50.3428)
		(stroke
			(width 0.2)
			(type default)
		)
		(fill no)
		(layer "In8.Cu")
	)
	(gr_circle
		(center 115.503452 -49.5808)
		(end 116.392452 -49.5808)
		(stroke
			(width 0.2)
			(type default)
		)
		(fill no)
		(layer "In8.Cu")
	)
	(gr_circle
		(center 115.503452 -48.8188)
		(end 116.392452 -48.8188)
		(stroke
			(width 0.2)
			(type default)
		)
		(fill no)
		(layer "In8.Cu")
	)
	(gr_circle
		(center 115.503452 -48.0568)
		(end 116.392452 -48.0568)
		(stroke
			(width 0.2)
			(type default)
		)
		(fill no)
		(layer "In8.Cu")
	)
	(gr_circle
		(center 115.503452 -39.8272)
		(end 116.392452 -39.8272)
		(stroke
			(width 0.2)
			(type default)
		)
		(fill no)
		(layer "In8.Cu")
	)
	(gr_circle
		(center 115.503452 -39.0652)
		(end 116.392452 -39.0652)
		(stroke
			(width 0.2)
			(type default)
		)
		(fill no)
		(layer "In8.Cu")
	)
	(gr_circle
		(center 115.503452 -38.3032)
		(end 116.392452 -38.3032)
		(stroke
			(width 0.2)
			(type default)
		)
		(fill no)
		(layer "In8.Cu")
	)
	(gr_circle
		(center 115.503452 -37.5412)
		(end 116.392452 -37.5412)
		(stroke
			(width 0.2)
			(type default)
		)
		(fill no)
		(layer "In8.Cu")
	)
	(gr_circle
		(center 115.503452 -36.7792)
		(end 116.392452 -36.7792)
		(stroke
			(width 0.2)
			(type default)
		)
		(fill no)
		(layer "In8.Cu")
	)
	(gr_circle
		(center 115.503452 -28.5496)
		(end 116.392452 -28.5496)
		(stroke
			(width 0.2)
			(type default)
		)
		(fill no)
		(layer "In8.Cu")
	)
	(gr_circle
		(center 115.503452 -27.7876)
		(end 116.392452 -27.7876)
		(stroke
			(width 0.2)
			(type default)
		)
		(fill no)
		(layer "In8.Cu")
	)
	(gr_circle
		(center 115.503452 -27.0256)
		(end 116.392452 -27.0256)
		(stroke
			(width 0.2)
			(type default)
		)
		(fill no)
		(layer "In8.Cu")
	)
	(gr_circle
		(center 115.503452 -26.2636)
		(end 116.392452 -26.2636)
		(stroke
			(width 0.2)
			(type default)
		)
		(fill no)
		(layer "In8.Cu")
	)
	(gr_circle
		(center 115.503452 -25.5016)
		(end 116.392452 -25.5016)
		(stroke
			(width 0.2)
			(type default)
		)
		(fill no)
		(layer "In8.Cu")
	)
	(gr_circle
		(center 115.503452 -17.272)
		(end 116.392452 -17.272)
		(stroke
			(width 0.2)
			(type default)
		)
		(fill no)
		(layer "In8.Cu")
	)
	(gr_circle
		(center 115.503452 -16.51)
		(end 116.392452 -16.51)
		(stroke
			(width 0.2)
			(type default)
		)
		(fill no)
		(layer "In8.Cu")
	)
	(gr_circle
		(center 115.503452 -15.748)
		(end 116.392452 -15.748)
		(stroke
			(width 0.2)
			(type default)
		)
		(fill no)
		(layer "In8.Cu")
	)
	(gr_circle
		(center 115.503452 -14.986)
		(end 116.392452 -14.986)
		(stroke
			(width 0.2)
			(type default)
		)
		(fill no)
		(layer "In8.Cu")
	)
	(gr_circle
		(center 115.503452 -14.224)
		(end 116.392452 -14.224)
		(stroke
			(width 0.2)
			(type default)
		)
		(fill no)
		(layer "In8.Cu")
	)
	(gr_line
		(start 122.8344 -79.883)
		(end 123.4694 -80.518)
		(stroke
			(width 1.016)
			(type default)
		)
		(layer "In8.Cu")
	)
	(gr_line
		(start 122.8344 -46.863)
		(end 122.8344 -79.883)
		(stroke
			(width 1.016)
			(type default)
		)
		(layer "In8.Cu")
	)
	(gr_line
		(start 122.8344 -46.863)
		(end 122.8344 -13.081)
		(stroke
			(width 1.016)
			(type default)
		)
		(layer "In8.Cu")
	)
	(gr_line
		(start 122.8344 -13.081)
		(end 123.4694 -12.446)
		(stroke
			(width 1.016)
			(type default)
		)
		(layer "In8.Cu")
	)
	(gr_line
		(start 123.3424 -46.355)
		(end 122.8344 -46.863)
		(stroke
			(width 1.016)
			(type default)
		)
		(layer "In8.Cu")
	)
	(gr_line
		(start 123.3424 -46.355)
		(end 122.8344 -45.847)
		(stroke
			(width 1.016)
			(type default)
		)
		(layer "In8.Cu")
	)
	(gr_line
		(start 123.4694 -80.518)
		(end 136.23925 -80.518)
		(stroke
			(width 1.016)
			(type default)
		)
		(layer "In8.Cu")
	)
	(gr_line
		(start 136.23925 -80.518)
		(end 136.86663 -79.89062)
		(stroke
			(width 1.016)
			(type default)
		)
		(layer "In8.Cu")
	)
	(gr_line
		(start 136.86663 -79.89062)
		(end 136.86663 -68.303902)
		(stroke
			(width 1.016)
			(type default)
		)
		(layer "In8.Cu")
	)
	(gr_line
		(start 136.86663 -68.303902)
		(end 137.855706 -67.314826)
		(stroke
			(width 1.016)
			(type default)
		)
		(layer "In8.Cu")
	)
	(gr_line
		(start 138.049 -38.862)
		(end 139.1666 -39.9796)
		(stroke
			(width 1.016)
			(type default)
		)
		(layer "In8.Cu")
	)
	(gr_line
		(start 138.049 -33.8328)
		(end 138.049 -38.862)
		(stroke
			(width 1.016)
			(type default)
		)
		(layer "In8.Cu")
	)
	(gr_line
		(start 138.2268 -38.2524)
		(end 147.066 -38.2524)
		(stroke
			(width 1.016)
			(type default)
		)
		(layer "In8.Cu")
	)
	(gr_line
		(start 138.2268 -37.6682)
		(end 147.066 -37.6682)
		(stroke
			(width 1.016)
			(type default)
		)
		(layer "In8.Cu")
	)
	(gr_line
		(start 138.2522 -37.0586)
		(end 147.0914 -37.0586)
		(stroke
			(width 1.016)
			(type default)
		)
		(layer "In8.Cu")
	)
	(gr_line
		(start 138.2522 -34.8742)
		(end 147.0914 -34.8742)
		(stroke
			(width 1.016)
			(type default)
		)
		(layer "In8.Cu")
	)
	(gr_line
		(start 138.2776 -36.3474)
		(end 147.1168 -36.3474)
		(stroke
			(width 1.016)
			(type default)
		)
		(layer "In8.Cu")
	)
	(gr_line
		(start 138.303 -35.6616)
		(end 147.1422 -35.6616)
		(stroke
			(width 1.016)
			(type default)
		)
		(layer "In8.Cu")
	)
	(gr_line
		(start 138.34872 -33.53308)
		(end 138.049 -33.8328)
		(stroke
			(width 1.016)
			(type default)
		)
		(layer "In8.Cu")
	)
	(gr_line
		(start 138.3538 -34.2392)
		(end 147.193 -34.2392)
		(stroke
			(width 1.016)
			(type default)
		)
		(layer "In8.Cu")
	)
	(gr_line
		(start 138.3792 -38.7604)
		(end 147.2184 -38.7604)
		(stroke
			(width 1.016)
			(type default)
		)
		(layer "In8.Cu")
	)
	(gr_line
		(start 138.6078 -34.2646)
		(end 138.6078 -39.2938)
		(stroke
			(width 1.016)
			(type default)
		)
		(layer "In8.Cu")
	)
	(gr_line
		(start 139.0904 -34.5694)
		(end 139.0904 -39.5986)
		(stroke
			(width 1.016)
			(type default)
		)
		(layer "In8.Cu")
	)
	(gr_line
		(start 139.1666 -39.9796)
		(end 141.7066 -39.9796)
		(stroke
			(width 1.016)
			(type default)
		)
		(layer "In8.Cu")
	)
	(gr_line
		(start 141.7066 -39.9796)
		(end 142.6464 -40.9194)
		(stroke
			(width 1.016)
			(type default)
		)
		(layer "In8.Cu")
	)
	(gr_line
		(start 141.8844 -12.446)
		(end 142.6464 -13.208)
		(stroke
			(width 1.016)
			(type default)
		)
		(layer "In8.Cu")
	)
	(gr_line
		(start 142.3924 -46.355)
		(end 123.3424 -46.355)
		(stroke
			(width 1.016)
			(type default)
		)
		(layer "In8.Cu")
	)
	(gr_line
		(start 142.3924 -46.355)
		(end 142.6464 -46.609)
		(stroke
			(width 1.016)
			(type default)
		)
		(layer "In8.Cu")
	)
	(gr_line
		(start 142.621 -32.6644)
		(end 141.5034 -33.782)
		(stroke
			(width 1.016)
			(type default)
		)
		(layer "In8.Cu")
	)
	(gr_line
		(start 142.621 -32.6644)
		(end 143.7386 -33.782)
		(stroke
			(width 1.016)
			(type default)
		)
		(layer "In8.Cu")
	)
	(gr_line
		(start 142.6464 -47.498)
		(end 141.5288 -46.3804)
		(stroke
			(width 1.016)
			(type default)
		)
		(layer "In8.Cu")
	)
	(gr_line
		(start 142.6464 -45.1612)
		(end 141.5288 -46.2788)
		(stroke
			(width 1.016)
			(type default)
		)
		(layer "In8.Cu")
	)
	(gr_line
		(start 142.6464 -33.909)
		(end 142.6464 -67.437)
		(stroke
			(width 1.016)
			(type default)
		)
		(layer "In8.Cu")
	)
	(gr_line
		(start 142.6464 -33.53308)
		(end 138.34872 -33.53308)
		(stroke
			(width 1.016)
			(type default)
		)
		(layer "In8.Cu")
	)
	(gr_line
		(start 142.6464 -33.53308)
		(end 147.35048 -33.53308)
		(stroke
			(width 1.016)
			(type default)
		)
		(layer "In8.Cu")
	)
	(gr_line
		(start 142.6464 -13.208)
		(end 142.6464 -33.53308)
		(stroke
			(width 1.016)
			(type default)
		)
		(layer "In8.Cu")
	)
	(gr_line
		(start 143.4084 -12.446)
		(end 142.6464 -13.208)
		(stroke
			(width 1.016)
			(type default)
		)
		(layer "In8.Cu")
	)
	(gr_circle
		(center 143.533114 -76.858368)
		(end 144.422114 -76.858368)
		(stroke
			(width 0.2)
			(type default)
		)
		(fill no)
		(layer "In8.Cu")
	)
	(gr_line
		(start 143.5862 -39.9796)
		(end 142.6464 -40.9194)
		(stroke
			(width 1.016)
			(type default)
		)
		(layer "In8.Cu")
	)
	(gr_line
		(start 144.4244 -39.3192)
		(end 139.3952 -39.3192)
		(stroke
			(width 1.016)
			(type default)
		)
		(layer "In8.Cu")
	)
	(gr_circle
		(center 144.892522 -76.886308)
		(end 145.781522 -76.886308)
		(stroke
			(width 0.2)
			(type default)
		)
		(fill no)
		(layer "In8.Cu")
	)
	(gr_line
		(start 145.5928 -39.8272)
		(end 140.5636 -39.8272)
		(stroke
			(width 1.016)
			(type default)
		)
		(layer "In8.Cu")
	)
	(gr_line
		(start 146.05 -34.544)
		(end 146.05 -39.5732)
		(stroke
			(width 1.016)
			(type default)
		)
		(layer "In8.Cu")
	)
	(gr_line
		(start 146.2024 -39.4208)
		(end 141.1732 -39.4208)
		(stroke
			(width 1.016)
			(type default)
		)
		(layer "In8.Cu")
	)
	(gr_line
		(start 146.2532 -39.9796)
		(end 143.5862 -39.9796)
		(stroke
			(width 1.016)
			(type default)
		)
		(layer "In8.Cu")
	)
	(gr_line
		(start 146.6596 -34.1884)
		(end 146.6596 -39.2176)
		(stroke
			(width 1.016)
			(type default)
		)
		(layer "In8.Cu")
	)
	(gr_line
		(start 147.2692 -33.8582)
		(end 147.2692 -38.8874)
		(stroke
			(width 1.016)
			(type default)
		)
		(layer "In8.Cu")
	)
	(gr_line
		(start 147.35048 -33.53308)
		(end 147.8534 -34.036)
		(stroke
			(width 1.016)
			(type default)
		)
		(layer "In8.Cu")
	)
	(gr_line
		(start 147.8534 -38.3794)
		(end 146.2532 -39.9796)
		(stroke
			(width 1.016)
			(type default)
		)
		(layer "In8.Cu")
	)
	(gr_line
		(start 147.8534 -34.036)
		(end 147.8534 -38.3794)
		(stroke
			(width 1.016)
			(type default)
		)
		(layer "In8.Cu")
	)
	(gr_line
		(start 148.668232 -67.314826)
		(end 137.855706 -67.314826)
		(stroke
			(width 1.016)
			(type default)
		)
		(layer "In8.Cu")
	)
	(gr_line
		(start 148.668232 -67.314826)
		(end 149.982174 -67.314826)
		(stroke
			(width 1.016)
			(type default)
		)
		(layer "In8.Cu")
	)
	(gr_line
		(start 149.3774 -66.605658)
		(end 148.668232 -67.314826)
		(stroke
			(width 1.016)
			(type default)
		)
		(layer "In8.Cu")
	)
	(gr_line
		(start 149.3774 -60.2234)
		(end 149.3774 -66.605658)
		(stroke
			(width 1.016)
			(type default)
		)
		(layer "In8.Cu")
	)
	(gr_line
		(start 149.421342 -66.605658)
		(end 149.3774 -66.605658)
		(stroke
			(width 1.016)
			(type default)
		)
		(layer "In8.Cu")
	)
	(gr_line
		(start 149.86 -79.756)
		(end 149.86 -76.2)
		(stroke
			(width 1.016)
			(type default)
		)
		(layer "In8.Cu")
	)
	(gr_line
		(start 149.86 -76.2)
		(end 151.511 -74.549)
		(stroke
			(width 1.016)
			(type default)
		)
		(layer "In8.Cu")
	)
	(gr_line
		(start 149.982174 -67.314826)
		(end 150.0378 -67.2592)
		(stroke
			(width 1.016)
			(type default)
		)
		(layer "In8.Cu")
	)
	(gr_line
		(start 149.987 -64.6176)
		(end 156.2354 -58.3692)
		(stroke
			(width 2.032)
			(type default)
		)
		(layer "In8.Cu")
	)
	(gr_line
		(start 149.987 -60.6298)
		(end 149.987 -64.6176)
		(stroke
			(width 1.016)
			(type default)
		)
		(layer "In8.Cu")
	)
	(gr_circle
		(center 150.033736 -79.7052)
		(end 150.922736 -79.7052)
		(stroke
			(width 0.2)
			(type default)
		)
		(fill no)
		(layer "In8.Cu")
	)
	(gr_circle
		(center 150.033736 -78.9432)
		(end 150.922736 -78.9432)
		(stroke
			(width 0.2)
			(type default)
		)
		(fill no)
		(layer "In8.Cu")
	)
	(gr_line
		(start 150.0378 -67.2592)
		(end 150.0378 -65.1002)
		(stroke
			(width 1.016)
			(type default)
		)
		(layer "In8.Cu")
	)
	(gr_line
		(start 150.0378 -65.1002)
		(end 157.8864 -57.2516)
		(stroke
			(width 1.016)
			(type default)
		)
		(layer "In8.Cu")
	)
	(gr_line
		(start 150.114 -80.01)
		(end 149.86 -79.756)
		(stroke
			(width 1.016)
			(type default)
		)
		(layer "In8.Cu")
	)
	(gr_line
		(start 150.495 -79.121)
		(end 150.749 -79.375)
		(stroke
			(width 1.016)
			(type default)
		)
		(layer "In8.Cu")
	)
	(gr_line
		(start 150.495 -76.581)
		(end 150.495 -79.121)
		(stroke
			(width 1.016)
			(type default)
		)
		(layer "In8.Cu")
	)
	(gr_line
		(start 150.5966 -62.3062)
		(end 150.7236 -62.3062)
		(stroke
			(width 2.032)
			(type default)
		)
		(layer "In8.Cu")
	)
	(gr_line
		(start 150.5966 -61.468)
		(end 150.5966 -62.3062)
		(stroke
			(width 2.032)
			(type default)
		)
		(layer "In8.Cu")
	)
	(gr_line
		(start 150.7236 -62.3062)
		(end 154.1526 -58.8772)
		(stroke
			(width 2.032)
			(type default)
		)
		(layer "In8.Cu")
	)
	(gr_line
		(start 150.749 -79.375)
		(end 151.003 -79.375)
		(stroke
			(width 1.016)
			(type default)
		)
		(layer "In8.Cu")
	)
	(gr_line
		(start 150.749 -78.613)
		(end 150.876 -78.74)
		(stroke
			(width 1.016)
			(type default)
		)
		(layer "In8.Cu")
	)
	(gr_line
		(start 150.749 -76.073)
		(end 150.749 -78.613)
		(stroke
			(width 1.016)
			(type default)
		)
		(layer "In8.Cu")
	)
	(gr_circle
		(center 150.801832 -60.917582)
		(end 151.690832 -60.917582)
		(stroke
			(width 0.2)
			(type default)
		)
		(fill no)
		(layer "In8.Cu")
	)
	(gr_line
		(start 151.003 -79.375)
		(end 151.257 -79.121)
		(stroke
			(width 1.016)
			(type default)
		)
		(layer "In8.Cu")
	)
	(gr_line
		(start 151.13 -75.692)
		(end 150.749 -76.073)
		(stroke
			(width 1.016)
			(type default)
		)
		(layer "In8.Cu")
	)
	(gr_line
		(start 151.257 -80.01)
		(end 150.114 -80.01)
		(stroke
			(width 1.016)
			(type default)
		)
		(layer "In8.Cu")
	)
	(gr_line
		(start 151.257 -79.121)
		(end 151.257 -75.692)
		(stroke
			(width 1.016)
			(type default)
		)
		(layer "In8.Cu")
	)
	(gr_line
		(start 151.257 -75.692)
		(end 151.13 -75.692)
		(stroke
			(width 1.016)
			(type default)
		)
		(layer "In8.Cu")
	)
	(gr_line
		(start 151.511 -74.549)
		(end 151.892 -74.93)
		(stroke
			(width 1.016)
			(type default)
		)
		(layer "In8.Cu")
	)
	(gr_line
		(start 151.511 -73.0504)
		(end 151.511 -74.549)
		(stroke
			(width 1.016)
			(type default)
		)
		(layer "In8.Cu")
	)
	(gr_line
		(start 151.5364 -73.025)
		(end 151.511 -73.0504)
		(stroke
			(width 1.016)
			(type default)
		)
		(layer "In8.Cu")
	)
	(gr_circle
		(center 151.563832 -60.917582)
		(end 152.452832 -60.917582)
		(stroke
			(width 0.2)
			(type default)
		)
		(fill no)
		(layer "In8.Cu")
	)
	(gr_line
		(start 151.892 -79.375)
		(end 151.257 -80.01)
		(stroke
			(width 1.016)
			(type default)
		)
		(layer "In8.Cu")
	)
	(gr_line
		(start 151.892 -74.93)
		(end 151.892 -79.375)
		(stroke
			(width 1.016)
			(type default)
		)
		(layer "In8.Cu")
	)
	(gr_line
		(start 151.892 -74.93)
		(end 151.892 -73.3806)
		(stroke
			(width 1.016)
			(type default)
		)
		(layer "In8.Cu")
	)
	(gr_line
		(start 151.892 -73.3806)
		(end 151.5364 -73.025)
		(stroke
			(width 1.016)
			(type default)
		)
		(layer "In8.Cu")
	)
	(gr_line
		(start 152.908 -56.6928)
		(end 149.3774 -60.2234)
		(stroke
			(width 1.016)
			(type default)
		)
		(layer "In8.Cu")
	)
	(gr_line
		(start 153.3652 -57.2516)
		(end 149.987 -60.6298)
		(stroke
			(width 1.016)
			(type default)
		)
		(layer "In8.Cu")
	)
	(gr_line
		(start 153.924 -58.1406)
		(end 150.5966 -61.468)
		(stroke
			(width 2.032)
			(type default)
		)
		(layer "In8.Cu")
	)
	(gr_line
		(start 156.2354 -58.3692)
		(end 156.2354 -58.1406)
		(stroke
			(width 2.032)
			(type default)
		)
		(layer "In8.Cu")
	)
	(gr_line
		(start 156.2354 -58.1406)
		(end 153.924 -58.1406)
		(stroke
			(width 2.032)
			(type default)
		)
		(layer "In8.Cu")
	)
	(gr_line
		(start 156.980382 -12.446)
		(end 123.4694 -12.446)
		(stroke
			(width 1.016)
			(type default)
		)
		(layer "In8.Cu")
	)
	(gr_line
		(start 157.8864 -57.2516)
		(end 153.3652 -57.2516)
		(stroke
			(width 1.016)
			(type default)
		)
		(layer "In8.Cu")
	)
	(gr_circle
		(center 158.369 -96.266)
		(end 159.258 -96.266)
		(stroke
			(width 0.2)
			(type default)
		)
		(fill no)
		(layer "In8.Cu")
	)
	(gr_line
		(start 159.3342 -56.6928)
		(end 149.421342 -66.605658)
		(stroke
			(width 1.016)
			(type default)
		)
		(layer "In8.Cu")
	)
	(gr_line
		(start 159.3342 -56.6928)
		(end 152.908 -56.6928)
		(stroke
			(width 1.016)
			(type default)
		)
		(layer "In8.Cu")
	)
	(gr_line
		(start 160.4772 -55.5498)
		(end 159.3342 -56.6928)
		(stroke
			(width 1.016)
			(type default)
		)
		(layer "In8.Cu")
	)
	(gr_circle
		(center 160.575244 -86.084918)
		(end 161.464244 -86.084918)
		(stroke
			(width 0.2)
			(type default)
		)
		(fill no)
		(layer "In8.Cu")
	)
	(gr_line
		(start 160.6804 -27.182318)
		(end 161.946082 -28.448)
		(stroke
			(width 1.016)
			(type default)
		)
		(layer "In8.Cu")
	)
	(gr_line
		(start 160.6804 -16.146018)
		(end 156.980382 -12.446)
		(stroke
			(width 1.016)
			(type default)
		)
		(layer "In8.Cu")
	)
	(gr_line
		(start 160.6804 -16.146018)
		(end 160.6804 -27.182318)
		(stroke
			(width 1.016)
			(type default)
		)
		(layer "In8.Cu")
	)
	(gr_line
		(start 161.946082 -28.448)
		(end 209.1944 -28.448)
		(stroke
			(width 1.016)
			(type default)
		)
		(layer "In8.Cu")
	)
	(gr_circle
		(center 166.5224 -60.3758)
		(end 167.4114 -60.3758)
		(stroke
			(width 0.2)
			(type default)
		)
		(fill no)
		(layer "In8.Cu")
	)
	(gr_circle
		(center 167.2844 -60.3758)
		(end 168.1734 -60.3758)
		(stroke
			(width 0.2)
			(type default)
		)
		(fill no)
		(layer "In8.Cu")
	)
	(gr_line
		(start 172.174662 -50.696622)
		(end 172.174662 -43.570398)
		(stroke
			(width 1.016)
			(type default)
		)
		(layer "In8.Cu")
	)
	(gr_line
		(start 172.174662 -43.570398)
		(end 173.915832 -41.829228)
		(stroke
			(width 1.016)
			(type default)
		)
		(layer "In8.Cu")
	)
	(gr_line
		(start 172.583348 -51.105308)
		(end 172.174662 -50.696622)
		(stroke
			(width 1.016)
			(type default)
		)
		(layer "In8.Cu")
	)
	(gr_line
		(start 173.915832 -41.829228)
		(end 191.747394 -41.829228)
		(stroke
			(width 1.016)
			(type default)
		)
		(layer "In8.Cu")
	)
	(gr_line
		(start 173.980348 -51.105308)
		(end 172.583348 -51.105308)
		(stroke
			(width 1.016)
			(type default)
		)
		(layer "In8.Cu")
	)
	(gr_line
		(start 173.980348 -51.105308)
		(end 176.302162 -53.427122)
		(stroke
			(width 1.016)
			(type default)
		)
		(layer "In8.Cu")
	)
	(gr_circle
		(center 174.9044 -82.296)
		(end 175.7934 -82.296)
		(stroke
			(width 0.2)
			(type default)
		)
		(fill no)
		(layer "In8.Cu")
	)
	(gr_line
		(start 175.133 -55.9816)
		(end 160.0454 -55.9816)
		(stroke
			(width 1.016)
			(type default)
		)
		(layer "In8.Cu")
	)
	(gr_line
		(start 175.5648 -55.5498)
		(end 160.4772 -55.5498)
		(stroke
			(width 1.016)
			(type default)
		)
		(layer "In8.Cu")
	)
	(gr_line
		(start 175.5648 -55.5498)
		(end 175.133 -55.9816)
		(stroke
			(width 1.016)
			(type default)
		)
		(layer "In8.Cu")
	)
	(gr_circle
		(center 175.6664 -82.296)
		(end 176.5554 -82.296)
		(stroke
			(width 0.2)
			(type default)
		)
		(fill no)
		(layer "In8.Cu")
	)
	(gr_line
		(start 176.302162 -54.812438)
		(end 175.5648 -55.5498)
		(stroke
			(width 1.016)
			(type default)
		)
		(layer "In8.Cu")
	)
	(gr_line
		(start 176.302162 -53.427122)
		(end 176.302162 -54.812438)
		(stroke
			(width 1.016)
			(type default)
		)
		(layer "In8.Cu")
	)
	(gr_circle
		(center 177.1904 -82.296)
		(end 178.0794 -82.296)
		(stroke
			(width 0.2)
			(type default)
		)
		(fill no)
		(layer "In8.Cu")
	)
	(gr_circle
		(center 177.9524 -82.296)
		(end 178.8414 -82.296)
		(stroke
			(width 0.2)
			(type default)
		)
		(fill no)
		(layer "In8.Cu")
	)
	(gr_circle
		(center 178.87696 -46.99)
		(end 179.76596 -46.99)
		(stroke
			(width 0.2)
			(type default)
		)
		(fill no)
		(layer "In8.Cu")
	)
	(gr_line
		(start 182.1434 -50.894996)
		(end 182.1434 -50.419)
		(stroke
			(width 1.016)
			(type default)
		)
		(layer "In8.Cu")
	)
	(gr_line
		(start 182.1434 -50.419)
		(end 182.1434 -47.879)
		(stroke
			(width 1.016)
			(type default)
		)
		(layer "In8.Cu")
	)
	(gr_line
		(start 182.1434 -47.879)
		(end 182.1434 -46.609)
		(stroke
			(width 1.016)
			(type default)
		)
		(layer "In8.Cu")
	)
	(gr_line
		(start 182.1434 -46.609)
		(end 185.8264 -42.926)
		(stroke
			(width 1.016)
			(type default)
		)
		(layer "In8.Cu")
	)
	(gr_circle
		(center 182.215536 -69.4436)
		(end 183.104536 -69.4436)
		(stroke
			(width 0.2)
			(type default)
		)
		(fill no)
		(layer "In8.Cu")
	)
	(gr_line
		(start 182.815484 -51.56708)
		(end 182.1434 -50.894996)
		(stroke
			(width 1.016)
			(type default)
		)
		(layer "In8.Cu")
	)
	(gr_circle
		(center 184.8104 -68.58)
		(end 185.6994 -68.58)
		(stroke
			(width 0.2)
			(type default)
		)
		(fill no)
		(layer "In8.Cu")
	)
	(gr_circle
		(center 185.5724 -68.58)
		(end 186.4614 -68.58)
		(stroke
			(width 0.2)
			(type default)
		)
		(fill no)
		(layer "In8.Cu")
	)
	(gr_line
		(start 185.8264 -42.926)
		(end 189.847982 -42.926)
		(stroke
			(width 1.016)
			(type default)
		)
		(layer "In8.Cu")
	)
	(gr_line
		(start 189.847982 -42.926)
		(end 193.576448 -46.654466)
		(stroke
			(width 1.016)
			(type default)
		)
		(layer "In8.Cu")
	)
	(gr_line
		(start 191.747394 -41.829228)
		(end 197.797166 -47.879)
		(stroke
			(width 1.016)
			(type default)
		)
		(layer "In8.Cu")
	)
	(gr_line
		(start 193.031618 -51.56708)
		(end 182.815484 -51.56708)
		(stroke
			(width 1.016)
			(type default)
		)
		(layer "In8.Cu")
	)
	(gr_line
		(start 193.576448 -51.02225)
		(end 193.031618 -51.56708)
		(stroke
			(width 1.016)
			(type default)
		)
		(layer "In8.Cu")
	)
	(gr_line
		(start 193.576448 -47.879)
		(end 193.576448 -51.02225)
		(stroke
			(width 1.016)
			(type default)
		)
		(layer "In8.Cu")
	)
	(gr_line
		(start 193.576448 -46.654466)
		(end 193.576448 -47.879)
		(stroke
			(width 1.016)
			(type default)
		)
		(layer "In8.Cu")
	)
	(gr_line
		(start 197.797166 -47.879)
		(end 210.0834 -47.879)
		(stroke
			(width 1.016)
			(type default)
		)
		(layer "In8.Cu")
	)
	(gr_circle
		(center 208.810098 -51.049936)
		(end 210.20913 -51.049936)
		(stroke
			(width 0.2)
			(type default)
		)
		(fill no)
		(layer "In8.Cu")
	)
	(gr_line
		(start 209.1944 -28.448)
		(end 210.9724 -30.226)
		(stroke
			(width 1.016)
			(type default)
		)
		(layer "In8.Cu")
	)
	(gr_line
		(start 210.9724 -46.99)
		(end 210.0834 -47.879)
		(stroke
			(width 1.016)
			(type default)
		)
		(layer "In8.Cu")
	)
	(gr_line
		(start 210.9724 -30.226)
		(end 210.9724 -46.99)
		(stroke
			(width 1.016)
			(type default)
		)
		(layer "In8.Cu")
	)
	(gr_line
		(start 229.362 -46.99)
		(end 230.251 -47.879)
		(stroke
			(width 1.016)
			(type default)
		)
		(layer "In8.Cu")
	)
	(gr_line
		(start 229.362 -30.226)
		(end 229.362 -46.99)
		(stroke
			(width 1.016)
			(type default)
		)
		(layer "In8.Cu")
	)
	(gr_line
		(start 230.251 -47.879)
		(end 242.963954 -47.879)
		(stroke
			(width 1.016)
			(type default)
		)
		(layer "In8.Cu")
	)
	(gr_line
		(start 231.14 -28.448)
		(end 229.362 -30.226)
		(stroke
			(width 1.016)
			(type default)
		)
		(layer "In8.Cu")
	)
	(gr_circle
		(center 238.810038 -51.049936)
		(end 240.20907 -51.049936)
		(stroke
			(width 0.2)
			(type default)
		)
		(fill no)
		(layer "In8.Cu")
	)
	(gr_line
		(start 246.757952 -51.02225)
		(end 247.302782 -51.56708)
		(stroke
			(width 1.016)
			(type default)
		)
		(layer "In8.Cu")
	)
	(gr_line
		(start 246.757952 -47.879)
		(end 246.757952 -51.02225)
		(stroke
			(width 1.016)
			(type default)
		)
		(layer "In8.Cu")
	)
	(gr_line
		(start 246.757952 -46.654466)
		(end 246.757952 -47.879)
		(stroke
			(width 1.016)
			(type default)
		)
		(layer "In8.Cu")
	)
	(gr_line
		(start 246.757952 -46.654466)
		(end 250.867418 -42.545)
		(stroke
			(width 1.016)
			(type default)
		)
		(layer "In8.Cu")
	)
	(gr_line
		(start 248.993406 -41.849548)
		(end 242.963954 -47.879)
		(stroke
			(width 1.016)
			(type default)
		)
		(layer "In8.Cu")
	)
	(gr_line
		(start 250.486418 -42.926)
		(end 246.757952 -46.654466)
		(stroke
			(width 1.016)
			(type default)
		)
		(layer "In8.Cu")
	)
	(gr_line
		(start 250.867418 -42.545)
		(end 256.07899 -42.545)
		(stroke
			(width 1.016)
			(type default)
		)
		(layer "In8.Cu")
	)
	(gr_line
		(start 254.508 -42.926)
		(end 250.486418 -42.926)
		(stroke
			(width 1.016)
			(type default)
		)
		(layer "In8.Cu")
	)
	(gr_line
		(start 254.508 -42.926)
		(end 258.191 -46.609)
		(stroke
			(width 1.016)
			(type default)
		)
		(layer "In8.Cu")
	)
	(gr_line
		(start 255.397 -42.926)
		(end 250.486418 -42.926)
		(stroke
			(width 1.016)
			(type default)
		)
		(layer "In8.Cu")
	)
	(gr_line
		(start 256.07899 -42.545)
		(end 258.61899 -45.085)
		(stroke
			(width 1.016)
			(type default)
		)
		(layer "In8.Cu")
	)
	(gr_line
		(start 256.9718 -41.91)
		(end 272.5928 -41.91)
		(stroke
			(width 1.016)
			(type default)
		)
		(layer "In8.Cu")
	)
	(gr_line
		(start 257.37312 -51.56708)
		(end 247.302782 -51.56708)
		(stroke
			(width 1.016)
			(type default)
		)
		(layer "In8.Cu")
	)
	(gr_line
		(start 257.518916 -51.56708)
		(end 258.191 -50.894996)
		(stroke
			(width 1.016)
			(type default)
		)
		(layer "In8.Cu")
	)
	(gr_line
		(start 257.556 -45.085)
		(end 255.397 -42.926)
		(stroke
			(width 1.016)
			(type default)
		)
		(layer "In8.Cu")
	)
	(gr_line
		(start 257.6068 -43.561)
		(end 255.955292 -41.909492)
		(stroke
			(width 1.016)
			(type default)
		)
		(layer "In8.Cu")
	)
	(gr_line
		(start 258.191 -50.894996)
		(end 258.191 -50.419)
		(stroke
			(width 1.016)
			(type default)
		)
		(layer "In8.Cu")
	)
	(gr_line
		(start 258.191 -50.419)
		(end 258.191 -47.879)
		(stroke
			(width 1.016)
			(type default)
		)
		(layer "In8.Cu")
	)
	(gr_line
		(start 258.191 -47.879)
		(end 258.191 -46.609)
		(stroke
			(width 1.016)
			(type default)
		)
		(layer "In8.Cu")
	)
	(gr_line
		(start 258.191 -46.609)
		(end 254.508 -42.926)
		(stroke
			(width 1.016)
			(type default)
		)
		(layer "In8.Cu")
	)
	(gr_line
		(start 258.191 -46.609)
		(end 258.191 -45.72)
		(stroke
			(width 1.016)
			(type default)
		)
		(layer "In8.Cu")
	)
	(gr_line
		(start 258.191 -45.72)
		(end 257.556 -45.085)
		(stroke
			(width 1.016)
			(type default)
		)
		(layer "In8.Cu")
	)
	(gr_line
		(start 258.572 -44.5262)
		(end 256.920492 -42.874692)
		(stroke
			(width 1.016)
			(type default)
		)
		(layer "In8.Cu")
	)
	(gr_line
		(start 258.61899 -47.03699)
		(end 260.51383 -48.93183)
		(stroke
			(width 1.016)
			(type default)
		)
		(layer "In8.Cu")
	)
	(gr_line
		(start 258.61899 -45.085)
		(end 257.556 -45.085)
		(stroke
			(width 1.016)
			(type default)
		)
		(layer "In8.Cu")
	)
	(gr_line
		(start 258.61899 -45.085)
		(end 258.61899 -47.03699)
		(stroke
			(width 1.016)
			(type default)
		)
		(layer "In8.Cu")
	)
	(gr_line
		(start 258.623308 -43.561508)
		(end 256.9718 -41.91)
		(stroke
			(width 1.016)
			(type default)
		)
		(layer "In8.Cu")
	)
	(gr_line
		(start 258.757166 -42.697908)
		(end 266.6238 -42.697908)
		(stroke
			(width 1.27)
			(type default)
		)
		(layer "In8.Cu")
	)
	(gr_line
		(start 258.909566 -43.078908)
		(end 266.7762 -43.078908)
		(stroke
			(width 1.27)
			(type default)
		)
		(layer "In8.Cu")
	)
	(gr_line
		(start 258.934966 -43.561508)
		(end 267.0556 -43.561508)
		(stroke
			(width 1.27)
			(type default)
		)
		(layer "In8.Cu")
	)
	(gr_line
		(start 259.188966 -43.561508)
		(end 258.623308 -43.561508)
		(stroke
			(width 1.016)
			(type default)
		)
		(layer "In8.Cu")
	)
	(gr_line
		(start 259.334 -46.482)
		(end 259.334 -45.847)
		(stroke
			(width 1.27)
			(type default)
		)
		(layer "In8.Cu")
	)
	(gr_line
		(start 259.334 -45.847)
		(end 259.461 -45.974)
		(stroke
			(width 1.27)
			(type default)
		)
		(layer "In8.Cu")
	)
	(gr_line
		(start 259.461 -45.974)
		(end 268.224 -45.974)
		(stroke
			(width 1.27)
			(type default)
		)
		(layer "In8.Cu")
	)
	(gr_circle
		(center 260.2484 -46.99)
		(end 261.1374 -46.99)
		(stroke
			(width 0.2)
			(type default)
		)
		(fill no)
		(layer "In8.Cu")
	)
	(gr_line
		(start 260.35 -46.736)
		(end 261.366 -47.752)
		(stroke
			(width 1.27)
			(type default)
		)
		(layer "In8.Cu")
	)
	(gr_line
		(start 260.509766 -44.475908)
		(end 268.6304 -44.475908)
		(stroke
			(width 1.27)
			(type default)
		)
		(layer "In8.Cu")
	)
	(gr_line
		(start 260.51383 -85.493606)
		(end 260.51383 -78.47457)
		(stroke
			(width 1.016)
			(type default)
		)
		(layer "In8.Cu")
	)
	(gr_line
		(start 260.51383 -78.47457)
		(end 260.8834 -78.105)
		(stroke
			(width 1.016)
			(type default)
		)
		(layer "In8.Cu")
	)
	(gr_line
		(start 260.51383 -48.93183)
		(end 262.820912 -51.238912)
		(stroke
			(width 1.016)
			(type default)
		)
		(layer "In8.Cu")
	)
	(gr_line
		(start 260.7564 -44.196)
		(end 258.42087 -44.196)
		(stroke
			(width 1.016)
			(type default)
		)
		(layer "In8.Cu")
	)
	(gr_line
		(start 260.8834 -78.105)
		(end 264.1854 -78.105)
		(stroke
			(width 1.016)
			(type default)
		)
		(layer "In8.Cu")
	)
	(gr_line
		(start 260.985 -44.577)
		(end 258.64947 -44.577)
		(stroke
			(width 1.016)
			(type default)
		)
		(layer "In8.Cu")
	)
	(gr_line
		(start 261.0104 -84.8614)
		(end 261.0104 -78.994)
		(stroke
			(width 1.016)
			(type default)
		)
		(layer "In8.Cu")
	)
	(gr_line
		(start 261.0104 -84.8614)
		(end 262.3566 -84.8614)
		(stroke
			(width 1.016)
			(type default)
		)
		(layer "In8.Cu")
	)
	(gr_line
		(start 261.0104 -78.994)
		(end 261.2644 -78.74)
		(stroke
			(width 1.016)
			(type default)
		)
		(layer "In8.Cu")
	)
	(gr_line
		(start 261.239 -85.09)
		(end 261.0104 -84.8614)
		(stroke
			(width 1.016)
			(type default)
		)
		(layer "In8.Cu")
	)
	(gr_line
		(start 261.239 -48.4886)
		(end 261.239 -48.387)
		(stroke
			(width 1.524)
			(type default)
		)
		(layer "In8.Cu")
	)
	(gr_line
		(start 261.239 -48.387)
		(end 259.334 -46.482)
		(stroke
			(width 1.27)
			(type default)
		)
		(layer "In8.Cu")
	)
	(gr_line
		(start 261.239 -48.387)
		(end 262.128 -48.387)
		(stroke
			(width 1.524)
			(type default)
		)
		(layer "In8.Cu")
	)
	(gr_line
		(start 261.2644 -78.74)
		(end 263.6774 -78.74)
		(stroke
			(width 1.016)
			(type default)
		)
		(layer "In8.Cu")
	)
	(gr_line
		(start 261.366 -47.752)
		(end 262.001 -47.752)
		(stroke
			(width 1.27)
			(type default)
		)
		(layer "In8.Cu")
	)
	(gr_circle
		(center 261.493 -71.5772)
		(end 262.382 -71.5772)
		(stroke
			(width 0.2)
			(type default)
		)
		(fill no)
		(layer "In8.Cu")
	)
	(gr_line
		(start 261.6454 -84.2264)
		(end 261.6454 -79.629)
		(stroke
			(width 1.016)
			(type default)
		)
		(layer "In8.Cu")
	)
	(gr_line
		(start 261.6454 -84.2264)
		(end 261.747 -84.2264)
		(stroke
			(width 1.016)
			(type default)
		)
		(layer "In8.Cu")
	)
	(gr_line
		(start 261.6454 -79.629)
		(end 261.7724 -79.502)
		(stroke
			(width 1.016)
			(type default)
		)
		(layer "In8.Cu")
	)
	(gr_line
		(start 261.747 -84.2264)
		(end 262.9154 -83.058)
		(stroke
			(width 1.016)
			(type default)
		)
		(layer "In8.Cu")
	)
	(gr_line
		(start 261.7724 -79.502)
		(end 263.0424 -79.502)
		(stroke
			(width 1.016)
			(type default)
		)
		(layer "In8.Cu")
	)
	(gr_line
		(start 261.874 -84.455)
		(end 261.6454 -84.2264)
		(stroke
			(width 1.016)
			(type default)
		)
		(layer "In8.Cu")
	)
	(gr_line
		(start 262.128 -48.387)
		(end 263.144 -49.403)
		(stroke
			(width 1.524)
			(type default)
		)
		(layer "In8.Cu")
	)
	(gr_line
		(start 262.1534 -80.264)
		(end 262.1534 -83.058)
		(stroke
			(width 1.016)
			(type default)
		)
		(layer "In8.Cu")
	)
	(gr_circle
		(center 262.255 -71.5772)
		(end 263.144 -71.5772)
		(stroke
			(width 0.2)
			(type default)
		)
		(fill no)
		(layer "In8.Cu")
	)
	(gr_line
		(start 262.255 -47.498)
		(end 264.795 -47.498)
		(stroke
			(width 1.27)
			(type default)
		)
		(layer "In8.Cu")
	)
	(gr_line
		(start 262.2804 -80.137)
		(end 262.1534 -80.264)
		(stroke
			(width 1.016)
			(type default)
		)
		(layer "In8.Cu")
	)
	(gr_line
		(start 262.3566 -84.8614)
		(end 263.525 -83.693)
		(stroke
			(width 1.016)
			(type default)
		)
		(layer "In8.Cu")
	)
	(gr_line
		(start 262.4074 -78.105)
		(end 265.7094 -78.105)
		(stroke
			(width 1.016)
			(type default)
		)
		(layer "In8.Cu")
	)
	(gr_line
		(start 262.5344 -80.137)
		(end 262.2804 -80.137)
		(stroke
			(width 1.016)
			(type default)
		)
		(layer "In8.Cu")
	)
	(gr_line
		(start 262.636 -49.403)
		(end 262.636 -48.768)
		(stroke
			(width 1.27)
			(type default)
		)
		(layer "In8.Cu")
	)
	(gr_line
		(start 262.636 -48.768)
		(end 263.271 -48.133)
		(stroke
			(width 1.27)
			(type default)
		)
		(layer "In8.Cu")
	)
	(gr_line
		(start 262.763 -84.328)
		(end 264.414 -85.979)
		(stroke
			(width 1.27)
			(type default)
		)
		(layer "In8.Cu")
	)
	(gr_line
		(start 262.7884 -78.74)
		(end 265.2014 -78.74)
		(stroke
			(width 1.016)
			(type default)
		)
		(layer "In8.Cu")
	)
	(gr_line
		(start 262.820912 -51.238912)
		(end 274.733512 -51.238912)
		(stroke
			(width 1.016)
			(type default)
		)
		(layer "In8.Cu")
	)
	(gr_line
		(start 262.9154 -83.058)
		(end 262.9154 -80.518)
		(stroke
			(width 1.016)
			(type default)
		)
		(layer "In8.Cu")
	)
	(gr_line
		(start 262.9154 -80.518)
		(end 262.5344 -80.137)
		(stroke
			(width 1.016)
			(type default)
		)
		(layer "In8.Cu")
	)
	(gr_line
		(start 263.0424 -79.502)
		(end 263.525 -79.9846)
		(stroke
			(width 1.016)
			(type default)
		)
		(layer "In8.Cu")
	)
	(gr_line
		(start 263.0424 -50.292)
		(end 261.239 -48.4886)
		(stroke
			(width 1.524)
			(type default)
		)
		(layer "In8.Cu")
	)
	(gr_line
		(start 263.144 -49.403)
		(end 262.636 -49.403)
		(stroke
			(width 1.27)
			(type default)
		)
		(layer "In8.Cu")
	)
	(gr_line
		(start 263.144 -49.403)
		(end 264.668 -49.403)
		(stroke
			(width 1.524)
			(type default)
		)
		(layer "In8.Cu")
	)
	(gr_line
		(start 263.525 -83.693)
		(end 265.176 -85.344)
		(stroke
			(width 1.27)
			(type default)
		)
		(layer "In8.Cu")
	)
	(gr_line
		(start 263.525 -79.9846)
		(end 263.525 -83.693)
		(stroke
			(width 1.016)
			(type default)
		)
		(layer "In8.Cu")
	)
	(gr_line
		(start 263.66343 -88.643206)
		(end 260.51383 -85.493606)
		(stroke
			(width 1.016)
			(type default)
		)
		(layer "In8.Cu")
	)
	(gr_line
		(start 263.6774 -78.74)
		(end 264.16 -79.2226)
		(stroke
			(width 1.016)
			(type default)
		)
		(layer "In8.Cu")
	)
	(gr_line
		(start 263.906 -87.757)
		(end 261.239 -85.09)
		(stroke
			(width 1.27)
			(type default)
		)
		(layer "In8.Cu")
	)
	(gr_line
		(start 264.16 -83.185)
		(end 265.684 -84.709)
		(stroke
			(width 1.27)
			(type default)
		)
		(layer "In8.Cu")
	)
	(gr_line
		(start 264.16 -79.2226)
		(end 264.16 -83.185)
		(stroke
			(width 1.016)
			(type default)
		)
		(layer "In8.Cu")
	)
	(gr_line
		(start 264.1854 -78.105)
		(end 264.696702 -78.616302)
		(stroke
			(width 1.016)
			(type default)
		)
		(layer "In8.Cu")
	)
	(gr_line
		(start 264.287 -86.868)
		(end 261.874 -84.455)
		(stroke
			(width 1.27)
			(type default)
		)
		(layer "In8.Cu")
	)
	(gr_line
		(start 264.414 -85.979)
		(end 276.86 -85.979)
		(stroke
			(width 1.27)
			(type default)
		)
		(layer "In8.Cu")
	)
	(gr_line
		(start 264.668 -49.403)
		(end 265.176 -48.895)
		(stroke
			(width 1.524)
			(type default)
		)
		(layer "In8.Cu")
	)
	(gr_line
		(start 264.696702 -82.761074)
		(end 265.824716 -83.889088)
		(stroke
			(width 1.016)
			(type default)
		)
		(layer "In8.Cu")
	)
	(gr_line
		(start 264.696702 -78.616302)
		(end 264.696702 -82.761074)
		(stroke
			(width 1.016)
			(type default)
		)
		(layer "In8.Cu")
	)
	(gr_line
		(start 264.795 -47.498)
		(end 264.922 -47.625)
		(stroke
			(width 1.27)
			(type default)
		)
		(layer "In8.Cu")
	)
	(gr_line
		(start 264.922 -47.625)
		(end 263.144 -49.403)
		(stroke
			(width 1.27)
			(type default)
		)
		(layer "In8.Cu")
	)
	(gr_line
		(start 265.176 -85.344)
		(end 277.876 -85.344)
		(stroke
			(width 1.27)
			(type default)
		)
		(layer "In8.Cu")
	)
	(gr_line
		(start 265.176 -48.895)
		(end 269.24 -48.895)
		(stroke
			(width 1.27)
			(type default)
		)
		(layer "In8.Cu")
	)
	(gr_line
		(start 265.2014 -78.74)
		(end 265.684 -79.2226)
		(stroke
			(width 1.016)
			(type default)
		)
		(layer "In8.Cu")
	)
	(gr_circle
		(center 265.4046 -70.7644)
		(end 266.2936 -70.7644)
		(stroke
			(width 0.2)
			(type default)
		)
		(fill no)
		(layer "In8.Cu")
	)
	(gr_line
		(start 265.6332 -82.931)
		(end 266.761214 -84.059014)
		(stroke
			(width 1.016)
			(type default)
		)
		(layer "In8.Cu")
	)
	(gr_line
		(start 265.684 -84.709)
		(end 278.638 -84.709)
		(stroke
			(width 1.27)
			(type default)
		)
		(layer "In8.Cu")
	)
	(gr_line
		(start 265.684 -79.2226)
		(end 265.684 -83.185)
		(stroke
			(width 1.016)
			(type default)
		)
		(layer "In8.Cu")
	)
	(gr_line
		(start 265.684 -49.53)
		(end 270.637 -49.53)
		(stroke
			(width 1.27)
			(type default)
		)
		(layer "In8.Cu")
	)
	(gr_line
		(start 265.7094 -78.105)
		(end 266.220702 -78.616302)
		(stroke
			(width 1.016)
			(type default)
		)
		(layer "In8.Cu")
	)
	(gr_line
		(start 265.824716 -83.889088)
		(end 279.229566 -83.889088)
		(stroke
			(width 1.016)
			(type default)
		)
		(layer "In8.Cu")
	)
	(gr_line
		(start 265.938 -50.292)
		(end 263.0424 -50.292)
		(stroke
			(width 1.524)
			(type default)
		)
		(layer "In8.Cu")
	)
	(gr_line
		(start 266.220702 -82.761074)
		(end 267.348716 -83.889088)
		(stroke
			(width 1.016)
			(type default)
		)
		(layer "In8.Cu")
	)
	(gr_line
		(start 266.220702 -78.616302)
		(end 266.220702 -82.761074)
		(stroke
			(width 1.016)
			(type default)
		)
		(layer "In8.Cu")
	)
	(gr_line
		(start 266.6238 -42.697908)
		(end 267.868908 -42.697908)
		(stroke
			(width 2.032)
			(type default)
		)
		(layer "In8.Cu")
	)
	(gr_line
		(start 267.208508 -43.561508)
		(end 258.934966 -43.561508)
		(stroke
			(width 1.016)
			(type default)
		)
		(layer "In8.Cu")
	)
	(gr_line
		(start 267.348716 -83.889088)
		(end 268.538706 -83.889088)
		(stroke
			(width 1.016)
			(type default)
		)
		(layer "In8.Cu")
	)
	(gr_line
		(start 267.868908 -42.697908)
		(end 274.0152 -48.8442)
		(stroke
			(width 2.032)
			(type default)
		)
		(layer "In8.Cu")
	)
	(gr_line
		(start 267.97 -46.736)
		(end 260.35 -46.736)
		(stroke
			(width 1.27)
			(type default)
		)
		(layer "In8.Cu")
	)
	(gr_line
		(start 268.224 -45.974)
		(end 273.05 -50.8)
		(stroke
			(width 1.27)
			(type default)
		)
		(layer "In8.Cu")
	)
	(gr_line
		(start 268.351 -48.006)
		(end 265.049 -48.006)
		(stroke
			(width 1.27)
			(type default)
		)
		(layer "In8.Cu")
	)
	(gr_line
		(start 268.478 -42.6974)
		(end 269.4686 -42.6974)
		(stroke
			(width 2.032)
			(type default)
		)
		(layer "In8.Cu")
	)
	(gr_line
		(start 268.5288 -42.7482)
		(end 268.478 -42.6974)
		(stroke
			(width 2.032)
			(type default)
		)
		(layer "In8.Cu")
	)
	(gr_line
		(start 268.5796 -45.085)
		(end 258.61899 -45.085)
		(stroke
			(width 1.016)
			(type default)
		)
		(layer "In8.Cu")
	)
	(gr_line
		(start 269.24 -48.895)
		(end 268.351 -48.006)
		(stroke
			(width 1.27)
			(type default)
		)
		(layer "In8.Cu")
	)
	(gr_line
		(start 269.4686 -42.6974)
		(end 273.4818 -46.7106)
		(stroke
			(width 2.032)
			(type default)
		)
		(layer "In8.Cu")
	)
	(gr_circle
		(center 269.6464 -57.912)
		(end 270.5354 -57.912)
		(stroke
			(width 0.2)
			(type default)
		)
		(fill no)
		(layer "In8.Cu")
	)
	(gr_circle
		(center 270.0782 -86.233)
		(end 270.9672 -86.233)
		(stroke
			(width 0.2)
			(type default)
		)
		(fill no)
		(layer "In8.Cu")
	)
	(gr_circle
		(center 270.4084 -57.912)
		(end 271.2974 -57.912)
		(stroke
			(width 0.2)
			(type default)
		)
		(fill no)
		(layer "In8.Cu")
	)
	(gr_line
		(start 270.637 -49.53)
		(end 270.764 -49.657)
		(stroke
			(width 1.27)
			(type default)
		)
		(layer "In8.Cu")
	)
	(gr_circle
		(center 270.7132 -86.233)
		(end 271.6022 -86.233)
		(stroke
			(width 0.2)
			(type default)
		)
		(fill no)
		(layer "In8.Cu")
	)
	(gr_line
		(start 270.764 -49.657)
		(end 270.764 -49.53)
		(stroke
			(width 1.27)
			(type default)
		)
		(layer "In8.Cu")
	)
	(gr_line
		(start 270.764 -49.53)
		(end 267.97 -46.736)
		(stroke
			(width 1.27)
			(type default)
		)
		(layer "In8.Cu")
	)
	(gr_line
		(start 271.3482 -43.1038)
		(end 270.9672 -43.1038)
		(stroke
			(width 2.032)
			(type default)
		)
		(layer "In8.Cu")
	)
	(gr_circle
		(center 271.9324 -57.912)
		(end 272.8214 -57.912)
		(stroke
			(width 0.2)
			(type default)
		)
		(fill no)
		(layer "In8.Cu")
	)
	(gr_circle
		(center 272.1102 -86.233)
		(end 272.9992 -86.233)
		(stroke
			(width 0.2)
			(type default)
		)
		(fill no)
		(layer "In8.Cu")
	)
	(gr_line
		(start 272.2626 -42.7482)
		(end 268.5288 -42.7482)
		(stroke
			(width 2.032)
			(type default)
		)
		(layer "In8.Cu")
	)
	(gr_line
		(start 272.5928 -41.91)
		(end 274.8026 -44.1198)
		(stroke
			(width 1.016)
			(type default)
		)
		(layer "In8.Cu")
	)
	(gr_circle
		(center 272.6944 -57.912)
		(end 273.5834 -57.912)
		(stroke
			(width 0.2)
			(type default)
		)
		(fill no)
		(layer "In8.Cu")
	)
	(gr_circle
		(center 272.7452 -86.233)
		(end 273.6342 -86.233)
		(stroke
			(width 0.2)
			(type default)
		)
		(fill no)
		(layer "In8.Cu")
	)
	(gr_line
		(start 272.796 -50.292)
		(end 265.938 -50.292)
		(stroke
			(width 1.27)
			(type default)
		)
		(layer "In8.Cu")
	)
	(gr_line
		(start 273.05 -50.8)
		(end 273.304 -50.8)
		(stroke
			(width 1.27)
			(type default)
		)
		(layer "In8.Cu")
	)
	(gr_line
		(start 273.2278 -46.5836)
		(end 273.2278 -44.9834)
		(stroke
			(width 2.032)
			(type default)
		)
		(layer "In8.Cu")
	)
	(gr_line
		(start 273.2278 -44.9834)
		(end 271.3482 -43.1038)
		(stroke
			(width 2.032)
			(type default)
		)
		(layer "In8.Cu")
	)
	(gr_line
		(start 273.304 -50.8)
		(end 272.796 -50.292)
		(stroke
			(width 1.27)
			(type default)
		)
		(layer "In8.Cu")
	)
	(gr_line
		(start 273.4818 -46.8376)
		(end 273.2278 -46.5836)
		(stroke
			(width 2.032)
			(type default)
		)
		(layer "In8.Cu")
	)
	(gr_line
		(start 273.4818 -46.7106)
		(end 273.4818 -46.8376)
		(stroke
			(width 2.032)
			(type default)
		)
		(layer "In8.Cu")
	)
	(gr_line
		(start 273.700748 -41.849548)
		(end 248.993406 -41.849548)
		(stroke
			(width 1.016)
			(type default)
		)
		(layer "In8.Cu")
	)
	(gr_line
		(start 274.0152 -48.8442)
		(end 274.066 -48.7934)
		(stroke
			(width 2.032)
			(type default)
		)
		(layer "In8.Cu")
	)
	(gr_line
		(start 274.066 -48.7934)
		(end 274.066 -44.5516)
		(stroke
			(width 2.032)
			(type default)
		)
		(layer "In8.Cu")
	)
	(gr_line
		(start 274.066 -44.5516)
		(end 272.2626 -42.7482)
		(stroke
			(width 2.032)
			(type default)
		)
		(layer "In8.Cu")
	)
	(gr_circle
		(center 274.1422 -86.233)
		(end 275.0312 -86.233)
		(stroke
			(width 0.2)
			(type default)
		)
		(fill no)
		(layer "In8.Cu")
	)
	(gr_line
		(start 274.733512 -51.238912)
		(end 268.5796 -45.085)
		(stroke
			(width 1.016)
			(type default)
		)
		(layer "In8.Cu")
	)
	(gr_circle
		(center 274.7772 -86.233)
		(end 275.6662 -86.233)
		(stroke
			(width 0.2)
			(type default)
		)
		(fill no)
		(layer "In8.Cu")
	)
	(gr_line
		(start 274.8026 -49.5808)
		(end 274.4978 -49.8856)
		(stroke
			(width 1.016)
			(type default)
		)
		(layer "In8.Cu")
	)
	(gr_line
		(start 274.8026 -44.1198)
		(end 274.8026 -49.5808)
		(stroke
			(width 1.016)
			(type default)
		)
		(layer "In8.Cu")
	)
	(gr_line
		(start 275.4122 -50.1396)
		(end 275.4122 -43.561)
		(stroke
			(width 1.016)
			(type default)
		)
		(layer "In8.Cu")
	)
	(gr_line
		(start 275.4122 -43.561)
		(end 273.700748 -41.849548)
		(stroke
			(width 1.016)
			(type default)
		)
		(layer "In8.Cu")
	)
	(gr_circle
		(center 276.0472 -86.233)
		(end 276.9362 -86.233)
		(stroke
			(width 0.2)
			(type default)
		)
		(fill no)
		(layer "In8.Cu")
	)
	(gr_line
		(start 276.5298 -52.07)
		(end 276.7584 -52.2986)
		(stroke
			(width 1.016)
			(type default)
		)
		(layer "In8.Cu")
	)
	(gr_line
		(start 276.5298 -51.2572)
		(end 275.4122 -50.1396)
		(stroke
			(width 1.016)
			(type default)
		)
		(layer "In8.Cu")
	)
	(gr_line
		(start 276.5298 -51.2572)
		(end 276.5298 -52.07)
		(stroke
			(width 1.016)
			(type default)
		)
		(layer "In8.Cu")
	)
	(gr_circle
		(center 276.6822 -86.233)
		(end 277.5712 -86.233)
		(stroke
			(width 0.2)
			(type default)
		)
		(fill no)
		(layer "In8.Cu")
	)
	(gr_line
		(start 276.733 -86.868)
		(end 264.287 -86.868)
		(stroke
			(width 1.27)
			(type default)
		)
		(layer "In8.Cu")
	)
	(gr_line
		(start 276.86 -85.979)
		(end 277.241 -86.36)
		(stroke
			(width 1.27)
			(type default)
		)
		(layer "In8.Cu")
	)
	(gr_line
		(start 277.114 -87.757)
		(end 263.906 -87.757)
		(stroke
			(width 1.27)
			(type default)
		)
		(layer "In8.Cu")
	)
	(gr_line
		(start 277.241 -86.36)
		(end 276.733 -86.868)
		(stroke
			(width 1.27)
			(type default)
		)
		(layer "In8.Cu")
	)
	(gr_line
		(start 277.3172 -52.5018)
		(end 271.7546 -46.9392)
		(stroke
			(width 1.27)
			(type default)
		)
		(layer "In8.Cu")
	)
	(gr_line
		(start 277.3934 -52.5272)
		(end 277.3934 -52.1208)
		(stroke
			(width 1.016)
			(type default)
		)
		(layer "In8.Cu")
	)
	(gr_line
		(start 277.3934 -52.5272)
		(end 277.9522 -51.9684)
		(stroke
			(width 1.27)
			(type default)
		)
		(layer "In8.Cu")
	)
	(gr_line
		(start 277.3934 -52.1208)
		(end 276.5298 -51.2572)
		(stroke
			(width 1.016)
			(type default)
		)
		(layer "In8.Cu")
	)
	(gr_line
		(start 277.876 -85.344)
		(end 278.003 -85.471)
		(stroke
			(width 1.27)
			(type default)
		)
		(layer "In8.Cu")
	)
	(gr_line
		(start 277.9522 -51.9684)
		(end 294.4622 -51.9684)
		(stroke
			(width 1.27)
			(type default)
		)
		(layer "In8.Cu")
	)
	(gr_line
		(start 278.003 -86.868)
		(end 277.114 -87.757)
		(stroke
			(width 1.27)
			(type default)
		)
		(layer "In8.Cu")
	)
	(gr_line
		(start 278.003 -85.471)
		(end 278.003 -86.868)
		(stroke
			(width 1.27)
			(type default)
		)
		(layer "In8.Cu")
	)
	(gr_line
		(start 278.06904 -85.15096)
		(end 277.876 -85.344)
		(stroke
			(width 1.016)
			(type default)
		)
		(layer "In8.Cu")
	)
	(gr_line
		(start 278.213566 -85.260434)
		(end 277.876 -85.598)
		(stroke
			(width 0.508)
			(type default)
		)
		(layer "In8.Cu")
	)
	(gr_line
		(start 278.384 -87.757)
		(end 263.906 -87.757)
		(stroke
			(width 1.27)
			(type default)
		)
		(layer "In8.Cu")
	)
	(gr_line
		(start 278.388318 -28.448)
		(end 231.14 -28.448)
		(stroke
			(width 1.016)
			(type default)
		)
		(layer "In8.Cu")
	)
	(gr_line
		(start 278.4348 -52.705)
		(end 282.956 -57.2262)
		(stroke
			(width 1.27)
			(type default)
		)
		(layer "In8.Cu")
	)
	(gr_line
		(start 278.638 -84.709)
		(end 278.892 -84.963)
		(stroke
			(width 1.27)
			(type default)
		)
		(layer "In8.Cu")
	)
	(gr_line
		(start 278.853392 -88.643206)
		(end 263.66343 -88.643206)
		(stroke
			(width 1.016)
			(type default)
		)
		(layer "In8.Cu")
	)
	(gr_line
		(start 278.892 -87.249)
		(end 278.384 -87.757)
		(stroke
			(width 1.27)
			(type default)
		)
		(layer "In8.Cu")
	)
	(gr_line
		(start 278.892 -84.963)
		(end 278.638 -84.709)
		(stroke
			(width 1.27)
			(type default)
		)
		(layer "In8.Cu")
	)
	(gr_line
		(start 278.892 -84.963)
		(end 278.892 -87.249)
		(stroke
			(width 1.27)
			(type default)
		)
		(layer "In8.Cu")
	)
	(gr_line
		(start 278.892 -84.963)
		(end 280.035 -84.963)
		(stroke
			(width 0.508)
			(type default)
		)
		(layer "In8.Cu")
	)
	(gr_line
		(start 278.892 -84.455)
		(end 278.554434 -84.792566)
		(stroke
			(width 0.508)
			(type default)
		)
		(layer "In8.Cu")
	)
	(gr_line
		(start 278.975566 -84.244434)
		(end 278.638 -84.582)
		(stroke
			(width 0.508)
			(type default)
		)
		(layer "In8.Cu")
	)
	(gr_line
		(start 279.229566 -84.625434)
		(end 278.892 -84.963)
		(stroke
			(width 0.508)
			(type default)
		)
		(layer "In8.Cu")
	)
	(gr_line
		(start 279.229566 -83.889088)
		(end 279.229566 -84.625434)
		(stroke
			(width 0.508)
			(type default)
		)
		(layer "In8.Cu")
	)
	(gr_line
		(start 279.229566 -83.889088)
		(end 279.653238 -84.31276)
		(stroke
			(width 1.016)
			(type default)
		)
		(layer "In8.Cu")
	)
	(gr_line
		(start 279.653238 -87.84336)
		(end 278.853392 -88.643206)
		(stroke
			(width 1.016)
			(type default)
		)
		(layer "In8.Cu")
	)
	(gr_line
		(start 279.653238 -84.31276)
		(end 279.229566 -83.889088)
		(stroke
			(width 1.016)
			(type default)
		)
		(layer "In8.Cu")
	)
	(gr_line
		(start 279.653238 -84.31276)
		(end 279.653238 -87.84336)
		(stroke
			(width 1.016)
			(type default)
		)
		(layer "In8.Cu")
	)
	(gr_line
		(start 279.653238 -84.31276)
		(end 279.764998 -84.201)
		(stroke
			(width 0.508)
			(type default)
		)
		(layer "In8.Cu")
	)
	(gr_line
		(start 279.653238 -84.31276)
		(end 279.922478 -84.582)
		(stroke
			(width 0.508)
			(type default)
		)
		(layer "In8.Cu")
	)
	(gr_line
		(start 279.654 -27.182318)
		(end 278.388318 -28.448)
		(stroke
			(width 1.016)
			(type default)
		)
		(layer "In8.Cu")
	)
	(gr_line
		(start 279.654 -16.146018)
		(end 279.654 -27.182318)
		(stroke
			(width 1.016)
			(type default)
		)
		(layer "In8.Cu")
	)
	(gr_line
		(start 279.764998 -84.201)
		(end 280.714958 -85.15096)
		(stroke
			(width 0.508)
			(type default)
		)
		(layer "In8.Cu")
	)
	(gr_line
		(start 280.0858 -53.4416)
		(end 283.1592 -56.515)
		(stroke
			(width 1.27)
			(type default)
		)
		(layer "In8.Cu")
	)
	(gr_line
		(start 280.289 -85.4964)
		(end 279.908 -85.8774)
		(stroke
			(width 0.508)
			(type default)
		)
		(layer "In8.Cu")
	)
	(gr_circle
		(center 280.329894 -78.1558)
		(end 281.218894 -78.1558)
		(stroke
			(width 0.2)
			(type default)
		)
		(fill no)
		(layer "In8.Cu")
	)
	(gr_line
		(start 280.3398 -53.1876)
		(end 280.0858 -53.4416)
		(stroke
			(width 1.27)
			(type default)
		)
		(layer "In8.Cu")
	)
	(gr_line
		(start 280.714958 -85.15096)
		(end 281.74696 -85.15096)
		(stroke
			(width 0.508)
			(type default)
		)
		(layer "In8.Cu")
	)
	(gr_circle
		(center 281.091894 -78.1558)
		(end 281.980894 -78.1558)
		(stroke
			(width 0.2)
			(type default)
		)
		(fill no)
		(layer "In8.Cu")
	)
	(gr_line
		(start 281.686 -54.1274)
		(end 283.1338 -55.5752)
		(stroke
			(width 2.54)
			(type default)
		)
		(layer "In8.Cu")
	)
	(gr_line
		(start 281.74696 -85.15096)
		(end 278.06904 -85.15096)
		(stroke
			(width 1.016)
			(type default)
		)
		(layer "In8.Cu")
	)
	(gr_line
		(start 281.9654 -53.848)
		(end 281.686 -54.1274)
		(stroke
			(width 2.54)
			(type default)
		)
		(layer "In8.Cu")
	)
	(gr_line
		(start 282.0162 -88.38184)
		(end 282.0162 -87.26424)
		(stroke
			(width 0.254)
			(type default)
		)
		(layer "In8.Cu")
	)
	(gr_line
		(start 282.0162 -87.26424)
		(end 283.3878 -87.26424)
		(stroke
			(width 0.254)
			(type default)
		)
		(layer "In8.Cu")
	)
	(gr_line
		(start 282.2448 -87.4014)
		(end 282.2448 -88.2396)
		(stroke
			(width 0.508)
			(type default)
		)
		(layer "In8.Cu")
	)
	(gr_line
		(start 282.2702 -88.1634)
		(end 283.1084 -88.1634)
		(stroke
			(width 0.508)
			(type default)
		)
		(layer "In8.Cu")
	)
	(gr_line
		(start 282.2702 -87.4776)
		(end 283.1084 -87.4776)
		(stroke
			(width 0.508)
			(type default)
		)
		(layer "In8.Cu")
	)
	(gr_line
		(start 282.448 -58.801)
		(end 267.208508 -43.561508)
		(stroke
			(width 1.016)
			(type default)
		)
		(layer "In8.Cu")
	)
	(gr_line
		(start 282.5242 -86.9442)
		(end 282.1432 -87.3252)
		(stroke
			(width 0.508)
			(type default)
		)
		(layer "In8.Cu")
	)
	(gr_line
		(start 282.6258 -87.2998)
		(end 282.6258 -88.138)
		(stroke
			(width 0.508)
			(type default)
		)
		(layer "In8.Cu")
	)
	(gr_line
		(start 282.702 -87.82304)
		(end 282.702 -86.106)
		(stroke
			(width 1.016)
			(type default)
		)
		(layer "In8.Cu")
	)
	(gr_line
		(start 282.702 -86.106)
		(end 281.74696 -85.15096)
		(stroke
			(width 1.016)
			(type default)
		)
		(layer "In8.Cu")
	)
	(gr_line
		(start 282.956 -58.0898)
		(end 277.3934 -52.5272)
		(stroke
			(width 1.27)
			(type default)
		)
		(layer "In8.Cu")
	)
	(gr_line
		(start 282.956 -57.2262)
		(end 293.6494 -57.2262)
		(stroke
			(width 1.27)
			(type default)
		)
		(layer "In8.Cu")
	)
	(gr_line
		(start 283.0322 -87.376)
		(end 283.0322 -88.2142)
		(stroke
			(width 0.508)
			(type default)
		)
		(layer "In8.Cu")
	)
	(gr_line
		(start 283.1338 -55.5752)
		(end 293.497 -55.5752)
		(stroke
			(width 2.54)
			(type default)
		)
		(layer "In8.Cu")
	)
	(gr_line
		(start 283.1592 -56.515)
		(end 293.878 -56.515)
		(stroke
			(width 1.27)
			(type default)
		)
		(layer "In8.Cu")
	)
	(gr_line
		(start 283.2608 -87.3252)
		(end 282.8798 -86.9442)
		(stroke
			(width 0.508)
			(type default)
		)
		(layer "In8.Cu")
	)
	(gr_line
		(start 283.354018 -12.446)
		(end 279.654 -16.146018)
		(stroke
			(width 1.016)
			(type default)
		)
		(layer "In8.Cu")
	)
	(gr_line
		(start 283.3878 -88.38184)
		(end 282.0162 -88.38184)
		(stroke
			(width 0.254)
			(type default)
		)
		(layer "In8.Cu")
	)
	(gr_line
		(start 283.3878 -87.26424)
		(end 283.3878 -88.38184)
		(stroke
			(width 0.254)
			(type default)
		)
		(layer "In8.Cu")
	)
	(gr_line
		(start 293.497 -58.801)
		(end 282.448 -58.801)
		(stroke
			(width 1.016)
			(type default)
		)
		(layer "In8.Cu")
	)
	(gr_line
		(start 293.497 -55.5752)
		(end 293.8526 -55.2196)
		(stroke
			(width 2.54)
			(type default)
		)
		(layer "In8.Cu")
	)
	(gr_line
		(start 293.497 -53.848)
		(end 281.9654 -53.848)
		(stroke
			(width 2.54)
			(type default)
		)
		(layer "In8.Cu")
	)
	(gr_line
		(start 293.6494 -57.2262)
		(end 294.5892 -58.166)
		(stroke
			(width 1.27)
			(type default)
		)
		(layer "In8.Cu")
	)
	(gr_line
		(start 293.6748 -58.0898)
		(end 282.956 -58.0898)
		(stroke
			(width 1.27)
			(type default)
		)
		(layer "In8.Cu")
	)
	(gr_line
		(start 293.6748 -53.1876)
		(end 280.3398 -53.1876)
		(stroke
			(width 1.27)
			(type default)
		)
		(layer "In8.Cu")
	)
	(gr_line
		(start 293.878 -56.515)
		(end 293.878 -54.229)
		(stroke
			(width 2.54)
			(type default)
		)
		(layer "In8.Cu")
	)
	(gr_line
		(start 293.878 -54.229)
		(end 293.497 -53.848)
		(stroke
			(width 2.54)
			(type default)
		)
		(layer "In8.Cu")
	)
	(gr_line
		(start 294.3606 -52.705)
		(end 278.4348 -52.705)
		(stroke
			(width 1.27)
			(type default)
		)
		(layer "In8.Cu")
	)
	(gr_line
		(start 294.4622 -51.9684)
		(end 296.2656 -53.7718)
		(stroke
			(width 1.27)
			(type default)
		)
		(layer "In8.Cu")
	)
	(gr_line
		(start 294.5892 -58.166)
		(end 294.5892 -54.102)
		(stroke
			(width 1.27)
			(type default)
		)
		(layer "In8.Cu")
	)
	(gr_line
		(start 294.5892 -54.102)
		(end 293.6748 -53.1876)
		(stroke
			(width 1.27)
			(type default)
		)
		(layer "In8.Cu")
	)
	(gr_line
		(start 294.8432 -51.2572)
		(end 276.5298 -51.2572)
		(stroke
			(width 1.016)
			(type default)
		)
		(layer "In8.Cu")
	)
	(gr_line
		(start 295.2242 -59.6392)
		(end 295.2242 -53.5686)
		(stroke
			(width 1.27)
			(type default)
		)
		(layer "In8.Cu")
	)
	(gr_line
		(start 295.2242 -53.5686)
		(end 294.3606 -52.705)
		(stroke
			(width 1.27)
			(type default)
		)
		(layer "In8.Cu")
	)
	(gr_line
		(start 296.2656 -60.6806)
		(end 293.6748 -58.0898)
		(stroke
			(width 1.27)
			(type default)
		)
		(layer "In8.Cu")
	)
	(gr_line
		(start 296.2656 -60.6806)
		(end 295.2242 -59.6392)
		(stroke
			(width 1.27)
			(type default)
		)
		(layer "In8.Cu")
	)
	(gr_line
		(start 296.2656 -53.7718)
		(end 296.2656 -60.6806)
		(stroke
			(width 1.27)
			(type default)
		)
		(layer "In8.Cu")
	)
	(gr_line
		(start 296.545 -65.532)
		(end 296.545 -61.849)
		(stroke
			(width 1.016)
			(type default)
		)
		(layer "In8.Cu")
	)
	(gr_line
		(start 296.545 -61.849)
		(end 293.497 -58.801)
		(stroke
			(width 1.016)
			(type default)
		)
		(layer "In8.Cu")
	)
	(gr_line
		(start 296.545 -61.849)
		(end 296.545 -52.959)
		(stroke
			(width 1.016)
			(type default)
		)
		(layer "In8.Cu")
	)
	(gr_line
		(start 296.545 -52.959)
		(end 294.8432 -51.2572)
		(stroke
			(width 1.016)
			(type default)
		)
		(layer "In8.Cu")
	)
	(gr_circle
		(center 297.9928 -80.391)
		(end 298.8818 -80.391)
		(stroke
			(width 0.2)
			(type default)
		)
		(fill no)
		(layer "In8.Cu")
	)
	(gr_circle
		(center 298.069 -75.819)
		(end 298.958 -75.819)
		(stroke
			(width 0.2)
			(type default)
		)
		(fill no)
		(layer "In8.Cu")
	)
	(gr_line
		(start 298.35729 -67.34429)
		(end 296.545 -65.532)
		(stroke
			(width 1.016)
			(type default)
		)
		(layer "In8.Cu")
	)
	(gr_line
		(start 298.35729 -67.34429)
		(end 298.49318 -67.48018)
		(stroke
			(width 1.016)
			(type default)
		)
		(layer "In8.Cu")
	)
	(gr_line
		(start 298.35729 -67.34429)
		(end 309.808372 -67.34429)
		(stroke
			(width 1.016)
			(type default)
		)
		(layer "In8.Cu")
	)
	(gr_circle
		(center 298.7548 -80.391)
		(end 299.6438 -80.391)
		(stroke
			(width 0.2)
			(type default)
		)
		(fill no)
		(layer "In8.Cu")
	)
	(gr_line
		(start 299.168312 -38.996112)
		(end 300.6852 -40.513)
		(stroke
			(width 1.016)
			(type default)
		)
		(layer "In8.Cu")
	)
	(gr_line
		(start 299.168312 -33.576768)
		(end 299.168312 -38.996112)
		(stroke
			(width 1.016)
			(type default)
		)
		(layer "In8.Cu")
	)
	(gr_line
		(start 299.265086 -33.479994)
		(end 299.168312 -33.576768)
		(stroke
			(width 1.016)
			(type default)
		)
		(layer "In8.Cu")
	)
	(gr_line
		(start 300.446694 -34.461958)
		(end 300.126654 -34.781998)
		(stroke
			(width 2.54)
			(type default)
		)
		(layer "In8.Cu")
	)
	(gr_line
		(start 300.6852 -40.513)
		(end 303.4792 -40.513)
		(stroke
			(width 1.016)
			(type default)
		)
		(layer "In8.Cu")
	)
	(gr_line
		(start 302.078136 -36.06165)
		(end 301.822104 -36.317682)
		(stroke
			(width 2.54)
			(type default)
		)
		(layer "In8.Cu")
	)
	(gr_line
		(start 303.101756 -37.821108)
		(end 303.069752 -37.853112)
		(stroke
			(width 2.54)
			(type default)
		)
		(layer "In8.Cu")
	)
	(gr_line
		(start 303.391316 -40.2844)
		(end 305.5366 -40.2844)
		(stroke
			(width 1.016)
			(type default)
		)
		(layer "In8.Cu")
	)
	(gr_line
		(start 303.4792 -40.513)
		(end 304.8 -41.8338)
		(stroke
			(width 1.016)
			(type default)
		)
		(layer "In8.Cu")
	)
	(gr_line
		(start 304.038 -12.446)
		(end 304.8 -13.208)
		(stroke
			(width 1.016)
			(type default)
		)
		(layer "In8.Cu")
	)
	(gr_circle
		(center 304.070258 -79.823056)
		(end 304.959258 -79.823056)
		(stroke
			(width 0.2)
			(type default)
		)
		(fill no)
		(layer "In8.Cu")
	)
	(gr_line
		(start 304.546 -39.053516)
		(end 304.546 -41.1988)
		(stroke
			(width 1.016)
			(type default)
		)
		(layer "In8.Cu")
	)
	(gr_line
		(start 304.779934 -32.938466)
		(end 303.7586 -33.9598)
		(stroke
			(width 1.016)
			(type default)
		)
		(layer "In8.Cu")
	)
	(gr_line
		(start 304.794666 -32.938466)
		(end 305.816 -33.9598)
		(stroke
			(width 1.016)
			(type default)
		)
		(layer "In8.Cu")
	)
	(gr_line
		(start 304.8 -67.065144)
		(end 305.079146 -67.34429)
		(stroke
			(width 1.016)
			(type default)
		)
		(layer "In8.Cu")
	)
	(gr_line
		(start 304.8 -33.909)
		(end 304.8 -67.065144)
		(stroke
			(width 1.016)
			(type default)
		)
		(layer "In8.Cu")
	)
	(gr_line
		(start 304.8 -33.479994)
		(end 299.265086 -33.479994)
		(stroke
			(width 1.016)
			(type default)
		)
		(layer "In8.Cu")
	)
	(gr_line
		(start 304.8 -33.479994)
		(end 309.723028 -33.479994)
		(stroke
			(width 1.016)
			(type default)
		)
		(layer "In8.Cu")
	)
	(gr_line
		(start 304.8 -13.208)
		(end 304.8 -33.479994)
		(stroke
			(width 1.016)
			(type default)
		)
		(layer "In8.Cu")
	)
	(gr_circle
		(center 305.063398 -81.003648)
		(end 305.952398 -81.003648)
		(stroke
			(width 0.2)
			(type default)
		)
		(fill no)
		(layer "In8.Cu")
	)
	(gr_line
		(start 305.562 -12.446)
		(end 304.8 -13.208)
		(stroke
			(width 1.016)
			(type default)
		)
		(layer "In8.Cu")
	)
	(gr_line
		(start 305.6128 -40.513)
		(end 304.8 -41.3258)
		(stroke
			(width 1.016)
			(type default)
		)
		(layer "In8.Cu")
	)
	(gr_line
		(start 305.6636 -46.2534)
		(end 304.8508 -45.4406)
		(stroke
			(width 1.016)
			(type default)
		)
		(layer "In8.Cu")
	)
	(gr_line
		(start 306.076858 -37.821108)
		(end 303.101756 -37.821108)
		(stroke
			(width 2.54)
			(type default)
		)
		(layer "In8.Cu")
	)
	(gr_line
		(start 306.17287 -37.91712)
		(end 306.076858 -37.821108)
		(stroke
			(width 2.54)
			(type default)
		)
		(layer "In8.Cu")
	)
	(gr_line
		(start 307.388514 -36.06165)
		(end 302.078136 -36.06165)
		(stroke
			(width 2.54)
			(type default)
		)
		(layer "In8.Cu")
	)
	(gr_line
		(start 307.836316 -36.509452)
		(end 307.388514 -36.06165)
		(stroke
			(width 2.54)
			(type default)
		)
		(layer "In8.Cu")
	)
	(gr_line
		(start 308.3052 -37.5412)
		(end 300.083728 -37.5412)
		(stroke
			(width 2.54)
			(type default)
		)
		(layer "In8.Cu")
	)
	(gr_line
		(start 308.3306 -36.068)
		(end 300.109128 -36.068)
		(stroke
			(width 2.54)
			(type default)
		)
		(layer "In8.Cu")
	)
	(gr_line
		(start 308.5592 -38.7858)
		(end 300.337728 -38.7858)
		(stroke
			(width 2.54)
			(type default)
		)
		(layer "In8.Cu")
	)
	(gr_line
		(start 308.668166 -34.461958)
		(end 300.446694 -34.461958)
		(stroke
			(width 2.54)
			(type default)
		)
		(layer "In8.Cu")
	)
	(gr_line
		(start 309.1688 -39.2938)
		(end 300.947328 -39.2938)
		(stroke
			(width 2.54)
			(type default)
		)
		(layer "In8.Cu")
	)
	(gr_line
		(start 309.2704 -40.513)
		(end 305.6128 -40.513)
		(stroke
			(width 1.016)
			(type default)
		)
		(layer "In8.Cu")
	)
	(gr_line
		(start 309.448962 -34.323528)
		(end 309.448962 -38.861238)
		(stroke
			(width 1.016)
			(type default)
		)
		(layer "In8.Cu")
	)
	(gr_line
		(start 309.627778 -35.42157)
		(end 308.668166 -34.461958)
		(stroke
			(width 2.54)
			(type default)
		)
		(layer "In8.Cu")
	)
	(gr_line
		(start 309.723028 -33.479994)
		(end 310.744362 -34.501328)
		(stroke
			(width 1.016)
			(type default)
		)
		(layer "In8.Cu")
	)
	(gr_line
		(start 309.804562 -34.425128)
		(end 309.804562 -38.962838)
		(stroke
			(width 1.016)
			(type default)
		)
		(layer "In8.Cu")
	)
	(gr_line
		(start 309.808372 -67.34429)
		(end 310.72201 -68.257928)
		(stroke
			(width 1.016)
			(type default)
		)
		(layer "In8.Cu")
	)
	(gr_line
		(start 310.236362 -34.501328)
		(end 310.236362 -39.039038)
		(stroke
			(width 1.016)
			(type default)
		)
		(layer "In8.Cu")
	)
	(gr_line
		(start 310.72201 -79.844646)
		(end 311.395364 -80.518)
		(stroke
			(width 1.016)
			(type default)
		)
		(layer "In8.Cu")
	)
	(gr_line
		(start 310.72201 -68.257928)
		(end 310.72201 -79.844646)
		(stroke
			(width 1.016)
			(type default)
		)
		(layer "In8.Cu")
	)
	(gr_line
		(start 310.744362 -39.039038)
		(end 309.2704 -40.513)
		(stroke
			(width 1.016)
			(type default)
		)
		(layer "In8.Cu")
	)
	(gr_line
		(start 310.744362 -34.501328)
		(end 310.744362 -39.039038)
		(stroke
			(width 1.016)
			(type default)
		)
		(layer "In8.Cu")
	)
	(gr_line
		(start 311.395364 -80.518)
		(end 323.977 -80.518)
		(stroke
			(width 1.016)
			(type default)
		)
		(layer "In8.Cu")
	)
	(gr_line
		(start 323.977 -80.518)
		(end 324.612 -79.883)
		(stroke
			(width 1.016)
			(type default)
		)
		(layer "In8.Cu")
	)
	(gr_line
		(start 323.977 -12.446)
		(end 283.354018 -12.446)
		(stroke
			(width 1.016)
			(type default)
		)
		(layer "In8.Cu")
	)
	(gr_line
		(start 324.104 -46.355)
		(end 305.010058 -46.355)
		(stroke
			(width 1.016)
			(type default)
		)
		(layer "In8.Cu")
	)
	(gr_line
		(start 324.104 -46.355)
		(end 324.612 -45.847)
		(stroke
			(width 1.016)
			(type default)
		)
		(layer "In8.Cu")
	)
	(gr_line
		(start 324.612 -79.883)
		(end 324.612 -46.863)
		(stroke
			(width 1.016)
			(type default)
		)
		(layer "In8.Cu")
	)
	(gr_line
		(start 324.612 -46.863)
		(end 324.104 -46.355)
		(stroke
			(width 1.016)
			(type default)
		)
		(layer "In8.Cu")
	)
	(gr_line
		(start 324.612 -46.863)
		(end 324.612 -13.081)
		(stroke
			(width 1.016)
			(type default)
		)
		(layer "In8.Cu")
	)
	(gr_line
		(start 324.612 -13.081)
		(end 323.977 -12.446)
		(stroke
			(width 1.016)
			(type default)
		)
		(layer "In8.Cu")
	)
	(gr_circle
		(center 332.1558 -79.4766)
		(end 333.0448 -79.4766)
		(stroke
			(width 0.2)
			(type default)
		)
		(fill no)
		(layer "In8.Cu")
	)
	(gr_circle
		(center 332.1558 -78.7146)
		(end 333.0448 -78.7146)
		(stroke
			(width 0.2)
			(type default)
		)
		(fill no)
		(layer "In8.Cu")
	)
	(gr_circle
		(center 332.1558 -77.9526)
		(end 333.0448 -77.9526)
		(stroke
			(width 0.2)
			(type default)
		)
		(fill no)
		(layer "In8.Cu")
	)
	(gr_circle
		(center 332.1558 -77.1906)
		(end 333.0448 -77.1906)
		(stroke
			(width 0.2)
			(type default)
		)
		(fill no)
		(layer "In8.Cu")
	)
	(gr_circle
		(center 332.1558 -76.4286)
		(end 333.0448 -76.4286)
		(stroke
			(width 0.2)
			(type default)
		)
		(fill no)
		(layer "In8.Cu")
	)
	(gr_circle
		(center 332.1558 -68.199)
		(end 333.0448 -68.199)
		(stroke
			(width 0.2)
			(type default)
		)
		(fill no)
		(layer "In8.Cu")
	)
	(gr_circle
		(center 332.1558 -67.437)
		(end 333.0448 -67.437)
		(stroke
			(width 0.2)
			(type default)
		)
		(fill no)
		(layer "In8.Cu")
	)
	(gr_circle
		(center 332.1558 -66.675)
		(end 333.0448 -66.675)
		(stroke
			(width 0.2)
			(type default)
		)
		(fill no)
		(layer "In8.Cu")
	)
	(gr_circle
		(center 332.1558 -65.913)
		(end 333.0448 -65.913)
		(stroke
			(width 0.2)
			(type default)
		)
		(fill no)
		(layer "In8.Cu")
	)
	(gr_circle
		(center 332.1558 -65.151)
		(end 333.0448 -65.151)
		(stroke
			(width 0.2)
			(type default)
		)
		(fill no)
		(layer "In8.Cu")
	)
	(gr_circle
		(center 332.1558 -56.9214)
		(end 333.0448 -56.9214)
		(stroke
			(width 0.2)
			(type default)
		)
		(fill no)
		(layer "In8.Cu")
	)
	(gr_circle
		(center 332.1558 -56.1594)
		(end 333.0448 -56.1594)
		(stroke
			(width 0.2)
			(type default)
		)
		(fill no)
		(layer "In8.Cu")
	)
	(gr_circle
		(center 332.1558 -55.3974)
		(end 333.0448 -55.3974)
		(stroke
			(width 0.2)
			(type default)
		)
		(fill no)
		(layer "In8.Cu")
	)
	(gr_circle
		(center 332.1558 -54.6354)
		(end 333.0448 -54.6354)
		(stroke
			(width 0.2)
			(type default)
		)
		(fill no)
		(layer "In8.Cu")
	)
	(gr_circle
		(center 332.1558 -53.8734)
		(end 333.0448 -53.8734)
		(stroke
			(width 0.2)
			(type default)
		)
		(fill no)
		(layer "In8.Cu")
	)
	(gr_circle
		(center 332.1558 -45.6438)
		(end 333.0448 -45.6438)
		(stroke
			(width 0.2)
			(type default)
		)
		(fill no)
		(layer "In8.Cu")
	)
	(gr_circle
		(center 332.1558 -44.8818)
		(end 333.0448 -44.8818)
		(stroke
			(width 0.2)
			(type default)
		)
		(fill no)
		(layer "In8.Cu")
	)
	(gr_circle
		(center 332.1558 -44.1198)
		(end 333.0448 -44.1198)
		(stroke
			(width 0.2)
			(type default)
		)
		(fill no)
		(layer "In8.Cu")
	)
	(gr_circle
		(center 332.1558 -43.3578)
		(end 333.0448 -43.3578)
		(stroke
			(width 0.2)
			(type default)
		)
		(fill no)
		(layer "In8.Cu")
	)
	(gr_circle
		(center 332.1558 -42.5958)
		(end 333.0448 -42.5958)
		(stroke
			(width 0.2)
			(type default)
		)
		(fill no)
		(layer "In8.Cu")
	)
	(gr_circle
		(center 332.1558 -34.3662)
		(end 333.0448 -34.3662)
		(stroke
			(width 0.2)
			(type default)
		)
		(fill no)
		(layer "In8.Cu")
	)
	(gr_circle
		(center 332.1558 -33.6042)
		(end 333.0448 -33.6042)
		(stroke
			(width 0.2)
			(type default)
		)
		(fill no)
		(layer "In8.Cu")
	)
	(gr_circle
		(center 332.1558 -32.8422)
		(end 333.0448 -32.8422)
		(stroke
			(width 0.2)
			(type default)
		)
		(fill no)
		(layer "In8.Cu")
	)
	(gr_circle
		(center 332.1558 -32.0802)
		(end 333.0448 -32.0802)
		(stroke
			(width 0.2)
			(type default)
		)
		(fill no)
		(layer "In8.Cu")
	)
	(gr_circle
		(center 332.1558 -31.3182)
		(end 333.0448 -31.3182)
		(stroke
			(width 0.2)
			(type default)
		)
		(fill no)
		(layer "In8.Cu")
	)
	(gr_circle
		(center 332.1558 -23.0886)
		(end 333.0448 -23.0886)
		(stroke
			(width 0.2)
			(type default)
		)
		(fill no)
		(layer "In8.Cu")
	)
	(gr_circle
		(center 332.1558 -22.3266)
		(end 333.0448 -22.3266)
		(stroke
			(width 0.2)
			(type default)
		)
		(fill no)
		(layer "In8.Cu")
	)
	(gr_circle
		(center 332.1558 -21.5646)
		(end 333.0448 -21.5646)
		(stroke
			(width 0.2)
			(type default)
		)
		(fill no)
		(layer "In8.Cu")
	)
	(gr_circle
		(center 332.1558 -20.8026)
		(end 333.0448 -20.8026)
		(stroke
			(width 0.2)
			(type default)
		)
		(fill no)
		(layer "In8.Cu")
	)
	(gr_circle
		(center 332.1558 -20.0406)
		(end 333.0448 -20.0406)
		(stroke
			(width 0.2)
			(type default)
		)
		(fill no)
		(layer "In8.Cu")
	)
	(gr_circle
		(center 332.9178 -79.4766)
		(end 333.8068 -79.4766)
		(stroke
			(width 0.2)
			(type default)
		)
		(fill no)
		(layer "In8.Cu")
	)
	(gr_circle
		(center 332.9178 -78.7146)
		(end 333.8068 -78.7146)
		(stroke
			(width 0.2)
			(type default)
		)
		(fill no)
		(layer "In8.Cu")
	)
	(gr_circle
		(center 332.9178 -77.9526)
		(end 333.8068 -77.9526)
		(stroke
			(width 0.2)
			(type default)
		)
		(fill no)
		(layer "In8.Cu")
	)
	(gr_circle
		(center 332.9178 -77.1906)
		(end 333.8068 -77.1906)
		(stroke
			(width 0.2)
			(type default)
		)
		(fill no)
		(layer "In8.Cu")
	)
	(gr_circle
		(center 332.9178 -76.4286)
		(end 333.8068 -76.4286)
		(stroke
			(width 0.2)
			(type default)
		)
		(fill no)
		(layer "In8.Cu")
	)
	(gr_circle
		(center 332.9178 -68.199)
		(end 333.8068 -68.199)
		(stroke
			(width 0.2)
			(type default)
		)
		(fill no)
		(layer "In8.Cu")
	)
	(gr_circle
		(center 332.9178 -67.437)
		(end 333.8068 -67.437)
		(stroke
			(width 0.2)
			(type default)
		)
		(fill no)
		(layer "In8.Cu")
	)
	(gr_circle
		(center 332.9178 -66.675)
		(end 333.8068 -66.675)
		(stroke
			(width 0.2)
			(type default)
		)
		(fill no)
		(layer "In8.Cu")
	)
	(gr_circle
		(center 332.9178 -65.913)
		(end 333.8068 -65.913)
		(stroke
			(width 0.2)
			(type default)
		)
		(fill no)
		(layer "In8.Cu")
	)
	(gr_circle
		(center 332.9178 -65.151)
		(end 333.8068 -65.151)
		(stroke
			(width 0.2)
			(type default)
		)
		(fill no)
		(layer "In8.Cu")
	)
	(gr_circle
		(center 332.9178 -56.9214)
		(end 333.8068 -56.9214)
		(stroke
			(width 0.2)
			(type default)
		)
		(fill no)
		(layer "In8.Cu")
	)
	(gr_circle
		(center 332.9178 -56.1594)
		(end 333.8068 -56.1594)
		(stroke
			(width 0.2)
			(type default)
		)
		(fill no)
		(layer "In8.Cu")
	)
	(gr_circle
		(center 332.9178 -55.3974)
		(end 333.8068 -55.3974)
		(stroke
			(width 0.2)
			(type default)
		)
		(fill no)
		(layer "In8.Cu")
	)
	(gr_circle
		(center 332.9178 -54.6354)
		(end 333.8068 -54.6354)
		(stroke
			(width 0.2)
			(type default)
		)
		(fill no)
		(layer "In8.Cu")
	)
	(gr_circle
		(center 332.9178 -53.8734)
		(end 333.8068 -53.8734)
		(stroke
			(width 0.2)
			(type default)
		)
		(fill no)
		(layer "In8.Cu")
	)
	(gr_circle
		(center 332.9178 -45.6438)
		(end 333.8068 -45.6438)
		(stroke
			(width 0.2)
			(type default)
		)
		(fill no)
		(layer "In8.Cu")
	)
	(gr_circle
		(center 332.9178 -44.8818)
		(end 333.8068 -44.8818)
		(stroke
			(width 0.2)
			(type default)
		)
		(fill no)
		(layer "In8.Cu")
	)
	(gr_circle
		(center 332.9178 -44.1198)
		(end 333.8068 -44.1198)
		(stroke
			(width 0.2)
			(type default)
		)
		(fill no)
		(layer "In8.Cu")
	)
	(gr_circle
		(center 332.9178 -43.3578)
		(end 333.8068 -43.3578)
		(stroke
			(width 0.2)
			(type default)
		)
		(fill no)
		(layer "In8.Cu")
	)
	(gr_circle
		(center 332.9178 -42.5958)
		(end 333.8068 -42.5958)
		(stroke
			(width 0.2)
			(type default)
		)
		(fill no)
		(layer "In8.Cu")
	)
	(gr_circle
		(center 332.9178 -34.3662)
		(end 333.8068 -34.3662)
		(stroke
			(width 0.2)
			(type default)
		)
		(fill no)
		(layer "In8.Cu")
	)
	(gr_circle
		(center 332.9178 -33.6042)
		(end 333.8068 -33.6042)
		(stroke
			(width 0.2)
			(type default)
		)
		(fill no)
		(layer "In8.Cu")
	)
	(gr_circle
		(center 332.9178 -32.8422)
		(end 333.8068 -32.8422)
		(stroke
			(width 0.2)
			(type default)
		)
		(fill no)
		(layer "In8.Cu")
	)
	(gr_circle
		(center 332.9178 -32.0802)
		(end 333.8068 -32.0802)
		(stroke
			(width 0.2)
			(type default)
		)
		(fill no)
		(layer "In8.Cu")
	)
	(gr_circle
		(center 332.9178 -31.3182)
		(end 333.8068 -31.3182)
		(stroke
			(width 0.2)
			(type default)
		)
		(fill no)
		(layer "In8.Cu")
	)
	(gr_circle
		(center 332.9178 -23.0886)
		(end 333.8068 -23.0886)
		(stroke
			(width 0.2)
			(type default)
		)
		(fill no)
		(layer "In8.Cu")
	)
	(gr_circle
		(center 332.9178 -22.3266)
		(end 333.8068 -22.3266)
		(stroke
			(width 0.2)
			(type default)
		)
		(fill no)
		(layer "In8.Cu")
	)
	(gr_circle
		(center 332.9178 -21.5646)
		(end 333.8068 -21.5646)
		(stroke
			(width 0.2)
			(type default)
		)
		(fill no)
		(layer "In8.Cu")
	)
	(gr_circle
		(center 332.9178 -20.8026)
		(end 333.8068 -20.8026)
		(stroke
			(width 0.2)
			(type default)
		)
		(fill no)
		(layer "In8.Cu")
	)
	(gr_circle
		(center 332.9178 -20.0406)
		(end 333.8068 -20.0406)
		(stroke
			(width 0.2)
			(type default)
		)
		(fill no)
		(layer "In8.Cu")
	)
	(gr_circle
		(center 333.6798 -78.7146)
		(end 334.5688 -78.7146)
		(stroke
			(width 0.2)
			(type default)
		)
		(fill no)
		(layer "In8.Cu")
	)
	(gr_circle
		(center 333.6798 -77.9526)
		(end 334.5688 -77.9526)
		(stroke
			(width 0.2)
			(type default)
		)
		(fill no)
		(layer "In8.Cu")
	)
	(gr_circle
		(center 333.6798 -77.1906)
		(end 334.5688 -77.1906)
		(stroke
			(width 0.2)
			(type default)
		)
		(fill no)
		(layer "In8.Cu")
	)
	(gr_circle
		(center 333.6798 -76.4286)
		(end 334.5688 -76.4286)
		(stroke
			(width 0.2)
			(type default)
		)
		(fill no)
		(layer "In8.Cu")
	)
	(gr_circle
		(center 333.6798 -68.199)
		(end 334.5688 -68.199)
		(stroke
			(width 0.2)
			(type default)
		)
		(fill no)
		(layer "In8.Cu")
	)
	(gr_circle
		(center 333.6798 -67.437)
		(end 334.5688 -67.437)
		(stroke
			(width 0.2)
			(type default)
		)
		(fill no)
		(layer "In8.Cu")
	)
	(gr_circle
		(center 333.6798 -66.675)
		(end 334.5688 -66.675)
		(stroke
			(width 0.2)
			(type default)
		)
		(fill no)
		(layer "In8.Cu")
	)
	(gr_circle
		(center 333.6798 -65.913)
		(end 334.5688 -65.913)
		(stroke
			(width 0.2)
			(type default)
		)
		(fill no)
		(layer "In8.Cu")
	)
	(gr_circle
		(center 333.6798 -65.151)
		(end 334.5688 -65.151)
		(stroke
			(width 0.2)
			(type default)
		)
		(fill no)
		(layer "In8.Cu")
	)
	(gr_circle
		(center 333.6798 -56.9214)
		(end 334.5688 -56.9214)
		(stroke
			(width 0.2)
			(type default)
		)
		(fill no)
		(layer "In8.Cu")
	)
	(gr_circle
		(center 333.6798 -56.1594)
		(end 334.5688 -56.1594)
		(stroke
			(width 0.2)
			(type default)
		)
		(fill no)
		(layer "In8.Cu")
	)
	(gr_circle
		(center 333.6798 -55.3974)
		(end 334.5688 -55.3974)
		(stroke
			(width 0.2)
			(type default)
		)
		(fill no)
		(layer "In8.Cu")
	)
	(gr_circle
		(center 333.6798 -54.6354)
		(end 334.5688 -54.6354)
		(stroke
			(width 0.2)
			(type default)
		)
		(fill no)
		(layer "In8.Cu")
	)
	(gr_circle
		(center 333.6798 -53.8734)
		(end 334.5688 -53.8734)
		(stroke
			(width 0.2)
			(type default)
		)
		(fill no)
		(layer "In8.Cu")
	)
	(gr_circle
		(center 333.6798 -45.6438)
		(end 334.5688 -45.6438)
		(stroke
			(width 0.2)
			(type default)
		)
		(fill no)
		(layer "In8.Cu")
	)
	(gr_circle
		(center 333.6798 -44.8818)
		(end 334.5688 -44.8818)
		(stroke
			(width 0.2)
			(type default)
		)
		(fill no)
		(layer "In8.Cu")
	)
	(gr_circle
		(center 333.6798 -44.1198)
		(end 334.5688 -44.1198)
		(stroke
			(width 0.2)
			(type default)
		)
		(fill no)
		(layer "In8.Cu")
	)
	(gr_circle
		(center 333.6798 -43.3578)
		(end 334.5688 -43.3578)
		(stroke
			(width 0.2)
			(type default)
		)
		(fill no)
		(layer "In8.Cu")
	)
	(gr_circle
		(center 333.6798 -42.5958)
		(end 334.5688 -42.5958)
		(stroke
			(width 0.2)
			(type default)
		)
		(fill no)
		(layer "In8.Cu")
	)
	(gr_circle
		(center 333.6798 -34.3662)
		(end 334.5688 -34.3662)
		(stroke
			(width 0.2)
			(type default)
		)
		(fill no)
		(layer "In8.Cu")
	)
	(gr_circle
		(center 333.6798 -33.6042)
		(end 334.5688 -33.6042)
		(stroke
			(width 0.2)
			(type default)
		)
		(fill no)
		(layer "In8.Cu")
	)
	(gr_circle
		(center 333.6798 -32.8422)
		(end 334.5688 -32.8422)
		(stroke
			(width 0.2)
			(type default)
		)
		(fill no)
		(layer "In8.Cu")
	)
	(gr_circle
		(center 333.6798 -32.0802)
		(end 334.5688 -32.0802)
		(stroke
			(width 0.2)
			(type default)
		)
		(fill no)
		(layer "In8.Cu")
	)
	(gr_circle
		(center 333.6798 -31.3182)
		(end 334.5688 -31.3182)
		(stroke
			(width 0.2)
			(type default)
		)
		(fill no)
		(layer "In8.Cu")
	)
	(gr_circle
		(center 333.6798 -23.0886)
		(end 334.5688 -23.0886)
		(stroke
			(width 0.2)
			(type default)
		)
		(fill no)
		(layer "In8.Cu")
	)
	(gr_circle
		(center 333.6798 -22.3266)
		(end 334.5688 -22.3266)
		(stroke
			(width 0.2)
			(type default)
		)
		(fill no)
		(layer "In8.Cu")
	)
	(gr_circle
		(center 333.6798 -21.5646)
		(end 334.5688 -21.5646)
		(stroke
			(width 0.2)
			(type default)
		)
		(fill no)
		(layer "In8.Cu")
	)
	(gr_circle
		(center 333.6798 -20.8026)
		(end 334.5688 -20.8026)
		(stroke
			(width 0.2)
			(type default)
		)
		(fill no)
		(layer "In8.Cu")
	)
	(gr_circle
		(center 333.6798 -20.0406)
		(end 334.5688 -20.0406)
		(stroke
			(width 0.2)
			(type default)
		)
		(fill no)
		(layer "In8.Cu")
	)
	(gr_circle
		(center 334.4418 -77.9526)
		(end 335.3308 -77.9526)
		(stroke
			(width 0.2)
			(type default)
		)
		(fill no)
		(layer "In8.Cu")
	)
	(gr_circle
		(center 334.4418 -77.1906)
		(end 335.3308 -77.1906)
		(stroke
			(width 0.2)
			(type default)
		)
		(fill no)
		(layer "In8.Cu")
	)
	(gr_circle
		(center 334.4418 -76.4286)
		(end 335.3308 -76.4286)
		(stroke
			(width 0.2)
			(type default)
		)
		(fill no)
		(layer "In8.Cu")
	)
	(gr_circle
		(center 334.4418 -68.199)
		(end 335.3308 -68.199)
		(stroke
			(width 0.2)
			(type default)
		)
		(fill no)
		(layer "In8.Cu")
	)
	(gr_circle
		(center 334.4418 -67.437)
		(end 335.3308 -67.437)
		(stroke
			(width 0.2)
			(type default)
		)
		(fill no)
		(layer "In8.Cu")
	)
	(gr_circle
		(center 334.4418 -66.675)
		(end 335.3308 -66.675)
		(stroke
			(width 0.2)
			(type default)
		)
		(fill no)
		(layer "In8.Cu")
	)
	(gr_circle
		(center 334.4418 -65.913)
		(end 335.3308 -65.913)
		(stroke
			(width 0.2)
			(type default)
		)
		(fill no)
		(layer "In8.Cu")
	)
	(gr_circle
		(center 334.4418 -65.151)
		(end 335.3308 -65.151)
		(stroke
			(width 0.2)
			(type default)
		)
		(fill no)
		(layer "In8.Cu")
	)
	(gr_circle
		(center 334.4418 -56.9214)
		(end 335.3308 -56.9214)
		(stroke
			(width 0.2)
			(type default)
		)
		(fill no)
		(layer "In8.Cu")
	)
	(gr_circle
		(center 334.4418 -56.1594)
		(end 335.3308 -56.1594)
		(stroke
			(width 0.2)
			(type default)
		)
		(fill no)
		(layer "In8.Cu")
	)
	(gr_circle
		(center 334.4418 -55.3974)
		(end 335.3308 -55.3974)
		(stroke
			(width 0.2)
			(type default)
		)
		(fill no)
		(layer "In8.Cu")
	)
	(gr_circle
		(center 334.4418 -54.6354)
		(end 335.3308 -54.6354)
		(stroke
			(width 0.2)
			(type default)
		)
		(fill no)
		(layer "In8.Cu")
	)
	(gr_circle
		(center 334.4418 -53.8734)
		(end 335.3308 -53.8734)
		(stroke
			(width 0.2)
			(type default)
		)
		(fill no)
		(layer "In8.Cu")
	)
	(gr_circle
		(center 334.4418 -44.8818)
		(end 335.3308 -44.8818)
		(stroke
			(width 0.2)
			(type default)
		)
		(fill no)
		(layer "In8.Cu")
	)
	(gr_circle
		(center 334.4418 -44.1198)
		(end 335.3308 -44.1198)
		(stroke
			(width 0.2)
			(type default)
		)
		(fill no)
		(layer "In8.Cu")
	)
	(gr_circle
		(center 334.4418 -43.3578)
		(end 335.3308 -43.3578)
		(stroke
			(width 0.2)
			(type default)
		)
		(fill no)
		(layer "In8.Cu")
	)
	(gr_circle
		(center 334.4418 -42.5958)
		(end 335.3308 -42.5958)
		(stroke
			(width 0.2)
			(type default)
		)
		(fill no)
		(layer "In8.Cu")
	)
	(gr_circle
		(center 334.4418 -34.3662)
		(end 335.3308 -34.3662)
		(stroke
			(width 0.2)
			(type default)
		)
		(fill no)
		(layer "In8.Cu")
	)
	(gr_circle
		(center 334.4418 -33.6042)
		(end 335.3308 -33.6042)
		(stroke
			(width 0.2)
			(type default)
		)
		(fill no)
		(layer "In8.Cu")
	)
	(gr_circle
		(center 334.4418 -32.8422)
		(end 335.3308 -32.8422)
		(stroke
			(width 0.2)
			(type default)
		)
		(fill no)
		(layer "In8.Cu")
	)
	(gr_circle
		(center 334.4418 -32.0802)
		(end 335.3308 -32.0802)
		(stroke
			(width 0.2)
			(type default)
		)
		(fill no)
		(layer "In8.Cu")
	)
	(gr_circle
		(center 334.4418 -31.3182)
		(end 335.3308 -31.3182)
		(stroke
			(width 0.2)
			(type default)
		)
		(fill no)
		(layer "In8.Cu")
	)
	(gr_circle
		(center 334.4418 -23.0886)
		(end 335.3308 -23.0886)
		(stroke
			(width 0.2)
			(type default)
		)
		(fill no)
		(layer "In8.Cu")
	)
	(gr_circle
		(center 334.4418 -22.3266)
		(end 335.3308 -22.3266)
		(stroke
			(width 0.2)
			(type default)
		)
		(fill no)
		(layer "In8.Cu")
	)
	(gr_circle
		(center 334.4418 -21.5646)
		(end 335.3308 -21.5646)
		(stroke
			(width 0.2)
			(type default)
		)
		(fill no)
		(layer "In8.Cu")
	)
	(gr_circle
		(center 334.4418 -20.8026)
		(end 335.3308 -20.8026)
		(stroke
			(width 0.2)
			(type default)
		)
		(fill no)
		(layer "In8.Cu")
	)
	(gr_circle
		(center 334.4418 -20.0406)
		(end 335.3308 -20.0406)
		(stroke
			(width 0.2)
			(type default)
		)
		(fill no)
		(layer "In8.Cu")
	)
	(gr_circle
		(center 335.2038 -77.1906)
		(end 336.0928 -77.1906)
		(stroke
			(width 0.2)
			(type default)
		)
		(fill no)
		(layer "In8.Cu")
	)
	(gr_circle
		(center 335.2038 -76.4286)
		(end 336.0928 -76.4286)
		(stroke
			(width 0.2)
			(type default)
		)
		(fill no)
		(layer "In8.Cu")
	)
	(gr_circle
		(center 335.2038 -68.199)
		(end 336.0928 -68.199)
		(stroke
			(width 0.2)
			(type default)
		)
		(fill no)
		(layer "In8.Cu")
	)
	(gr_circle
		(center 335.2038 -67.437)
		(end 336.0928 -67.437)
		(stroke
			(width 0.2)
			(type default)
		)
		(fill no)
		(layer "In8.Cu")
	)
	(gr_circle
		(center 335.2038 -66.675)
		(end 336.0928 -66.675)
		(stroke
			(width 0.2)
			(type default)
		)
		(fill no)
		(layer "In8.Cu")
	)
	(gr_circle
		(center 335.2038 -65.913)
		(end 336.0928 -65.913)
		(stroke
			(width 0.2)
			(type default)
		)
		(fill no)
		(layer "In8.Cu")
	)
	(gr_circle
		(center 335.2038 -65.151)
		(end 336.0928 -65.151)
		(stroke
			(width 0.2)
			(type default)
		)
		(fill no)
		(layer "In8.Cu")
	)
	(gr_circle
		(center 335.2038 -56.9214)
		(end 336.0928 -56.9214)
		(stroke
			(width 0.2)
			(type default)
		)
		(fill no)
		(layer "In8.Cu")
	)
	(gr_circle
		(center 335.2038 -56.1594)
		(end 336.0928 -56.1594)
		(stroke
			(width 0.2)
			(type default)
		)
		(fill no)
		(layer "In8.Cu")
	)
	(gr_circle
		(center 335.2038 -55.3974)
		(end 336.0928 -55.3974)
		(stroke
			(width 0.2)
			(type default)
		)
		(fill no)
		(layer "In8.Cu")
	)
	(gr_circle
		(center 335.2038 -54.6354)
		(end 336.0928 -54.6354)
		(stroke
			(width 0.2)
			(type default)
		)
		(fill no)
		(layer "In8.Cu")
	)
	(gr_circle
		(center 335.2038 -53.8734)
		(end 336.0928 -53.8734)
		(stroke
			(width 0.2)
			(type default)
		)
		(fill no)
		(layer "In8.Cu")
	)
	(gr_circle
		(center 335.2038 -44.8818)
		(end 336.0928 -44.8818)
		(stroke
			(width 0.2)
			(type default)
		)
		(fill no)
		(layer "In8.Cu")
	)
	(gr_circle
		(center 335.2038 -44.1198)
		(end 336.0928 -44.1198)
		(stroke
			(width 0.2)
			(type default)
		)
		(fill no)
		(layer "In8.Cu")
	)
	(gr_circle
		(center 335.2038 -43.3578)
		(end 336.0928 -43.3578)
		(stroke
			(width 0.2)
			(type default)
		)
		(fill no)
		(layer "In8.Cu")
	)
	(gr_circle
		(center 335.2038 -42.5958)
		(end 336.0928 -42.5958)
		(stroke
			(width 0.2)
			(type default)
		)
		(fill no)
		(layer "In8.Cu")
	)
	(gr_circle
		(center 335.2038 -34.3662)
		(end 336.0928 -34.3662)
		(stroke
			(width 0.2)
			(type default)
		)
		(fill no)
		(layer "In8.Cu")
	)
	(gr_circle
		(center 335.2038 -33.6042)
		(end 336.0928 -33.6042)
		(stroke
			(width 0.2)
			(type default)
		)
		(fill no)
		(layer "In8.Cu")
	)
	(gr_circle
		(center 335.2038 -32.8422)
		(end 336.0928 -32.8422)
		(stroke
			(width 0.2)
			(type default)
		)
		(fill no)
		(layer "In8.Cu")
	)
	(gr_circle
		(center 335.2038 -32.0802)
		(end 336.0928 -32.0802)
		(stroke
			(width 0.2)
			(type default)
		)
		(fill no)
		(layer "In8.Cu")
	)
	(gr_circle
		(center 335.2038 -31.3182)
		(end 336.0928 -31.3182)
		(stroke
			(width 0.2)
			(type default)
		)
		(fill no)
		(layer "In8.Cu")
	)
	(gr_circle
		(center 335.2038 -23.0886)
		(end 336.0928 -23.0886)
		(stroke
			(width 0.2)
			(type default)
		)
		(fill no)
		(layer "In8.Cu")
	)
	(gr_circle
		(center 335.2038 -22.3266)
		(end 336.0928 -22.3266)
		(stroke
			(width 0.2)
			(type default)
		)
		(fill no)
		(layer "In8.Cu")
	)
	(gr_circle
		(center 335.2038 -21.5646)
		(end 336.0928 -21.5646)
		(stroke
			(width 0.2)
			(type default)
		)
		(fill no)
		(layer "In8.Cu")
	)
	(gr_circle
		(center 335.2038 -20.8026)
		(end 336.0928 -20.8026)
		(stroke
			(width 0.2)
			(type default)
		)
		(fill no)
		(layer "In8.Cu")
	)
	(gr_circle
		(center 335.2038 -20.0406)
		(end 336.0928 -20.0406)
		(stroke
			(width 0.2)
			(type default)
		)
		(fill no)
		(layer "In8.Cu")
	)
	(gr_circle
		(center 335.367884 -73.6346)
		(end 336.256884 -73.6346)
		(stroke
			(width 0.2)
			(type default)
		)
		(fill no)
		(layer "In8.Cu")
	)
	(gr_circle
		(center 335.367884 -62.357)
		(end 336.256884 -62.357)
		(stroke
			(width 0.2)
			(type default)
		)
		(fill no)
		(layer "In8.Cu")
	)
	(gr_circle
		(center 335.367884 -51.0794)
		(end 336.256884 -51.0794)
		(stroke
			(width 0.2)
			(type default)
		)
		(fill no)
		(layer "In8.Cu")
	)
	(gr_circle
		(center 335.367884 -39.8018)
		(end 336.256884 -39.8018)
		(stroke
			(width 0.2)
			(type default)
		)
		(fill no)
		(layer "In8.Cu")
	)
	(gr_circle
		(center 335.367884 -28.5242)
		(end 336.256884 -28.5242)
		(stroke
			(width 0.2)
			(type default)
		)
		(fill no)
		(layer "In8.Cu")
	)
	(gr_circle
		(center 335.367884 -17.2466)
		(end 336.256884 -17.2466)
		(stroke
			(width 0.2)
			(type default)
		)
		(fill no)
		(layer "In8.Cu")
	)
	(gr_circle
		(center 336.3214 -49.5046)
		(end 337.2104 -49.5046)
		(stroke
			(width 0.2)
			(type default)
		)
		(fill no)
		(layer "In8.Cu")
	)
	(gr_circle
		(center 336.3214 -38.227)
		(end 337.2104 -38.227)
		(stroke
			(width 0.2)
			(type default)
		)
		(fill no)
		(layer "In8.Cu")
	)
	(gr_circle
		(center 338.498434 -48.423576)
		(end 339.387434 -48.423576)
		(stroke
			(width 0.2)
			(type default)
		)
		(fill no)
		(layer "In8.Cu")
	)
	(gr_circle
		(center 338.87156 -37.247068)
		(end 339.76056 -37.247068)
		(stroke
			(width 0.2)
			(type default)
		)
		(fill no)
		(layer "In8.Cu")
	)
	(gr_circle
		(center 354.89642 -5.353304)
		(end 355.78542 -5.353304)
		(stroke
			(width 0.2)
			(type default)
		)
		(fill no)
		(layer "In8.Cu")
	)
	(gr_circle
		(center 354.89642 -4.591304)
		(end 355.78542 -4.591304)
		(stroke
			(width 0.2)
			(type default)
		)
		(fill no)
		(layer "In8.Cu")
	)
	(gr_circle
		(center 354.89642 -3.829304)
		(end 355.78542 -3.829304)
		(stroke
			(width 0.2)
			(type default)
		)
		(fill no)
		(layer "In8.Cu")
	)
	(gr_circle
		(center 355.65842 -5.353304)
		(end 356.54742 -5.353304)
		(stroke
			(width 0.2)
			(type default)
		)
		(fill no)
		(layer "In8.Cu")
	)
	(gr_circle
		(center 355.65842 -4.591304)
		(end 356.54742 -4.591304)
		(stroke
			(width 0.2)
			(type default)
		)
		(fill no)
		(layer "In8.Cu")
	)
	(gr_circle
		(center 355.65842 -3.829304)
		(end 356.54742 -3.829304)
		(stroke
			(width 0.2)
			(type default)
		)
		(fill no)
		(layer "In8.Cu")
	)
	(gr_circle
		(center 356.42042 -5.353304)
		(end 357.30942 -5.353304)
		(stroke
			(width 0.2)
			(type default)
		)
		(fill no)
		(layer "In8.Cu")
	)
	(gr_circle
		(center 356.42042 -4.591304)
		(end 357.30942 -4.591304)
		(stroke
			(width 0.2)
			(type default)
		)
		(fill no)
		(layer "In8.Cu")
	)
	(gr_circle
		(center 356.42042 -3.829304)
		(end 357.30942 -3.829304)
		(stroke
			(width 0.2)
			(type default)
		)
		(fill no)
		(layer "In8.Cu")
	)
	(gr_circle
		(center 357.18242 -5.353304)
		(end 358.07142 -5.353304)
		(stroke
			(width 0.2)
			(type default)
		)
		(fill no)
		(layer "In8.Cu")
	)
	(gr_circle
		(center 357.18242 -4.591304)
		(end 358.07142 -4.591304)
		(stroke
			(width 0.2)
			(type default)
		)
		(fill no)
		(layer "In8.Cu")
	)
	(gr_circle
		(center 357.18242 -3.829304)
		(end 358.07142 -3.829304)
		(stroke
			(width 0.2)
			(type default)
		)
		(fill no)
		(layer "In8.Cu")
	)
	(gr_circle
		(center 357.94442 -5.353304)
		(end 358.83342 -5.353304)
		(stroke
			(width 0.2)
			(type default)
		)
		(fill no)
		(layer "In8.Cu")
	)
	(gr_circle
		(center 357.94442 -4.591304)
		(end 358.83342 -4.591304)
		(stroke
			(width 0.2)
			(type default)
		)
		(fill no)
		(layer "In8.Cu")
	)
	(gr_circle
		(center 357.94442 -3.829304)
		(end 358.83342 -3.829304)
		(stroke
			(width 0.2)
			(type default)
		)
		(fill no)
		(layer "In8.Cu")
	)
	(gr_circle
		(center 358.70642 -5.353304)
		(end 359.59542 -5.353304)
		(stroke
			(width 0.2)
			(type default)
		)
		(fill no)
		(layer "In8.Cu")
	)
	(gr_circle
		(center 358.70642 -4.591304)
		(end 359.59542 -4.591304)
		(stroke
			(width 0.2)
			(type default)
		)
		(fill no)
		(layer "In8.Cu")
	)
	(gr_circle
		(center 358.70642 -3.829304)
		(end 359.59542 -3.829304)
		(stroke
			(width 0.2)
			(type default)
		)
		(fill no)
		(layer "In8.Cu")
	)
	(gr_circle
		(center 363.000036 -160.830006)
		(end 364.21314 -160.830006)
		(stroke
			(width 0.2)
			(type default)
		)
		(fill no)
		(layer "In8.Cu")
	)
	(gr_circle
		(center 363.000036 -158.83001)
		(end 364.21314 -158.83001)
		(stroke
			(width 0.2)
			(type default)
		)
		(fill no)
		(layer "In8.Cu")
	)
	(gr_circle
		(center 363.000036 -156.830014)
		(end 364.21314 -156.830014)
		(stroke
			(width 0.2)
			(type default)
		)
		(fill no)
		(layer "In8.Cu")
	)
	(gr_circle
		(center 364.123478 -159.82061)
		(end 365.336582 -159.82061)
		(stroke
			(width 0.2)
			(type default)
		)
		(fill no)
		(layer "In8.Cu")
	)
	(gr_circle
		(center 364.123478 -157.820614)
		(end 365.336582 -157.820614)
		(stroke
			(width 0.2)
			(type default)
		)
		(fill no)
		(layer "In8.Cu")
	)
	(gr_circle
		(center 365.000032 -160.830006)
		(end 366.213136 -160.830006)
		(stroke
			(width 0.2)
			(type default)
		)
		(fill no)
		(layer "In8.Cu")
	)
	(gr_circle
		(center 365.000032 -158.83001)
		(end 366.213136 -158.83001)
		(stroke
			(width 0.2)
			(type default)
		)
		(fill no)
		(layer "In8.Cu")
	)
	(gr_circle
		(center 365.000032 -156.830014)
		(end 366.213136 -156.830014)
		(stroke
			(width 0.2)
			(type default)
		)
		(fill no)
		(layer "In8.Cu")
	)
	(gr_circle
		(center 366.119918 -2.590038)
		(end 367.333022 -2.590038)
		(stroke
			(width 0.2)
			(type default)
		)
		(fill no)
		(layer "In8.Cu")
	)
	(gr_circle
		(center 368.659918 -2.590038)
		(end 369.873022 -2.590038)
		(stroke
			(width 0.2)
			(type default)
		)
		(fill no)
		(layer "In8.Cu")
	)
	(gr_circle
		(center 369.000024 -160.830006)
		(end 370.213128 -160.830006)
		(stroke
			(width 0.2)
			(type default)
		)
		(fill no)
		(layer "In8.Cu")
	)
	(gr_circle
		(center 369.000024 -158.83001)
		(end 370.213128 -158.83001)
		(stroke
			(width 0.2)
			(type default)
		)
		(fill no)
		(layer "In8.Cu")
	)
	(gr_circle
		(center 369.000024 -156.830014)
		(end 370.213128 -156.830014)
		(stroke
			(width 0.2)
			(type default)
		)
		(fill no)
		(layer "In8.Cu")
	)
	(gr_circle
		(center 369.990878 -159.87141)
		(end 371.203982 -159.87141)
		(stroke
			(width 0.2)
			(type default)
		)
		(fill no)
		(layer "In8.Cu")
	)
	(gr_circle
		(center 369.990878 -157.871414)
		(end 371.203982 -157.871414)
		(stroke
			(width 0.2)
			(type default)
		)
		(fill no)
		(layer "In8.Cu")
	)
	(gr_circle
		(center 371.00002 -160.830006)
		(end 372.213124 -160.830006)
		(stroke
			(width 0.2)
			(type default)
		)
		(fill no)
		(layer "In8.Cu")
	)
	(gr_circle
		(center 371.00002 -158.83001)
		(end 372.213124 -158.83001)
		(stroke
			(width 0.2)
			(type default)
		)
		(fill no)
		(layer "In8.Cu")
	)
	(gr_circle
		(center 371.00002 -156.830014)
		(end 372.213124 -156.830014)
		(stroke
			(width 0.2)
			(type default)
		)
		(fill no)
		(layer "In8.Cu")
	)
	(gr_circle
		(center 375.000012 -160.830006)
		(end 376.213116 -160.830006)
		(stroke
			(width 0.2)
			(type default)
		)
		(fill no)
		(layer "In8.Cu")
	)
	(gr_circle
		(center 375.000012 -158.83001)
		(end 376.213116 -158.83001)
		(stroke
			(width 0.2)
			(type default)
		)
		(fill no)
		(layer "In8.Cu")
	)
	(gr_circle
		(center 375.000012 -156.830014)
		(end 376.213116 -156.830014)
		(stroke
			(width 0.2)
			(type default)
		)
		(fill no)
		(layer "In8.Cu")
	)
	(gr_circle
		(center 375.909078 -159.79521)
		(end 377.122182 -159.79521)
		(stroke
			(width 0.2)
			(type default)
		)
		(fill no)
		(layer "In8.Cu")
	)
	(gr_circle
		(center 375.909078 -157.795214)
		(end 377.122182 -157.795214)
		(stroke
			(width 0.2)
			(type default)
		)
		(fill no)
		(layer "In8.Cu")
	)
	(gr_circle
		(center 377.000008 -160.830006)
		(end 378.213112 -160.830006)
		(stroke
			(width 0.2)
			(type default)
		)
		(fill no)
		(layer "In8.Cu")
	)
	(gr_circle
		(center 377.000008 -158.83001)
		(end 378.213112 -158.83001)
		(stroke
			(width 0.2)
			(type default)
		)
		(fill no)
		(layer "In8.Cu")
	)
	(gr_circle
		(center 377.000008 -156.830014)
		(end 378.213112 -156.830014)
		(stroke
			(width 0.2)
			(type default)
		)
		(fill no)
		(layer "In8.Cu")
	)
	(gr_circle
		(center 378.079 -139.7)
		(end 379.603 -139.7)
		(stroke
			(width 0.2)
			(type default)
		)
		(fill no)
		(layer "In8.Cu")
	)
	(gr_circle
		(center 378.079 -119.38)
		(end 379.603 -119.38)
		(stroke
			(width 0.2)
			(type default)
		)
		(fill no)
		(layer "In8.Cu")
	)
	(gr_circle
		(center 378.079 -99.06)
		(end 379.603 -99.06)
		(stroke
			(width 0.2)
			(type default)
		)
		(fill no)
		(layer "In8.Cu")
	)
	(gr_circle
		(center 378.079 -78.74)
		(end 379.603 -78.74)
		(stroke
			(width 0.2)
			(type default)
		)
		(fill no)
		(layer "In8.Cu")
	)
	(gr_circle
		(center 378.079 -58.42)
		(end 379.603 -58.42)
		(stroke
			(width 0.2)
			(type default)
		)
		(fill no)
		(layer "In8.Cu")
	)
	(gr_circle
		(center 383.199894 -160.830006)
		(end 384.412998 -160.830006)
		(stroke
			(width 0.2)
			(type default)
		)
		(fill no)
		(layer "In8.Cu")
	)
	(gr_circle
		(center 383.199894 -158.83001)
		(end 384.412998 -158.83001)
		(stroke
			(width 0.2)
			(type default)
		)
		(fill no)
		(layer "In8.Cu")
	)
	(gr_circle
		(center 383.199894 -156.830014)
		(end 384.412998 -156.830014)
		(stroke
			(width 0.2)
			(type default)
		)
		(fill no)
		(layer "In8.Cu")
	)
	(gr_circle
		(center 384.062478 -159.64281)
		(end 385.275582 -159.64281)
		(stroke
			(width 0.2)
			(type default)
		)
		(fill no)
		(layer "In8.Cu")
	)
	(gr_circle
		(center 384.062478 -157.642814)
		(end 385.275582 -157.642814)
		(stroke
			(width 0.2)
			(type default)
		)
		(fill no)
		(layer "In8.Cu")
	)
	(gr_circle
		(center 385.19989 -160.830006)
		(end 386.412994 -160.830006)
		(stroke
			(width 0.2)
			(type default)
		)
		(fill no)
		(layer "In8.Cu")
	)
	(gr_circle
		(center 385.19989 -158.83001)
		(end 386.412994 -158.83001)
		(stroke
			(width 0.2)
			(type default)
		)
		(fill no)
		(layer "In8.Cu")
	)
	(gr_circle
		(center 385.19989 -156.830014)
		(end 386.412994 -156.830014)
		(stroke
			(width 0.2)
			(type default)
		)
		(fill no)
		(layer "In8.Cu")
	)
	(gr_circle
		(center 389.199882 -160.830006)
		(end 390.412986 -160.830006)
		(stroke
			(width 0.2)
			(type default)
		)
		(fill no)
		(layer "In8.Cu")
	)
	(gr_circle
		(center 389.199882 -158.83001)
		(end 390.412986 -158.83001)
		(stroke
			(width 0.2)
			(type default)
		)
		(fill no)
		(layer "In8.Cu")
	)
	(gr_circle
		(center 389.199882 -156.830014)
		(end 390.412986 -156.830014)
		(stroke
			(width 0.2)
			(type default)
		)
		(fill no)
		(layer "In8.Cu")
	)
	(gr_circle
		(center 390.158478 -159.71901)
		(end 391.371582 -159.71901)
		(stroke
			(width 0.2)
			(type default)
		)
		(fill no)
		(layer "In8.Cu")
	)
	(gr_circle
		(center 390.158478 -157.719014)
		(end 391.371582 -157.719014)
		(stroke
			(width 0.2)
			(type default)
		)
		(fill no)
		(layer "In8.Cu")
	)
	(gr_circle
		(center 391.199878 -160.830006)
		(end 392.412982 -160.830006)
		(stroke
			(width 0.2)
			(type default)
		)
		(fill no)
		(layer "In8.Cu")
	)
	(gr_circle
		(center 391.199878 -158.83001)
		(end 392.412982 -158.83001)
		(stroke
			(width 0.2)
			(type default)
		)
		(fill no)
		(layer "In8.Cu")
	)
	(gr_circle
		(center 391.199878 -156.830014)
		(end 392.412982 -156.830014)
		(stroke
			(width 0.2)
			(type default)
		)
		(fill no)
		(layer "In8.Cu")
	)
	(gr_circle
		(center 397.637 -139.7)
		(end 399.161 -139.7)
		(stroke
			(width 0.2)
			(type default)
		)
		(fill no)
		(layer "In8.Cu")
	)
	(gr_circle
		(center 397.637 -119.38)
		(end 399.161 -119.38)
		(stroke
			(width 0.2)
			(type default)
		)
		(fill no)
		(layer "In8.Cu")
	)
	(gr_circle
		(center 397.637 -99.06)
		(end 399.161 -99.06)
		(stroke
			(width 0.2)
			(type default)
		)
		(fill no)
		(layer "In8.Cu")
	)
	(gr_circle
		(center 397.637 -78.74)
		(end 399.161 -78.74)
		(stroke
			(width 0.2)
			(type default)
		)
		(fill no)
		(layer "In8.Cu")
	)
	(gr_circle
		(center 397.637 -58.42)
		(end 399.161 -58.42)
		(stroke
			(width 0.2)
			(type default)
		)
		(fill no)
		(layer "In8.Cu")
	)
	(gr_circle
		(center 398.375124 -168.82999)
		(end 399.588228 -168.82999)
		(stroke
			(width 0.2)
			(type default)
		)
		(fill no)
		(layer "In8.Cu")
	)
	(gr_circle
		(center 398.375124 -166.829994)
		(end 399.588228 -166.829994)
		(stroke
			(width 0.2)
			(type default)
		)
		(fill no)
		(layer "In8.Cu")
	)
	(gr_circle
		(center 398.375124 -164.829998)
		(end 399.588228 -164.829998)
		(stroke
			(width 0.2)
			(type default)
		)
		(fill no)
		(layer "In8.Cu")
	)
	(gr_circle
		(center 398.375124 -162.830002)
		(end 399.588228 -162.830002)
		(stroke
			(width 0.2)
			(type default)
		)
		(fill no)
		(layer "In8.Cu")
	)
	(gr_circle
		(center 398.375124 -160.830006)
		(end 399.588228 -160.830006)
		(stroke
			(width 0.2)
			(type default)
		)
		(fill no)
		(layer "In8.Cu")
	)
	(gr_circle
		(center 398.375124 -158.83001)
		(end 399.588228 -158.83001)
		(stroke
			(width 0.2)
			(type default)
		)
		(fill no)
		(layer "In8.Cu")
	)
	(gr_circle
		(center 398.375124 -156.830014)
		(end 399.588228 -156.830014)
		(stroke
			(width 0.2)
			(type default)
		)
		(fill no)
		(layer "In8.Cu")
	)
	(gr_circle
		(center 398.375124 -154.830018)
		(end 399.588228 -154.830018)
		(stroke
			(width 0.2)
			(type default)
		)
		(fill no)
		(layer "In8.Cu")
	)
	(gr_circle
		(center 398.375124 -152.830022)
		(end 399.588228 -152.830022)
		(stroke
			(width 0.2)
			(type default)
		)
		(fill no)
		(layer "In8.Cu")
	)
	(gr_circle
		(center 399.40992 -167.591994)
		(end 400.623024 -167.591994)
		(stroke
			(width 0.2)
			(type default)
		)
		(fill no)
		(layer "In8.Cu")
	)
	(gr_circle
		(center 399.40992 -165.591998)
		(end 400.623024 -165.591998)
		(stroke
			(width 0.2)
			(type default)
		)
		(fill no)
		(layer "In8.Cu")
	)
	(gr_circle
		(center 399.40992 -163.592002)
		(end 400.623024 -163.592002)
		(stroke
			(width 0.2)
			(type default)
		)
		(fill no)
		(layer "In8.Cu")
	)
	(gr_circle
		(center 399.40992 -161.592006)
		(end 400.623024 -161.592006)
		(stroke
			(width 0.2)
			(type default)
		)
		(fill no)
		(layer "In8.Cu")
	)
	(gr_circle
		(center 399.40992 -159.59201)
		(end 400.623024 -159.59201)
		(stroke
			(width 0.2)
			(type default)
		)
		(fill no)
		(layer "In8.Cu")
	)
	(gr_circle
		(center 399.40992 -157.592014)
		(end 400.623024 -157.592014)
		(stroke
			(width 0.2)
			(type default)
		)
		(fill no)
		(layer "In8.Cu")
	)
	(gr_circle
		(center 399.40992 -155.592018)
		(end 400.623024 -155.592018)
		(stroke
			(width 0.2)
			(type default)
		)
		(fill no)
		(layer "In8.Cu")
	)
	(gr_circle
		(center 399.40992 -153.592022)
		(end 400.623024 -153.592022)
		(stroke
			(width 0.2)
			(type default)
		)
		(fill no)
		(layer "In8.Cu")
	)
	(gr_circle
		(center 400.37512 -168.82999)
		(end 401.588224 -168.82999)
		(stroke
			(width 0.2)
			(type default)
		)
		(fill no)
		(layer "In8.Cu")
	)
	(gr_circle
		(center 400.37512 -166.829994)
		(end 401.588224 -166.829994)
		(stroke
			(width 0.2)
			(type default)
		)
		(fill no)
		(layer "In8.Cu")
	)
	(gr_circle
		(center 400.37512 -164.829998)
		(end 401.588224 -164.829998)
		(stroke
			(width 0.2)
			(type default)
		)
		(fill no)
		(layer "In8.Cu")
	)
	(gr_circle
		(center 400.37512 -162.830002)
		(end 401.588224 -162.830002)
		(stroke
			(width 0.2)
			(type default)
		)
		(fill no)
		(layer "In8.Cu")
	)
	(gr_circle
		(center 400.37512 -160.830006)
		(end 401.588224 -160.830006)
		(stroke
			(width 0.2)
			(type default)
		)
		(fill no)
		(layer "In8.Cu")
	)
	(gr_circle
		(center 400.37512 -158.83001)
		(end 401.588224 -158.83001)
		(stroke
			(width 0.2)
			(type default)
		)
		(fill no)
		(layer "In8.Cu")
	)
	(gr_circle
		(center 400.37512 -156.830014)
		(end 401.588224 -156.830014)
		(stroke
			(width 0.2)
			(type default)
		)
		(fill no)
		(layer "In8.Cu")
	)
	(gr_circle
		(center 400.37512 -154.830018)
		(end 401.588224 -154.830018)
		(stroke
			(width 0.2)
			(type default)
		)
		(fill no)
		(layer "In8.Cu")
	)
	(gr_circle
		(center 400.37512 -152.830022)
		(end 401.588224 -152.830022)
		(stroke
			(width 0.2)
			(type default)
		)
		(fill no)
		(layer "In8.Cu")
	)
	(gr_circle
		(center 468.920068 -76.309982)
		(end 470.329768 -76.309982)
		(stroke
			(width 0.2)
			(type default)
		)
		(fill no)
		(layer "In8.Cu")
	)
	(gr_circle
		(center 468.920068 -73.769982)
		(end 470.329768 -73.769982)
		(stroke
			(width 0.2)
			(type default)
		)
		(fill no)
		(layer "In8.Cu")
	)
	(gr_circle
		(center 468.920068 -71.229982)
		(end 470.329768 -71.229982)
		(stroke
			(width 0.2)
			(type default)
		)
		(fill no)
		(layer "In8.Cu")
	)
	(gr_circle
		(center 468.920068 -68.689982)
		(end 470.329768 -68.689982)
		(stroke
			(width 0.2)
			(type default)
		)
		(fill no)
		(layer "In8.Cu")
	)
	(gr_circle
		(center 469.994488 -74.785982)
		(end 471.404188 -74.785982)
		(stroke
			(width 0.2)
			(type default)
		)
		(fill no)
		(layer "In8.Cu")
	)
	(gr_circle
		(center 469.994488 -72.245982)
		(end 471.404188 -72.245982)
		(stroke
			(width 0.2)
			(type default)
		)
		(fill no)
		(layer "In8.Cu")
	)
	(gr_circle
		(center 469.994488 -69.705982)
		(end 471.404188 -69.705982)
		(stroke
			(width 0.2)
			(type default)
		)
		(fill no)
		(layer "In8.Cu")
	)
	(gr_circle
		(center 471.620088 -76.309982)
		(end 473.029788 -76.309982)
		(stroke
			(width 0.2)
			(type default)
		)
		(fill no)
		(layer "In8.Cu")
	)
	(gr_circle
		(center 471.620088 -73.769982)
		(end 473.029788 -73.769982)
		(stroke
			(width 0.2)
			(type default)
		)
		(fill no)
		(layer "In8.Cu")
	)
	(gr_circle
		(center 471.620088 -71.229982)
		(end 473.029788 -71.229982)
		(stroke
			(width 0.2)
			(type default)
		)
		(fill no)
		(layer "In8.Cu")
	)
	(gr_circle
		(center 471.620088 -68.689982)
		(end 473.029788 -68.689982)
		(stroke
			(width 0.2)
			(type default)
		)
		(fill no)
		(layer "In8.Cu")
	)
	(gr_line
		(start 0 -153.299922)
		(end 0 -4.99999)
		(stroke
			(width 0.05)
			(type default)
		)
		(layer "Edge.Cuts")
	)
	(gr_arc
		(start 0 -153.299922)
		(mid 1.464464 -156.835448)
		(end 4.99999 -158.299912)
		(stroke
			(width 0.05)
			(type default)
		)
		(layer "Edge.Cuts")
	)
	(gr_arc
		(start 4.99999 0)
		(mid 1.464463 -1.464463)
		(end 0 -4.99999)
		(stroke
			(width 0.05)
			(type default)
		)
		(layer "Edge.Cuts")
	)
	(gr_line
		(start 4.99999 0)
		(end 434.999892 0)
		(stroke
			(width 0.05)
			(type default)
		)
		(layer "Edge.Cuts")
	)
	(gr_line
		(start 25.999948 -158.299912)
		(end 4.99999 -158.299912)
		(stroke
			(width 0.05)
			(type default)
		)
		(layer "Edge.Cuts")
	)
	(gr_line
		(start 30.999938 -166.649908)
		(end 30.999938 -163.299902)
		(stroke
			(width 0.05)
			(type default)
		)
		(layer "Edge.Cuts")
	)
	(gr_arc
		(start 30.999938 -166.649908)
		(mid 32.4644 -170.185437)
		(end 35.999928 -171.649898)
		(stroke
			(width 0.05)
			(type default)
		)
		(layer "Edge.Cuts")
	)
	(gr_arc
		(start 30.999938 -163.299902)
		(mid 29.535475 -159.764375)
		(end 25.999948 -158.299912)
		(stroke
			(width 0.05)
			(type default)
		)
		(layer "Edge.Cuts")
	)
	(gr_line
		(start 75.000104 -171.649898)
		(end 35.999928 -171.649898)
		(stroke
			(width 0.05)
			(type default)
		)
		(layer "Edge.Cuts")
	)
	(gr_arc
		(start 75.000104 -171.649898)
		(mid 78.535631 -170.185434)
		(end 80.000094 -166.649908)
		(stroke
			(width 0.05)
			(type default)
		)
		(layer "Edge.Cuts")
	)
	(gr_line
		(start 80.000094 -161.299906)
		(end 80.000094 -166.649908)
		(stroke
			(width 0.05)
			(type default)
		)
		(layer "Edge.Cuts")
	)
	(gr_arc
		(start 83.000088 -158.299912)
		(mid 80.878772 -159.17859)
		(end 80.000094 -161.299906)
		(stroke
			(width 0.05)
			(type default)
		)
		(layer "Edge.Cuts")
	)
	(gr_line
		(start 83.49996 -158.299912)
		(end 83.000088 -158.299912)
		(stroke
			(width 0.05)
			(type default)
		)
		(layer "Edge.Cuts")
	)
	(gr_arc
		(start 83.49996 -158.299912)
		(mid 87.035488 -156.835449)
		(end 88.49995 -153.299922)
		(stroke
			(width 0.05)
			(type default)
		)
		(layer "Edge.Cuts")
	)
	(gr_line
		(start 88.49995 -110.499906)
		(end 88.49995 -153.299922)
		(stroke
			(width 0.05)
			(type default)
		)
		(layer "Edge.Cuts")
	)
	(gr_arc
		(start 96.000062 -103.000048)
		(mid 90.696697 -105.196616)
		(end 88.49995 -110.499906)
		(stroke
			(width 0.05)
			(type default)
		)
		(layer "Edge.Cuts")
	)
	(gr_line
		(start 344.000074 -103.000048)
		(end 96.000062 -103.000048)
		(stroke
			(width 0.05)
			(type default)
		)
		(layer "Edge.Cuts")
	)
	(gr_line
		(start 351.499932 -153.299922)
		(end 351.499932 -110.499906)
		(stroke
			(width 0.05)
			(type default)
		)
		(layer "Edge.Cuts")
	)
	(gr_arc
		(start 351.499932 -153.299922)
		(mid 352.964404 -156.835427)
		(end 356.499922 -158.299912)
		(stroke
			(width 0.05)
			(type default)
		)
		(layer "Edge.Cuts")
	)
	(gr_arc
		(start 351.499932 -110.499906)
		(mid 349.303274 -105.196706)
		(end 344.000074 -103.000048)
		(stroke
			(width 0.05)
			(type default)
		)
		(layer "Edge.Cuts")
	)
	(gr_line
		(start 357.000048 -158.299912)
		(end 356.499922 -158.299912)
		(stroke
			(width 0.05)
			(type default)
		)
		(layer "Edge.Cuts")
	)
	(gr_line
		(start 360.000042 -166.649908)
		(end 360.000042 -161.299906)
		(stroke
			(width 0.05)
			(type default)
		)
		(layer "Edge.Cuts")
	)
	(gr_arc
		(start 360.000042 -166.649908)
		(mid 361.46451 -170.185418)
		(end 365.000032 -171.649898)
		(stroke
			(width 0.05)
			(type default)
		)
		(layer "Edge.Cuts")
	)
	(gr_arc
		(start 360.000042 -161.299906)
		(mid 359.121364 -159.17859)
		(end 357.000048 -158.299912)
		(stroke
			(width 0.05)
			(type default)
		)
		(layer "Edge.Cuts")
	)
	(gr_line
		(start 403.999954 -171.649898)
		(end 365.000032 -171.649898)
		(stroke
			(width 0.05)
			(type default)
		)
		(layer "Edge.Cuts")
	)
	(gr_arc
		(start 403.999954 -171.649898)
		(mid 407.535513 -170.185452)
		(end 408.999944 -166.649908)
		(stroke
			(width 0.05)
			(type default)
		)
		(layer "Edge.Cuts")
	)
	(gr_line
		(start 408.999944 -163.299902)
		(end 408.999944 -166.649908)
		(stroke
			(width 0.05)
			(type default)
		)
		(layer "Edge.Cuts")
	)
	(gr_arc
		(start 413.999934 -158.299912)
		(mid 410.464407 -159.764375)
		(end 408.999944 -163.299902)
		(stroke
			(width 0.05)
			(type default)
		)
		(layer "Edge.Cuts")
	)
	(gr_line
		(start 434.999892 -158.299912)
		(end 413.999934 -158.299912)
		(stroke
			(width 0.05)
			(type default)
		)
		(layer "Edge.Cuts")
	)
	(gr_arc
		(start 434.999892 -158.299912)
		(mid 438.535432 -156.835453)
		(end 439.999882 -153.299922)
		(stroke
			(width 0.05)
			(type default)
		)
		(layer "Edge.Cuts")
	)
	(gr_line
		(start 439.999882 -136.77011)
		(end 439.999882 -153.299922)
		(stroke
			(width 0.05)
			(type default)
		)
		(layer "Edge.Cuts")
	)
	(gr_arc
		(start 439.999882 -11.770106)
		(mid 441.464435 -15.305723)
		(end 445.000126 -16.770096)
		(stroke
			(width 0.05)
			(type default)
		)
		(layer "Edge.Cuts")
	)
	(gr_arc
		(start 439.999882 -4.99999)
		(mid 438.535415 -1.464472)
		(end 434.999892 0)
		(stroke
			(width 0.05)
			(type default)
		)
		(layer "Edge.Cuts")
	)
	(gr_line
		(start 439.999882 -4.99999)
		(end 439.999882 -11.770106)
		(stroke
			(width 0.05)
			(type default)
		)
		(layer "Edge.Cuts")
	)
	(gr_arc
		(start 445.000126 -131.77012)
		(mid 441.464509 -133.234568)
		(end 439.999882 -136.77011)
		(stroke
			(width 0.05)
			(type default)
		)
		(layer "Edge.Cuts")
	)
	(gr_line
		(start 445.000126 -16.770096)
		(end 471.000074 -16.770096)
		(stroke
			(width 0.05)
			(type default)
		)
		(layer "Edge.Cuts")
	)
	(gr_line
		(start 471.000074 -131.77012)
		(end 445.000126 -131.77012)
		(stroke
			(width 0.05)
			(type default)
		)
		(layer "Edge.Cuts")
	)
	(gr_arc
		(start 471.000074 -131.77012)
		(mid 474.535595 -130.305484)
		(end 476.000064 -126.769876)
		(stroke
			(width 0.05)
			(type default)
		)
		(layer "Edge.Cuts")
	)
	(gr_arc
		(start 476.000064 -21.770086)
		(mid 474.535594 -18.234577)
		(end 471.000074 -16.770096)
		(stroke
			(width 0.05)
			(type default)
		)
		(layer "Edge.Cuts")
	)
	(gr_line
		(start 476.000064 -21.770086)
		(end 476.000064 -126.769876)
		(stroke
			(width 0.05)
			(type default)
		)
		(layer "Edge.Cuts")
	)
	(segment
		(start 420.94404 -41.768268)
		(end 420.94404 -44.937172)
		(width 0.17272)
		(layer "F.Cu")
		(net "TP_U8_P07")
	)
	(segment
		(start 420.94404 -44.937172)
		(end 420.61384 -45.267372)
		(width 0.17272)
		(layer "F.Cu")
		(net "TP_U8_P07")
	)
	(segment
		(start 421.64 -48.006)
		(end 421.64 -49.149)
		(width 0.17272)
		(layer "F.Cu")
		(net "TP_U8_P07")
	)
	(segment
		(start 417.449 -39.492936)
		(end 418.668708 -39.492936)
		(width 0.17272)
		(layer "F.Cu")
		(net "TP_U8_P07")
	)
	(segment
		(start 420.61384 -45.267372)
		(end 420.61384 -46.97984)
		(width 0.17272)
		(layer "F.Cu")
		(net "TP_U8_P07")
	)
	(segment
		(start 420.61384 -46.97984)
		(end 421.64 -48.006)
		(width 0.17272)
		(layer "F.Cu")
		(net "TP_U8_P07")
	)
	(segment
		(start 418.668708 -39.492936)
		(end 420.94404 -41.768268)
		(width 0.17272)
		(layer "F.Cu")
		(net "TP_U8_P07")
	)
	(via
		(at 421.64 -49.149)
		(size 0.508)
		(drill 0.254)
		(layers "F.Cu" "B.Cu")
		(net "TP_U8_P07")
	)
	(segment
		(start 419.989 -44.54144)
		(end 419.989 -42.164)
		(width 0.17272)
		(layer "F.Cu")
		(net "TP_U8_P05")
	)
	(segment
		(start 419.989 -42.164)
		(end 418.617908 -40.792908)
		(width 0.17272)
		(layer "F.Cu")
		(net "TP_U8_P05")
	)
	(segment
		(start 419.6588 -44.87164)
		(end 419.989 -44.54144)
		(width 0.17272)
		(layer "F.Cu")
		(net "TP_U8_P05")
	)
	(segment
		(start 419.6588 -48.4378)
		(end 419.6588 -44.87164)
		(width 0.17272)
		(layer "F.Cu")
		(net "TP_U8_P05")
	)
	(segment
		(start 420.116 -48.895)
		(end 419.6588 -48.4378)
		(width 0.17272)
		(layer "F.Cu")
		(net "TP_U8_P05")
	)
	(segment
		(start 418.617908 -40.792908)
		(end 417.449 -40.792908)
		(width 0.17272)
		(layer "F.Cu")
		(net "TP_U8_P05")
	)
	(via
		(at 420.116 -48.895)
		(size 0.508)
		(drill 0.254)
		(layers "F.Cu" "B.Cu")
		(net "TP_U8_P05")
	)
	(segment
		(start 182.372 -76.2)
		(end 182.372 -76.916026)
		(width 0.17272)
		(layer "F.Cu")
		(net "FM_HS2_EN_FUSE_BUF")
	)
	(segment
		(start 182.913528 -76.741528)
		(end 182.372 -76.2)
		(width 0.17272)
		(layer "F.Cu")
		(net "FM_HS2_EN_FUSE_BUF")
	)
	(segment
		(start 280.965402 -86.568788)
		(end 280.965402 -88.604598)
		(width 0.17272)
		(layer "F.Cu")
		(net "FM_HS2_EN_FUSE_BUF")
	)
	(segment
		(start 262.694166 -77.147166)
		(end 270.256 -84.709)
		(width 0.17272)
		(layer "F.Cu")
		(net "FM_HS2_EN_FUSE_BUF")
	)
	(segment
		(start 184.717944 -76.35113)
		(end 184.439814 -76.073)
		(width 0.17272)
		(layer "F.Cu")
		(net "FM_HS2_EN_FUSE_BUF")
	)
	(segment
		(start 280.965402 -88.604598)
		(end 278.003 -91.567)
		(width 0.17272)
		(layer "F.Cu")
		(net "FM_HS2_EN_FUSE_BUF")
	)
	(segment
		(start 260.67258 -77.147166)
		(end 262.694166 -77.147166)
		(width 0.17272)
		(layer "F.Cu")
		(net "FM_HS2_EN_FUSE_BUF")
	)
	(segment
		(start 182.372 -76.916026)
		(end 182.992014 -77.53604)
		(width 0.17272)
		(layer "F.Cu")
		(net "FM_HS2_EN_FUSE_BUF")
	)
	(segment
		(start 184.327546 -76.741528)
		(end 182.913528 -76.741528)
		(width 0.17272)
		(layer "F.Cu")
		(net "FM_HS2_EN_FUSE_BUF")
	)
	(segment
		(start 184.439814 -76.073)
		(end 183.62295 -76.073)
		(width 0.17272)
		(layer "F.Cu")
		(net "FM_HS2_EN_FUSE_BUF")
	)
	(segment
		(start 270.256 -84.709)
		(end 279.105614 -84.709)
		(width 0.17272)
		(layer "F.Cu")
		(net "FM_HS2_EN_FUSE_BUF")
	)
	(segment
		(start 184.717944 -76.35113)
		(end 184.327546 -76.741528)
		(width 0.17272)
		(layer "F.Cu")
		(net "FM_HS2_EN_FUSE_BUF")
	)
	(segment
		(start 279.105614 -84.709)
		(end 280.965402 -86.568788)
		(width 0.17272)
		(layer "F.Cu")
		(net "FM_HS2_EN_FUSE_BUF")
	)
	(via
		(at 417.83 -46.863)
		(size 0.508)
		(drill 0.254)
		(layers "F.Cu" "B.Cu")
		(net "FM_HS2_EN_FUSE_BUF")
	)
	(via
		(at 182.372 -76.2)
		(size 0.762)
		(drill 0.381)
		(layers "F.Cu" "B.Cu")
		(net "FM_HS2_EN_FUSE_BUF")
	)
	(via
		(at 278.003 -91.567)
		(size 0.508)
		(drill 0.254)
		(layers "F.Cu" "B.Cu")
		(net "FM_HS2_EN_FUSE_BUF")
	)
	(via
		(at 260.67258 -77.147166)
		(size 0.508)
		(drill 0.254)
		(layers "F.Cu" "B.Cu")
		(net "FM_HS2_EN_FUSE_BUF")
	)
	(via
		(at 183.62295 -76.073)
		(size 0.508)
		(drill 0.254)
		(layers "F.Cu" "B.Cu")
		(net "FM_HS2_EN_FUSE_BUF")
	)
	(segment
		(start 416.518852 -41.443148)
		(end 417.449 -41.443148)
		(width 0.17272)
		(layer "B.Cu")
		(net "FM_HS2_EN_FUSE_BUF")
	)
	(segment
		(start 417.83 -46.863)
		(end 417.195 -46.228)
		(width 0.17272)
		(layer "B.Cu")
		(net "FM_HS2_EN_FUSE_BUF")
	)
	(segment
		(start 416.56 -46.228)
		(end 415.163 -44.831)
		(width 0.17272)
		(layer "B.Cu")
		(net "FM_HS2_EN_FUSE_BUF")
	)
	(segment
		(start 415.163 -42.799)
		(end 416.518852 -41.443148)
		(width 0.17272)
		(layer "B.Cu")
		(net "FM_HS2_EN_FUSE_BUF")
	)
	(segment
		(start 417.195 -46.228)
		(end 416.56 -46.228)
		(width 0.17272)
		(layer "B.Cu")
		(net "FM_HS2_EN_FUSE_BUF")
	)
	(segment
		(start 415.163 -44.831)
		(end 415.163 -42.799)
		(width 0.17272)
		(layer "B.Cu")
		(net "FM_HS2_EN_FUSE_BUF")
	)
	(segment
		(start 221.582742 -87.758524)
		(end 210.034124 -87.758524)
		(width 0.12954)
		(layer "In2.Cu")
		(net "FM_HS2_EN_FUSE_BUF")
	)
	(segment
		(start 210.034124 -87.758524)
		(end 199.7456 -77.47)
		(width 0.12954)
		(layer "In2.Cu")
		(net "FM_HS2_EN_FUSE_BUF")
	)
	(segment
		(start 283.357828 -91.821)
		(end 294.326818 -91.821)
		(width 0.12954)
		(layer "In2.Cu")
		(net "FM_HS2_EN_FUSE_BUF")
	)
	(segment
		(start 199.7456 -77.47)
		(end 185.01995 -77.47)
		(width 0.12954)
		(layer "In2.Cu")
		(net "FM_HS2_EN_FUSE_BUF")
	)
	(segment
		(start 283.103828 -91.567)
		(end 283.357828 -91.821)
		(width 0.12954)
		(layer "In2.Cu")
		(net "FM_HS2_EN_FUSE_BUF")
	)
	(segment
		(start 225.911918 -91.059)
		(end 224.883218 -91.059)
		(width 0.12954)
		(layer "In2.Cu")
		(net "FM_HS2_EN_FUSE_BUF")
	)
	(segment
		(start 294.326818 -91.821)
		(end 297.090338 -94.58452)
		(width 0.12954)
		(layer "In2.Cu")
		(net "FM_HS2_EN_FUSE_BUF")
	)
	(segment
		(start 345.56192 -97.558098)
		(end 377.723654 -65.396364)
		(width 0.12954)
		(layer "In2.Cu")
		(net "FM_HS2_EN_FUSE_BUF")
	)
	(segment
		(start 401.73656 -65.396364)
		(end 415.544 -51.588924)
		(width 0.12954)
		(layer "In2.Cu")
		(net "FM_HS2_EN_FUSE_BUF")
	)
	(segment
		(start 417.195 -46.228)
		(end 417.83 -46.863)
		(width 0.12954)
		(layer "In2.Cu")
		(net "FM_HS2_EN_FUSE_BUF")
	)
	(segment
		(start 229.594918 -87.376)
		(end 225.911918 -91.059)
		(width 0.12954)
		(layer "In2.Cu")
		(net "FM_HS2_EN_FUSE_BUF")
	)
	(segment
		(start 185.01995 -77.47)
		(end 183.62295 -76.073)
		(width 0.12954)
		(layer "In2.Cu")
		(net "FM_HS2_EN_FUSE_BUF")
	)
	(segment
		(start 415.544 -47.244)
		(end 416.56 -46.228)
		(width 0.12954)
		(layer "In2.Cu")
		(net "FM_HS2_EN_FUSE_BUF")
	)
	(segment
		(start 258.015486 -79.80426)
		(end 247.152922 -79.80426)
		(width 0.12954)
		(layer "In2.Cu")
		(net "FM_HS2_EN_FUSE_BUF")
	)
	(segment
		(start 415.544 -51.588924)
		(end 415.544 -47.244)
		(width 0.12954)
		(layer "In2.Cu")
		(net "FM_HS2_EN_FUSE_BUF")
	)
	(segment
		(start 309.821326 -94.58452)
		(end 312.794904 -97.558098)
		(width 0.12954)
		(layer "In2.Cu")
		(net "FM_HS2_EN_FUSE_BUF")
	)
	(segment
		(start 312.794904 -97.558098)
		(end 345.56192 -97.558098)
		(width 0.12954)
		(layer "In2.Cu")
		(net "FM_HS2_EN_FUSE_BUF")
	)
	(segment
		(start 416.56 -46.228)
		(end 417.195 -46.228)
		(width 0.12954)
		(layer "In2.Cu")
		(net "FM_HS2_EN_FUSE_BUF")
	)
	(segment
		(start 377.723654 -65.396364)
		(end 401.73656 -65.396364)
		(width 0.12954)
		(layer "In2.Cu")
		(net "FM_HS2_EN_FUSE_BUF")
	)
	(segment
		(start 297.090338 -94.58452)
		(end 309.821326 -94.58452)
		(width 0.12954)
		(layer "In2.Cu")
		(net "FM_HS2_EN_FUSE_BUF")
	)
	(segment
		(start 278.003 -91.567)
		(end 283.103828 -91.567)
		(width 0.12954)
		(layer "In2.Cu")
		(net "FM_HS2_EN_FUSE_BUF")
	)
	(segment
		(start 260.67258 -77.147166)
		(end 258.015486 -79.80426)
		(width 0.12954)
		(layer "In2.Cu")
		(net "FM_HS2_EN_FUSE_BUF")
	)
	(segment
		(start 239.581182 -87.376)
		(end 229.594918 -87.376)
		(width 0.12954)
		(layer "In2.Cu")
		(net "FM_HS2_EN_FUSE_BUF")
	)
	(segment
		(start 224.883218 -91.059)
		(end 221.582742 -87.758524)
		(width 0.12954)
		(layer "In2.Cu")
		(net "FM_HS2_EN_FUSE_BUF")
	)
	(segment
		(start 247.152922 -79.80426)
		(end 239.581182 -87.376)
		(width 0.12954)
		(layer "In2.Cu")
		(net "FM_HS2_EN_FUSE_BUF")
	)
	(segment
		(start 164.860986 -82.48396)
		(end 165.429946 -81.915)
		(width 0.17272)
		(layer "F.Cu")
		(net "FM_HS2_EN_BUSBAR_BUF")
	)
	(segment
		(start 167.36695 -81.915)
		(end 167.36695 -81.28)
		(width 0.17272)
		(layer "F.Cu")
		(net "FM_HS2_EN_BUSBAR_BUF")
	)
	(segment
		(start 165.429946 -81.915)
		(end 167.36695 -81.915)
		(width 0.17272)
		(layer "F.Cu")
		(net "FM_HS2_EN_BUSBAR_BUF")
	)
	(via
		(at 415.29 -41.783)
		(size 0.6604)
		(drill 0.3302)
		(layers "F.Cu" "B.Cu")
		(net "FM_HS2_EN_BUSBAR_BUF")
	)
	(via
		(at 167.36695 -81.28)
		(size 0.508)
		(drill 0.254)
		(layers "F.Cu" "B.Cu")
		(net "FM_HS2_EN_BUSBAR_BUF")
	)
	(via
		(at 417.068 -46.863)
		(size 0.508)
		(drill 0.254)
		(layers "F.Cu" "B.Cu")
		(net "FM_HS2_EN_BUSBAR_BUF")
	)
	(segment
		(start 416.279838 -40.793162)
		(end 417.449 -40.793162)
		(width 0.17272)
		(layer "B.Cu")
		(net "FM_HS2_EN_BUSBAR_BUF")
	)
	(segment
		(start 414.655 -45.085)
		(end 414.655 -42.418)
		(width 0.17272)
		(layer "B.Cu")
		(net "FM_HS2_EN_BUSBAR_BUF")
	)
	(segment
		(start 417.068 -46.863)
		(end 416.433 -46.863)
		(width 0.17272)
		(layer "B.Cu")
		(net "FM_HS2_EN_BUSBAR_BUF")
	)
	(segment
		(start 416.433 -46.863)
		(end 414.655 -45.085)
		(width 0.17272)
		(layer "B.Cu")
		(net "FM_HS2_EN_BUSBAR_BUF")
	)
	(segment
		(start 415.29 -41.783)
		(end 416.279838 -40.793162)
		(width 0.17272)
		(layer "B.Cu")
		(net "FM_HS2_EN_BUSBAR_BUF")
	)
	(segment
		(start 414.655 -42.418)
		(end 415.29 -41.783)
		(width 0.17272)
		(layer "B.Cu")
		(net "FM_HS2_EN_BUSBAR_BUF")
	)
	(segment
		(start 296.84726 -95.17126)
		(end 309.578248 -95.17126)
		(width 0.12954)
		(layer "In2.Cu")
		(net "FM_HS2_EN_BUSBAR_BUF")
	)
	(segment
		(start 259.463286 -89.58326)
		(end 273.783806 -89.58326)
		(width 0.12954)
		(layer "In2.Cu")
		(net "FM_HS2_EN_BUSBAR_BUF")
	)
	(segment
		(start 168.00195 -80.645)
		(end 168.91 -80.645)
		(width 0.12954)
		(layer "In2.Cu")
		(net "FM_HS2_EN_BUSBAR_BUF")
	)
	(segment
		(start 167.36695 -81.28)
		(end 168.00195 -80.645)
		(width 0.12954)
		(layer "In2.Cu")
		(net "FM_HS2_EN_BUSBAR_BUF")
	)
	(segment
		(start 273.783806 -89.58326)
		(end 277.390606 -93.19006)
		(width 0.12954)
		(layer "In2.Cu")
		(net "FM_HS2_EN_BUSBAR_BUF")
	)
	(segment
		(start 233.299 -93.472)
		(end 236.893608 -97.066608)
		(width 0.12954)
		(layer "In2.Cu")
		(net "FM_HS2_EN_BUSBAR_BUF")
	)
	(segment
		(start 401.910804 -66.051938)
		(end 416.60191 -51.360832)
		(width 0.12954)
		(layer "In2.Cu")
		(net "FM_HS2_EN_BUSBAR_BUF")
	)
	(segment
		(start 283.72054 -93.19006)
		(end 284.4546 -92.456)
		(width 0.12954)
		(layer "In2.Cu")
		(net "FM_HS2_EN_BUSBAR_BUF")
	)
	(segment
		(start 416.60191 -51.360832)
		(end 416.60191 -47.32909)
		(width 0.12954)
		(layer "In2.Cu")
		(net "FM_HS2_EN_BUSBAR_BUF")
	)
	(segment
		(start 224.181162 -98.652838)
		(end 229.362 -93.472)
		(width 0.12954)
		(layer "In2.Cu")
		(net "FM_HS2_EN_BUSBAR_BUF")
	)
	(segment
		(start 277.390606 -93.19006)
		(end 283.72054 -93.19006)
		(width 0.12954)
		(layer "In2.Cu")
		(net "FM_HS2_EN_BUSBAR_BUF")
	)
	(segment
		(start 345.804998 -98.144838)
		(end 377.897898 -66.051938)
		(width 0.12954)
		(layer "In2.Cu")
		(net "FM_HS2_EN_BUSBAR_BUF")
	)
	(segment
		(start 377.897898 -66.051938)
		(end 401.910804 -66.051938)
		(width 0.12954)
		(layer "In2.Cu")
		(net "FM_HS2_EN_BUSBAR_BUF")
	)
	(segment
		(start 236.893608 -97.066608)
		(end 251.979938 -97.066608)
		(width 0.12954)
		(layer "In2.Cu")
		(net "FM_HS2_EN_BUSBAR_BUF")
	)
	(segment
		(start 294.132 -92.456)
		(end 296.84726 -95.17126)
		(width 0.12954)
		(layer "In2.Cu")
		(net "FM_HS2_EN_BUSBAR_BUF")
	)
	(segment
		(start 312.551826 -98.144838)
		(end 345.804998 -98.144838)
		(width 0.12954)
		(layer "In2.Cu")
		(net "FM_HS2_EN_BUSBAR_BUF")
	)
	(segment
		(start 284.4546 -92.456)
		(end 294.132 -92.456)
		(width 0.12954)
		(layer "In2.Cu")
		(net "FM_HS2_EN_BUSBAR_BUF")
	)
	(segment
		(start 179.8066 -91.922854)
		(end 186.536584 -98.652838)
		(width 0.12954)
		(layer "In2.Cu")
		(net "FM_HS2_EN_BUSBAR_BUF")
	)
	(segment
		(start 168.91 -80.645)
		(end 169.291 -81.026)
		(width 0.12954)
		(layer "In2.Cu")
		(net "FM_HS2_EN_BUSBAR_BUF")
	)
	(segment
		(start 178.510946 -81.026)
		(end 179.8066 -82.321654)
		(width 0.12954)
		(layer "In2.Cu")
		(net "FM_HS2_EN_BUSBAR_BUF")
	)
	(segment
		(start 186.536584 -98.652838)
		(end 224.181162 -98.652838)
		(width 0.12954)
		(layer "In2.Cu")
		(net "FM_HS2_EN_BUSBAR_BUF")
	)
	(segment
		(start 229.362 -93.472)
		(end 233.299 -93.472)
		(width 0.12954)
		(layer "In2.Cu")
		(net "FM_HS2_EN_BUSBAR_BUF")
	)
	(segment
		(start 251.979938 -97.066608)
		(end 259.463286 -89.58326)
		(width 0.12954)
		(layer "In2.Cu")
		(net "FM_HS2_EN_BUSBAR_BUF")
	)
	(segment
		(start 416.60191 -47.32909)
		(end 417.068 -46.863)
		(width 0.12954)
		(layer "In2.Cu")
		(net "FM_HS2_EN_BUSBAR_BUF")
	)
	(segment
		(start 179.8066 -82.321654)
		(end 179.8066 -91.922854)
		(width 0.12954)
		(layer "In2.Cu")
		(net "FM_HS2_EN_BUSBAR_BUF")
	)
	(segment
		(start 169.291 -81.026)
		(end 178.510946 -81.026)
		(width 0.12954)
		(layer "In2.Cu")
		(net "FM_HS2_EN_BUSBAR_BUF")
	)
	(segment
		(start 309.578248 -95.17126)
		(end 312.551826 -98.144838)
		(width 0.12954)
		(layer "In2.Cu")
		(net "FM_HS2_EN_BUSBAR_BUF")
	)
	(via
		(at 413.766 -44.45)
		(size 0.508)
		(drill 0.254)
		(layers "F.Cu" "B.Cu")
		(net "FM_HS1_EN_FUSE_BUF")
	)
	(via
		(at 299.593 -90.17)
		(size 0.762)
		(drill 0.254)
		(layers "F.Cu" "B.Cu")
		(net "FM_HS1_EN_FUSE_BUF")
	)
	(segment
		(start 415.913824 -40.142922)
		(end 417.449 -40.142922)
		(width 0.17272)
		(layer "B.Cu")
		(net "FM_HS1_EN_FUSE_BUF")
	)
	(segment
		(start 413.766 -42.290746)
		(end 415.913824 -40.142922)
		(width 0.17272)
		(layer "B.Cu")
		(net "FM_HS1_EN_FUSE_BUF")
	)
	(segment
		(start 298.718986 -90.585036)
		(end 298.704 -90.57005)
		(width 0.17272)
		(layer "B.Cu")
		(net "FM_HS1_EN_FUSE_BUF")
	)
	(segment
		(start 413.766 -44.45)
		(end 413.766 -42.290746)
		(width 0.17272)
		(layer "B.Cu")
		(net "FM_HS1_EN_FUSE_BUF")
	)
	(segment
		(start 298.718986 -91.76004)
		(end 298.718986 -90.585036)
		(width 0.17272)
		(layer "B.Cu")
		(net "FM_HS1_EN_FUSE_BUF")
	)
	(segment
		(start 299.593 -90.17)
		(end 299.19295 -90.57005)
		(width 0.17272)
		(layer "B.Cu")
		(net "FM_HS1_EN_FUSE_BUF")
	)
	(segment
		(start 299.19295 -90.57005)
		(end 298.704 -90.57005)
		(width 0.17272)
		(layer "B.Cu")
		(net "FM_HS1_EN_FUSE_BUF")
	)
	(segment
		(start 413.131 -45.085)
		(end 413.766 -44.45)
		(width 0.12954)
		(layer "In2.Cu")
		(net "FM_HS1_EN_FUSE_BUF")
	)
	(segment
		(start 306.227988 -92.80906)
		(end 326.575928 -92.80906)
		(width 0.12954)
		(layer "In2.Cu")
		(net "FM_HS1_EN_FUSE_BUF")
	)
	(segment
		(start 358.868726 -81.761838)
		(end 376.99442 -63.636144)
		(width 0.12954)
		(layer "In2.Cu")
		(net "FM_HS1_EN_FUSE_BUF")
	)
	(segment
		(start 326.575928 -92.80906)
		(end 337.62315 -81.761838)
		(width 0.12954)
		(layer "In2.Cu")
		(net "FM_HS1_EN_FUSE_BUF")
	)
	(segment
		(start 376.99442 -63.636144)
		(end 400.675856 -63.636144)
		(width 0.12954)
		(layer "In2.Cu")
		(net "FM_HS1_EN_FUSE_BUF")
	)
	(segment
		(start 337.62315 -81.761838)
		(end 358.868726 -81.761838)
		(width 0.12954)
		(layer "In2.Cu")
		(net "FM_HS1_EN_FUSE_BUF")
	)
	(segment
		(start 303.588928 -90.17)
		(end 306.227988 -92.80906)
		(width 0.12954)
		(layer "In2.Cu")
		(net "FM_HS1_EN_FUSE_BUF")
	)
	(segment
		(start 413.131 -51.181)
		(end 413.131 -45.085)
		(width 0.12954)
		(layer "In2.Cu")
		(net "FM_HS1_EN_FUSE_BUF")
	)
	(segment
		(start 299.593 -90.17)
		(end 303.588928 -90.17)
		(width 0.12954)
		(layer "In2.Cu")
		(net "FM_HS1_EN_FUSE_BUF")
	)
	(segment
		(start 400.675856 -63.636144)
		(end 413.131 -51.181)
		(width 0.12954)
		(layer "In2.Cu")
		(net "FM_HS1_EN_FUSE_BUF")
	)
	(via
		(at 296.799 -87.48395)
		(size 0.6604)
		(drill 0.3302)
		(layers "F.Cu" "B.Cu")
		(net "FM_HS1_EN_BUSBAR_BUF")
	)
	(via
		(at 421.132 -45.593)
		(size 0.508)
		(drill 0.254)
		(layers "F.Cu" "B.Cu")
		(net "FM_HS1_EN_BUSBAR_BUF")
	)
	(via
		(at 299.593 -88.9)
		(size 0.508)
		(drill 0.254)
		(layers "F.Cu" "B.Cu")
		(net "FM_HS1_EN_BUSBAR_BUF")
	)
	(segment
		(start 418.628322 -39.492936)
		(end 417.449 -39.492936)
		(width 0.17272)
		(layer "B.Cu")
		(net "FM_HS1_EN_BUSBAR_BUF")
	)
	(segment
		(start 421.132 -45.593)
		(end 421.132 -41.996614)
		(width 0.17272)
		(layer "B.Cu")
		(net "FM_HS1_EN_BUSBAR_BUF")
	)
	(segment
		(start 298.68495 -87.48395)
		(end 296.799 -87.48395)
		(width 0.17272)
		(layer "B.Cu")
		(net "FM_HS1_EN_BUSBAR_BUF")
	)
	(segment
		(start 421.132 -41.996614)
		(end 418.628322 -39.492936)
		(width 0.17272)
		(layer "B.Cu")
		(net "FM_HS1_EN_BUSBAR_BUF")
	)
	(segment
		(start 299.593 -88.9)
		(end 299.593 -88.392)
		(width 0.17272)
		(layer "B.Cu")
		(net "FM_HS1_EN_BUSBAR_BUF")
	)
	(segment
		(start 299.593 -88.392)
		(end 298.68495 -87.48395)
		(width 0.17272)
		(layer "B.Cu")
		(net "FM_HS1_EN_BUSBAR_BUF")
	)
	(segment
		(start 296.799 -87.48395)
		(end 295.402 -87.48395)
		(width 0.17272)
		(layer "B.Cu")
		(net "FM_HS1_EN_BUSBAR_BUF")
	)
	(segment
		(start 295.055036 -87.136986)
		(end 295.402 -87.48395)
		(width 0.17272)
		(layer "B.Cu")
		(net "FM_HS1_EN_BUSBAR_BUF")
	)
	(segment
		(start 294.06596 -87.136986)
		(end 295.055036 -87.136986)
		(width 0.17272)
		(layer "B.Cu")
		(net "FM_HS1_EN_BUSBAR_BUF")
	)
	(segment
		(start 328.825098 -88.9)
		(end 299.593 -88.9)
		(width 0.12954)
		(layer "In2.Cu")
		(net "FM_HS1_EN_BUSBAR_BUF")
	)
	(segment
		(start 418.086032 -44.657772)
		(end 416.687 -43.25874)
		(width 0.12954)
		(layer "In2.Cu")
		(net "FM_HS1_EN_BUSBAR_BUF")
	)
	(segment
		(start 337.13674 -80.588358)
		(end 328.825098 -88.9)
		(width 0.12954)
		(layer "In2.Cu")
		(net "FM_HS1_EN_BUSBAR_BUF")
	)
	(segment
		(start 411.490668 -43.677332)
		(end 411.490668 -50.763678)
		(width 0.12954)
		(layer "In2.Cu")
		(net "FM_HS1_EN_BUSBAR_BUF")
	)
	(segment
		(start 420.958772 -44.657772)
		(end 418.086032 -44.657772)
		(width 0.12954)
		(layer "In2.Cu")
		(net "FM_HS1_EN_BUSBAR_BUF")
	)
	(segment
		(start 411.90926 -43.25874)
		(end 411.490668 -43.677332)
		(width 0.12954)
		(layer "In2.Cu")
		(net "FM_HS1_EN_BUSBAR_BUF")
	)
	(segment
		(start 421.132 -45.593)
		(end 421.132 -44.831)
		(width 0.12954)
		(layer "In2.Cu")
		(net "FM_HS1_EN_BUSBAR_BUF")
	)
	(segment
		(start 376.50801 -62.462664)
		(end 358.382316 -80.588358)
		(width 0.12954)
		(layer "In2.Cu")
		(net "FM_HS1_EN_BUSBAR_BUF")
	)
	(segment
		(start 411.490668 -50.763678)
		(end 399.791682 -62.462664)
		(width 0.12954)
		(layer "In2.Cu")
		(net "FM_HS1_EN_BUSBAR_BUF")
	)
	(segment
		(start 358.382316 -80.588358)
		(end 337.13674 -80.588358)
		(width 0.12954)
		(layer "In2.Cu")
		(net "FM_HS1_EN_BUSBAR_BUF")
	)
	(segment
		(start 416.687 -43.25874)
		(end 411.90926 -43.25874)
		(width 0.12954)
		(layer "In2.Cu")
		(net "FM_HS1_EN_BUSBAR_BUF")
	)
	(segment
		(start 399.791682 -62.462664)
		(end 376.50801 -62.462664)
		(width 0.12954)
		(layer "In2.Cu")
		(net "FM_HS1_EN_BUSBAR_BUF")
	)
	(segment
		(start 421.132 -44.831)
		(end 420.958772 -44.657772)
		(width 0.12954)
		(layer "In2.Cu")
		(net "FM_HS1_EN_BUSBAR_BUF")
	)
	(segment
		(start 427.35881 -33.15081)
		(end 419.93058 -33.15081)
		(width 0.17272)
		(layer "F.Cu")
		(net "P12V_LED_EN_BUF")
	)
	(segment
		(start 427.99 -33.782)
		(end 427.35881 -33.15081)
		(width 0.17272)
		(layer "F.Cu")
		(net "P12V_LED_EN_BUF")
	)
	(via
		(at 427.99 -33.782)
		(size 0.508)
		(drill 0.254)
		(layers "F.Cu" "B.Cu")
		(net "P12V_LED_EN_BUF")
	)
	(segment
		(start 442.595 -51.308)
		(end 443.103 -50.8)
		(width 0.17272)
		(layer "B.Cu")
		(net "P12V_LED_EN_BUF")
	)
	(segment
		(start 427.99 -33.782)
		(end 429.26 -35.052)
		(width 0.17272)
		(layer "B.Cu")
		(net "P12V_LED_EN_BUF")
	)
	(segment
		(start 436.372 -46.355)
		(end 436.372 -50.673)
		(width 0.17272)
		(layer "B.Cu")
		(net "P12V_LED_EN_BUF")
	)
	(segment
		(start 431.038 -42.291)
		(end 432.308 -42.291)
		(width 0.17272)
		(layer "B.Cu")
		(net "P12V_LED_EN_BUF")
	)
	(segment
		(start 437.007 -51.308)
		(end 442.595 -51.308)
		(width 0.17272)
		(layer "B.Cu")
		(net "P12V_LED_EN_BUF")
	)
	(segment
		(start 430.784 -42.037)
		(end 431.038 -42.291)
		(width 0.17272)
		(layer "B.Cu")
		(net "P12V_LED_EN_BUF")
	)
	(segment
		(start 436.372 -50.673)
		(end 437.007 -51.308)
		(width 0.17272)
		(layer "B.Cu")
		(net "P12V_LED_EN_BUF")
	)
	(segment
		(start 446.741296 -49.153572)
		(end 446.741296 -48.57496)
		(width 0.17272)
		(layer "B.Cu")
		(net "P12V_LED_EN_BUF")
	)
	(segment
		(start 443.103 -50.8)
		(end 445.094868 -50.8)
		(width 0.17272)
		(layer "B.Cu")
		(net "P12V_LED_EN_BUF")
	)
	(segment
		(start 430.784 -36.322)
		(end 430.784 -42.037)
		(width 0.17272)
		(layer "B.Cu")
		(net "P12V_LED_EN_BUF")
	)
	(segment
		(start 429.26 -35.052)
		(end 429.514 -35.052)
		(width 0.17272)
		(layer "B.Cu")
		(net "P12V_LED_EN_BUF")
	)
	(segment
		(start 445.094868 -50.8)
		(end 446.741296 -49.153572)
		(width 0.17272)
		(layer "B.Cu")
		(net "P12V_LED_EN_BUF")
	)
	(segment
		(start 432.308 -42.291)
		(end 436.372 -46.355)
		(width 0.17272)
		(layer "B.Cu")
		(net "P12V_LED_EN_BUF")
	)
	(segment
		(start 429.514 -35.052)
		(end 430.784 -36.322)
		(width 0.17272)
		(layer "B.Cu")
		(net "P12V_LED_EN_BUF")
	)
	(via
		(at 442.849 -47.625)
		(size 0.6604)
		(drill 0.3302)
		(layers "F.Cu" "B.Cu")
		(net "P3V3_HPDB_PG_R1")
	)
	(segment
		(start 442.849 -47.625)
		(end 444.341504 -47.625)
		(width 0.17272)
		(layer "B.Cu")
		(net "P3V3_HPDB_PG_R1")
	)
	(segment
		(start 441.97905 -47.625)
		(end 442.849 -47.625)
		(width 0.17272)
		(layer "B.Cu")
		(net "P3V3_HPDB_PG_R1")
	)
	(segment
		(start 441.72505 -47.371)
		(end 441.97905 -47.625)
		(width 0.17272)
		(layer "B.Cu")
		(net "P3V3_HPDB_PG_R1")
	)
	(via
		(at 442.849 -45.974)
		(size 0.6604)
		(drill 0.3302)
		(layers "F.Cu" "B.Cu")
		(net "FAN_PWR_EN_BUF_R")
	)
	(segment
		(start 442.849 -45.974)
		(end 443.483746 -45.974)
		(width 0.17272)
		(layer "B.Cu")
		(net "FAN_PWR_EN_BUF_R")
	)
	(segment
		(start 444.184786 -46.67504)
		(end 444.341504 -46.67504)
		(width 0.17272)
		(layer "B.Cu")
		(net "FAN_PWR_EN_BUF_R")
	)
	(segment
		(start 441.72505 -45.974)
		(end 442.849 -45.974)
		(width 0.17272)
		(layer "B.Cu")
		(net "FAN_PWR_EN_BUF_R")
	)
	(segment
		(start 443.483746 -45.974)
		(end 444.184786 -46.67504)
		(width 0.17272)
		(layer "B.Cu")
		(net "FAN_PWR_EN_BUF_R")
	)
	(via
		(at 418.465 -35.56)
		(size 0.6604)
		(drill 0.3302)
		(layers "F.Cu" "B.Cu")
		(net "PU_U39_PIN1")
	)
	(segment
		(start 418.465 -35.56)
		(end 418.465 -36.449)
		(width 0.17272)
		(layer "B.Cu")
		(net "PU_U39_PIN1")
	)
	(segment
		(start 418.465 -36.449)
		(end 418.021008 -36.892992)
		(width 0.17272)
		(layer "B.Cu")
		(net "PU_U39_PIN1")
	)
	(segment
		(start 418.973 -35.052)
		(end 419.71595 -35.052)
		(width 0.17272)
		(layer "B.Cu")
		(net "PU_U39_PIN1")
	)
	(segment
		(start 418.465 -35.56)
		(end 418.973 -35.052)
		(width 0.17272)
		(layer "B.Cu")
		(net "PU_U39_PIN1")
	)
	(segment
		(start 418.021008 -36.892992)
		(end 417.449 -36.892992)
		(width 0.17272)
		(layer "B.Cu")
		(net "PU_U39_PIN1")
	)
	(via
		(at 427.228 -40.64)
		(size 0.6604)
		(drill 0.3302)
		(layers "F.Cu" "B.Cu")
		(net "TP_U39_P17")
	)
	(segment
		(start 426.085 -40.005)
		(end 425.45 -40.005)
		(width 0.17272)
		(layer "B.Cu")
		(net "TP_U39_P17")
	)
	(segment
		(start 427.228 -40.64)
		(end 426.72 -40.64)
		(width 0.17272)
		(layer "B.Cu")
		(net "TP_U39_P17")
	)
	(segment
		(start 425.45 -40.005)
		(end 424.937936 -39.492936)
		(width 0.17272)
		(layer "B.Cu")
		(net "TP_U39_P17")
	)
	(segment
		(start 426.72 -40.64)
		(end 426.085 -40.005)
		(width 0.17272)
		(layer "B.Cu")
		(net "TP_U39_P17")
	)
	(segment
		(start 424.937936 -39.492936)
		(end 423.291 -39.492936)
		(width 0.17272)
		(layer "B.Cu")
		(net "TP_U39_P17")
	)
	(via
		(at 421.894 -45.339)
		(size 0.6604)
		(drill 0.3302)
		(layers "F.Cu" "B.Cu")
		(net "TP_U39_P16")
	)
	(segment
		(start 421.64 -45.085)
		(end 421.64 -40.767)
		(width 0.17272)
		(layer "B.Cu")
		(net "TP_U39_P16")
	)
	(segment
		(start 421.64 -40.767)
		(end 422.264078 -40.142922)
		(width 0.17272)
		(layer "B.Cu")
		(net "TP_U39_P16")
	)
	(segment
		(start 422.264078 -40.142922)
		(end 423.291 -40.142922)
		(width 0.17272)
		(layer "B.Cu")
		(net "TP_U39_P16")
	)
	(segment
		(start 421.894 -45.339)
		(end 421.64 -45.085)
		(width 0.17272)
		(layer "B.Cu")
		(net "TP_U39_P16")
	)
	(via
		(at 426.847 -41.91)
		(size 0.6604)
		(drill 0.3302)
		(layers "F.Cu" "B.Cu")
		(net "TP_U39_P15")
	)
	(segment
		(start 426.847 -41.91)
		(end 425.703746 -41.91)
		(width 0.17272)
		(layer "B.Cu")
		(net "TP_U39_P15")
	)
	(segment
		(start 424.586908 -40.793162)
		(end 423.291 -40.793162)
		(width 0.17272)
		(layer "B.Cu")
		(net "TP_U39_P15")
	)
	(segment
		(start 425.703746 -41.91)
		(end 424.586908 -40.793162)
		(width 0.17272)
		(layer "B.Cu")
		(net "TP_U39_P15")
	)
	(via
		(at 425.958 -43.053)
		(size 0.6604)
		(drill 0.3302)
		(layers "F.Cu" "B.Cu")
		(net "TP_U39_P14")
	)
	(segment
		(start 425.958 -43.053)
		(end 424.348148 -41.443148)
		(width 0.17272)
		(layer "B.Cu")
		(net "TP_U39_P14")
	)
	(segment
		(start 424.348148 -41.443148)
		(end 423.291 -41.443148)
		(width 0.17272)
		(layer "B.Cu")
		(net "TP_U39_P14")
	)
	(via
		(at 423.291 -45.339)
		(size 0.6604)
		(drill 0.3302)
		(layers "F.Cu" "B.Cu")
		(net "TP_U39_P13")
	)
	(segment
		(start 422.148 -42.347134)
		(end 422.402 -42.093134)
		(width 0.17272)
		(layer "B.Cu")
		(net "TP_U39_P13")
	)
	(segment
		(start 422.148 -44.196)
		(end 422.148 -42.347134)
		(width 0.17272)
		(layer "B.Cu")
		(net "TP_U39_P13")
	)
	(segment
		(start 423.291 -45.339)
		(end 422.148 -44.196)
		(width 0.17272)
		(layer "B.Cu")
		(net "TP_U39_P13")
	)
	(segment
		(start 422.402 -42.093134)
		(end 423.291 -42.093134)
		(width 0.17272)
		(layer "B.Cu")
		(net "TP_U39_P13")
	)
	(via
		(at 426.72 -44.45)
		(size 0.6604)
		(drill 0.3302)
		(layers "F.Cu" "B.Cu")
		(net "TP_U39_P12")
	)
	(segment
		(start 426.212 -44.45)
		(end 424.50512 -42.74312)
		(width 0.17272)
		(layer "B.Cu")
		(net "TP_U39_P12")
	)
	(segment
		(start 424.50512 -42.74312)
		(end 423.291 -42.74312)
		(width 0.17272)
		(layer "B.Cu")
		(net "TP_U39_P12")
	)
	(segment
		(start 426.72 -44.45)
		(end 426.212 -44.45)
		(width 0.17272)
		(layer "B.Cu")
		(net "TP_U39_P12")
	)
	(via
		(at 425.323 -44.45)
		(size 0.6604)
		(drill 0.3302)
		(layers "F.Cu" "B.Cu")
		(net "TP_U39_P11")
	)
	(segment
		(start 424.266106 -43.393106)
		(end 425.323 -44.45)
		(width 0.17272)
		(layer "B.Cu")
		(net "TP_U39_P11")
	)
	(segment
		(start 423.291 -43.393106)
		(end 424.266106 -43.393106)
		(width 0.17272)
		(layer "B.Cu")
		(net "TP_U39_P11")
	)
	(via
		(at 426.085 -46.228)
		(size 0.6604)
		(drill 0.3302)
		(layers "F.Cu" "B.Cu")
		(net "TP_U39_P10")
	)
	(segment
		(start 423.900092 -44.043092)
		(end 423.291 -44.043092)
		(width 0.17272)
		(layer "B.Cu")
		(net "TP_U39_P10")
	)
	(segment
		(start 426.085 -46.228)
		(end 423.900092 -44.043092)
		(width 0.17272)
		(layer "B.Cu")
		(net "TP_U39_P10")
	)
	(via
		(at 419.735 -46.99)
		(size 0.6604)
		(drill 0.3302)
		(layers "F.Cu" "B.Cu")
		(net "TP_U39_P07")
	)
	(segment
		(start 419.186106 -43.393106)
		(end 417.449 -43.393106)
		(width 0.17272)
		(layer "B.Cu")
		(net "TP_U39_P07")
	)
	(segment
		(start 419.735 -43.942)
		(end 419.186106 -43.393106)
		(width 0.17272)
		(layer "B.Cu")
		(net "TP_U39_P07")
	)
	(segment
		(start 419.735 -46.99)
		(end 419.735 -43.942)
		(width 0.17272)
		(layer "B.Cu")
		(net "TP_U39_P07")
	)
	(via
		(at 421.259 -46.482)
		(size 0.6604)
		(drill 0.3302)
		(layers "F.Cu" "B.Cu")
		(net "TP_U39_P06")
	)
	(segment
		(start 421.259 -46.482)
		(end 420.497 -45.72)
		(width 0.17272)
		(layer "B.Cu")
		(net "TP_U39_P06")
	)
	(segment
		(start 420.497 -44.028614)
		(end 419.211506 -42.74312)
		(width 0.17272)
		(layer "B.Cu")
		(net "TP_U39_P06")
	)
	(segment
		(start 420.497 -45.72)
		(end 420.497 -44.028614)
		(width 0.17272)
		(layer "B.Cu")
		(net "TP_U39_P06")
	)
	(segment
		(start 419.211506 -42.74312)
		(end 417.449 -42.74312)
		(width 0.17272)
		(layer "B.Cu")
		(net "TP_U39_P06")
	)
	(via
		(at 416.941 -45.212)
		(size 0.6604)
		(drill 0.3302)
		(layers "F.Cu" "B.Cu")
		(net "TP_U39_P05")
	)
	(segment
		(start 416.306 -42.545)
		(end 416.757866 -42.093134)
		(width 0.17272)
		(layer "B.Cu")
		(net "TP_U39_P05")
	)
	(segment
		(start 416.306 -44.577)
		(end 416.306 -42.545)
		(width 0.17272)
		(layer "B.Cu")
		(net "TP_U39_P05")
	)
	(segment
		(start 416.757866 -42.093134)
		(end 417.449 -42.093134)
		(width 0.17272)
		(layer "B.Cu")
		(net "TP_U39_P05")
	)
	(segment
		(start 416.941 -45.212)
		(end 416.306 -44.577)
		(width 0.17272)
		(layer "B.Cu")
		(net "TP_U39_P05")
	)
	(via
		(at 424.942 -37.211)
		(size 0.6604)
		(drill 0.3302)
		(layers "F.Cu" "B.Cu")
		(net "SMB_IOEXP_2_SCL")
	)
	(segment
		(start 424.942 -37.211)
		(end 425.196 -36.957)
		(width 0.17272)
		(layer "B.Cu")
		(net "SMB_IOEXP_2_SCL")
	)
	(segment
		(start 424.214036 -38.192964)
		(end 424.942 -37.465)
		(width 0.17272)
		(layer "B.Cu")
		(net "SMB_IOEXP_2_SCL")
	)
	(segment
		(start 425.196 -36.957)
		(end 426.19295 -36.957)
		(width 0.17272)
		(layer "B.Cu")
		(net "SMB_IOEXP_2_SCL")
	)
	(segment
		(start 424.942 -37.465)
		(end 424.942 -37.211)
		(width 0.17272)
		(layer "B.Cu")
		(net "SMB_IOEXP_2_SCL")
	)
	(segment
		(start 423.291 -38.192964)
		(end 424.214036 -38.192964)
		(width 0.17272)
		(layer "B.Cu")
		(net "SMB_IOEXP_2_SCL")
	)
	(via
		(at 424.942 -35.814)
		(size 0.6604)
		(drill 0.3302)
		(layers "F.Cu" "B.Cu")
		(net "SMB_IOEXP_2_SDA")
	)
	(segment
		(start 424.942 -35.814)
		(end 425.450254 -35.814)
		(width 0.17272)
		(layer "B.Cu")
		(net "SMB_IOEXP_2_SDA")
	)
	(segment
		(start 424.307 -36.449)
		(end 424.307 -37.211)
		(width 0.17272)
		(layer "B.Cu")
		(net "SMB_IOEXP_2_SDA")
	)
	(segment
		(start 424.307 -37.211)
		(end 423.975022 -37.542978)
		(width 0.17272)
		(layer "B.Cu")
		(net "SMB_IOEXP_2_SDA")
	)
	(segment
		(start 425.577254 -35.941)
		(end 426.19295 -35.941)
		(width 0.17272)
		(layer "B.Cu")
		(net "SMB_IOEXP_2_SDA")
	)
	(segment
		(start 425.450254 -35.814)
		(end 425.577254 -35.941)
		(width 0.17272)
		(layer "B.Cu")
		(net "SMB_IOEXP_2_SDA")
	)
	(segment
		(start 424.942 -35.814)
		(end 424.307 -36.449)
		(width 0.17272)
		(layer "B.Cu")
		(net "SMB_IOEXP_2_SDA")
	)
	(segment
		(start 423.975022 -37.542978)
		(end 423.291 -37.542978)
		(width 0.17272)
		(layer "B.Cu")
		(net "SMB_IOEXP_2_SDA")
	)
	(via
		(at 415.163 -37.465)
		(size 0.6604)
		(drill 0.3302)
		(layers "F.Cu" "B.Cu")
		(net "PCA9555_2_A2")
	)
	(segment
		(start 414.015682 -37.509704)
		(end 414.015682 -37.949632)
		(width 0.17272)
		(layer "B.Cu")
		(net "PCA9555_2_A2")
	)
	(segment
		(start 415.163 -37.465)
		(end 414.782 -37.084)
		(width 0.17272)
		(layer "B.Cu")
		(net "PCA9555_2_A2")
	)
	(segment
		(start 414.782 -37.084)
		(end 414.03905 -37.084)
		(width 0.17272)
		(layer "B.Cu")
		(net "PCA9555_2_A2")
	)
	(segment
		(start 414.015936 -37.50945)
		(end 414.015682 -37.509704)
		(width 0.17272)
		(layer "B.Cu")
		(net "PCA9555_2_A2")
	)
	(segment
		(start 417.449 -38.192964)
		(end 415.890964 -38.192964)
		(width 0.17272)
		(layer "B.Cu")
		(net "PCA9555_2_A2")
	)
	(segment
		(start 415.890964 -38.192964)
		(end 415.163 -37.465)
		(width 0.17272)
		(layer "B.Cu")
		(net "PCA9555_2_A2")
	)
	(segment
		(start 414.015682 -37.949632)
		(end 414.03905 -37.973)
		(width 0.17272)
		(layer "B.Cu")
		(net "PCA9555_2_A2")
	)
	(segment
		(start 414.03905 -37.084)
		(end 414.015936 -37.107114)
		(width 0.17272)
		(layer "B.Cu")
		(net "PCA9555_2_A2")
	)
	(segment
		(start 414.015936 -37.107114)
		(end 414.015936 -37.50945)
		(width 0.17272)
		(layer "B.Cu")
		(net "PCA9555_2_A2")
	)
	(via
		(at 415.29 -36.195)
		(size 0.6604)
		(drill 0.3302)
		(layers "F.Cu" "B.Cu")
		(net "PCA9555_2_A1")
	)
	(segment
		(start 415.29 -36.195)
		(end 414.03905 -36.195)
		(width 0.17272)
		(layer "B.Cu")
		(net "PCA9555_2_A1")
	)
	(segment
		(start 414.041082 -36.192968)
		(end 414.041082 -35.308032)
		(width 0.17272)
		(layer "B.Cu")
		(net "PCA9555_2_A1")
	)
	(segment
		(start 416.637978 -37.542978)
		(end 415.29 -36.195)
		(width 0.17272)
		(layer "B.Cu")
		(net "PCA9555_2_A1")
	)
	(segment
		(start 417.449 -37.542978)
		(end 416.637978 -37.542978)
		(width 0.17272)
		(layer "B.Cu")
		(net "PCA9555_2_A1")
	)
	(segment
		(start 414.041082 -35.308032)
		(end 414.03905 -35.306)
		(width 0.17272)
		(layer "B.Cu")
		(net "PCA9555_2_A1")
	)
	(segment
		(start 414.03905 -36.195)
		(end 414.041082 -36.192968)
		(width 0.17272)
		(layer "B.Cu")
		(net "PCA9555_2_A1")
	)
	(via
		(at 425.0055 -38.5445)
		(size 0.6604)
		(drill 0.3302)
		(layers "F.Cu" "B.Cu")
		(net "PCA9555_2_A0")
	)
	(segment
		(start 424.70705 -38.84295)
		(end 423.291 -38.84295)
		(width 0.17272)
		(layer "B.Cu")
		(net "PCA9555_2_A0")
	)
	(segment
		(start 426.19295 -38.989)
		(end 426.19295 -37.973)
		(width 0.17272)
		(layer "B.Cu")
		(net "PCA9555_2_A0")
	)
	(segment
		(start 425.0055 -38.5445)
		(end 424.70705 -38.84295)
		(width 0.17272)
		(layer "B.Cu")
		(net "PCA9555_2_A0")
	)
	(segment
		(start 425.0055 -38.5445)
		(end 425.577 -37.973)
		(width 0.17272)
		(layer "B.Cu")
		(net "PCA9555_2_A0")
	)
	(segment
		(start 425.577 -37.973)
		(end 426.19295 -37.973)
		(width 0.17272)
		(layer "B.Cu")
		(net "PCA9555_2_A0")
	)
	(segment
		(start 415.150554 -29.252672)
		(end 414.363154 -29.252672)
		(width 0.17272)
		(layer "F.Cu")
		(net "PWRGD_P12V_FAN_LED_R")
	)
	(segment
		(start 414.356042 -29.24556)
		(end 413.47263 -29.24556)
		(width 0.17272)
		(layer "F.Cu")
		(net "PWRGD_P12V_FAN_LED_R")
	)
	(segment
		(start 414.363154 -29.252672)
		(end 414.356042 -29.24556)
		(width 0.17272)
		(layer "F.Cu")
		(net "PWRGD_P12V_FAN_LED_R")
	)
	(via
		(at 414.356042 -29.24556)
		(size 0.508)
		(drill 0.254)
		(layers "F.Cu" "B.Cu")
		(net "PWRGD_P12V_FAN_LED_R")
	)
	(via
		(at 413.23895 -39.624)
		(size 0.508)
		(drill 0.254)
		(layers "F.Cu" "B.Cu")
		(net "PWRGD_P12V_FAN_LED_R")
	)
	(segment
		(start 413.23895 -38.989)
		(end 413.23895 -39.624)
		(width 0.17272)
		(layer "B.Cu")
		(net "PWRGD_P12V_FAN_LED_R")
	)
	(segment
		(start 413.23895 -39.624)
		(end 414.356042 -38.506908)
		(width 0.12954)
		(layer "In2.Cu")
		(net "PWRGD_P12V_FAN_LED_R")
	)
	(segment
		(start 414.356042 -38.506908)
		(end 414.356042 -29.24556)
		(width 0.12954)
		(layer "In2.Cu")
		(net "PWRGD_P12V_FAN_LED_R")
	)
	(segment
		(start 450.198998 -50.891948)
		(end 450.23405 -50.927)
		(width 0.17272)
		(layer "F.Cu")
		(net "PWRGD_P3V3_HPDB_R")
	)
	(segment
		(start 450.198998 -48.514)
		(end 450.198998 -50.891948)
		(width 0.17272)
		(layer "F.Cu")
		(net "PWRGD_P3V3_HPDB_R")
	)
	(segment
		(start 451.612 -50.927)
		(end 450.23405 -50.927)
		(width 0.17272)
		(layer "F.Cu")
		(net "PWRGD_P3V3_HPDB_R")
	)
	(segment
		(start 451.612 -49.67605)
		(end 451.612 -50.927)
		(width 0.17272)
		(layer "F.Cu")
		(net "PWRGD_P3V3_HPDB_R")
	)
	(via
		(at 451.612 -50.927)
		(size 0.762)
		(drill 0.381)
		(layers "F.Cu" "B.Cu")
		(net "PWRGD_P3V3_HPDB_R")
	)
	(segment
		(start 451.612 -48.87595)
		(end 451.612 -48.133)
		(width 0.17272)
		(layer "F.Cu")
		(net "PWRGD_P3V3_HPDB")
	)
	(via
		(at 451.612 -48.133)
		(size 0.508)
		(drill 0.254)
		(layers "F.Cu" "B.Cu")
		(net "PWRGD_P3V3_HPDB")
	)
	(via
		(at 460.121 -47.244)
		(size 0.508)
		(drill 0.254)
		(layers "F.Cu" "B.Cu")
		(net "PWRGD_P3V3_HPDB")
	)
	(segment
		(start 462.71688 -76.378562)
		(end 465.047838 -78.70952)
		(width 0.17272)
		(layer "B.Cu")
		(net "PWRGD_P3V3_HPDB")
	)
	(segment
		(start 470.281 -78.70952)
		(end 470.905078 -79.333598)
		(width 0.17272)
		(layer "B.Cu")
		(net "PWRGD_P3V3_HPDB")
	)
	(segment
		(start 460.121 -47.244)
		(end 462.71688 -49.83988)
		(width 0.17272)
		(layer "B.Cu")
		(net "PWRGD_P3V3_HPDB")
	)
	(segment
		(start 470.905078 -79.333598)
		(end 470.905078 -81.080102)
		(width 0.17272)
		(layer "B.Cu")
		(net "PWRGD_P3V3_HPDB")
	)
	(segment
		(start 462.71688 -49.83988)
		(end 462.71688 -76.378562)
		(width 0.17272)
		(layer "B.Cu")
		(net "PWRGD_P3V3_HPDB")
	)
	(segment
		(start 465.047838 -78.70952)
		(end 470.281 -78.70952)
		(width 0.17272)
		(layer "B.Cu")
		(net "PWRGD_P3V3_HPDB")
	)
	(segment
		(start 460.121 -47.244)
		(end 459.232 -48.133)
		(width 0.12954)
		(layer "In2.Cu")
		(net "PWRGD_P3V3_HPDB")
	)
	(segment
		(start 459.232 -48.133)
		(end 451.612 -48.133)
		(width 0.12954)
		(layer "In2.Cu")
		(net "PWRGD_P3V3_HPDB")
	)
	(segment
		(start 414.42005 -41.529)
		(end 415.417 -41.529)
		(width 0.17272)
		(layer "F.Cu")
		(net "PRSNT_FAN_BP1_N")
	)
	(segment
		(start 416.48888 -42.09288)
		(end 417.449 -42.09288)
		(width 0.17272)
		(layer "F.Cu")
		(net "PRSNT_FAN_BP1_N")
	)
	(segment
		(start 415.417 -41.529)
		(end 415.671 -41.275)
		(width 0.17272)
		(layer "F.Cu")
		(net "PRSNT_FAN_BP1_N")
	)
	(segment
		(start 415.671 -41.275)
		(end 416.48888 -42.09288)
		(width 0.17272)
		(layer "F.Cu")
		(net "PRSNT_FAN_BP1_N")
	)
	(via
		(at 415.671 -41.275)
		(size 0.762)
		(drill 0.381)
		(layers "F.Cu" "B.Cu")
		(net "PRSNT_FAN_BP1_N")
	)
	(segment
		(start 414.42005 -42.545)
		(end 415.544 -42.545)
		(width 0.17272)
		(layer "F.Cu")
		(net "PRSNT_FAN_BP0_N")
	)
	(segment
		(start 415.74212 -42.74312)
		(end 415.671 -42.672)
		(width 0.17272)
		(layer "F.Cu")
		(net "PRSNT_FAN_BP0_N")
	)
	(segment
		(start 417.449 -42.74312)
		(end 415.74212 -42.74312)
		(width 0.17272)
		(layer "F.Cu")
		(net "PRSNT_FAN_BP0_N")
	)
	(segment
		(start 415.544 -42.545)
		(end 415.671 -42.672)
		(width 0.17272)
		(layer "F.Cu")
		(net "PRSNT_FAN_BP0_N")
	)
	(via
		(at 415.671 -42.672)
		(size 0.762)
		(drill 0.381)
		(layers "F.Cu" "B.Cu")
		(net "PRSNT_FAN_BP0_N")
	)
	(via
		(at 417.377118 -34.303716)
		(size 0.6604)
		(drill 0.3302)
		(layers "F.Cu" "B.Cu")
		(net "P12V_LED_ISET_R")
	)
	(segment
		(start 417.900358 -33.780476)
		(end 417.377118 -34.303716)
		(width 0.17272)
		(layer "B.Cu")
		(net "P12V_LED_ISET_R")
	)
	(segment
		(start 416.833558 -33.167066)
		(end 416.833558 -33.760156)
		(width 0.17272)
		(layer "B.Cu")
		(net "P12V_LED_ISET_R")
	)
	(segment
		(start 417.900358 -33.159446)
		(end 417.900358 -33.780476)
		(width 0.17272)
		(layer "B.Cu")
		(net "P12V_LED_ISET_R")
	)
	(segment
		(start 416.833558 -33.760156)
		(end 417.377118 -34.303716)
		(width 0.17272)
		(layer "B.Cu")
		(net "P12V_LED_ISET_R")
	)
	(via
		(at 414.03905 -40.132)
		(size 0.6604)
		(drill 0.3302)
		(layers "F.Cu" "B.Cu")
		(net "PWRGD_P12V_FAN_LED")
	)
	(segment
		(start 414.03905 -40.132)
		(end 414.03905 -38.989)
		(width 0.17272)
		(layer "B.Cu")
		(net "PWRGD_P12V_FAN_LED")
	)
	(segment
		(start 414.03905 -40.132)
		(end 415.036254 -40.132)
		(width 0.17272)
		(layer "B.Cu")
		(net "PWRGD_P12V_FAN_LED")
	)
	(segment
		(start 415.036254 -40.132)
		(end 416.325304 -38.84295)
		(width 0.17272)
		(layer "B.Cu")
		(net "PWRGD_P12V_FAN_LED")
	)
	(segment
		(start 416.325304 -38.84295)
		(end 417.449 -38.84295)
		(width 0.17272)
		(layer "B.Cu")
		(net "PWRGD_P12V_FAN_LED")
	)
	(segment
		(start 447.802 -49.860962)
		(end 448.199002 -49.46396)
		(width 0.17272)
		(layer "F.Cu")
		(net "PWRGD_P3V3_HPDB_R_N")
	)
	(segment
		(start 446.55105 -50.927)
		(end 447.802 -50.927)
		(width 0.17272)
		(layer "F.Cu")
		(net "PWRGD_P3V3_HPDB_R_N")
	)
	(segment
		(start 446.642998 -50.835052)
		(end 446.55105 -50.927)
		(width 0.17272)
		(layer "F.Cu")
		(net "PWRGD_P3V3_HPDB_R_N")
	)
	(segment
		(start 446.642998 -48.514)
		(end 446.642998 -50.835052)
		(width 0.17272)
		(layer "F.Cu")
		(net "PWRGD_P3V3_HPDB_R_N")
	)
	(segment
		(start 447.802 -50.927)
		(end 447.802 -49.860962)
		(width 0.17272)
		(layer "F.Cu")
		(net "PWRGD_P3V3_HPDB_R_N")
	)
	(via
		(at 447.802 -50.927)
		(size 0.762)
		(drill 0.381)
		(layers "F.Cu" "B.Cu")
		(net "PWRGD_P3V3_HPDB_R_N")
	)
	(segment
		(start 438.163208 -62.32398)
		(end 438.130188 -62.357)
		(width 0.17272)
		(layer "F.Cu")
		(net "LED_D6_R1")
	)
	(segment
		(start 439.14695 -63.5)
		(end 438.658254 -63.5)
		(width 0.17272)
		(layer "F.Cu")
		(net "LED_D6_R1")
	)
	(segment
		(start 439.674 -62.32398)
		(end 438.163208 -62.32398)
		(width 0.17272)
		(layer "F.Cu")
		(net "LED_D6_R1")
	)
	(segment
		(start 438.130188 -62.971934)
		(end 438.130188 -62.357)
		(width 0.17272)
		(layer "F.Cu")
		(net "LED_D6_R1")
	)
	(segment
		(start 438.658254 -63.5)
		(end 438.130188 -62.971934)
		(width 0.17272)
		(layer "F.Cu")
		(net "LED_D6_R1")
	)
	(via
		(at 438.130188 -62.357)
		(size 0.762)
		(drill 0.381)
		(layers "F.Cu" "B.Cu")
		(net "LED_D6_R1")
	)
	(segment
		(start 438.105296 -50.419)
		(end 437.2864 -50.419)
		(width 0.17272)
		(layer "F.Cu")
		(net "PWRGD_P52V_HS2_PG")
	)
	(segment
		(start 424.05681 -39.492936)
		(end 423.291 -39.492936)
		(width 0.17272)
		(layer "F.Cu")
		(net "PWRGD_P52V_HS2_PG")
	)
	(segment
		(start 422.148 -47.752)
		(end 421.767 -47.371)
		(width 0.17272)
		(layer "F.Cu")
		(net "PWRGD_P52V_HS2_PG")
	)
	(segment
		(start 423.5704 -50.419)
		(end 422.148 -48.9966)
		(width 0.17272)
		(layer "F.Cu")
		(net "PWRGD_P52V_HS2_PG")
	)
	(segment
		(start 417.9824 -38.1)
		(end 417.36645 -38.1)
		(width 0.17272)
		(layer "F.Cu")
		(net "PWRGD_P52V_HS2_PG")
	)
	(segment
		(start 421.2844 -41.402)
		(end 417.9824 -38.1)
		(width 0.17272)
		(layer "F.Cu")
		(net "PWRGD_P52V_HS2_PG")
	)
	(segment
		(start 422.148 -48.9966)
		(end 422.148 -47.752)
		(width 0.17272)
		(layer "F.Cu")
		(net "PWRGD_P52V_HS2_PG")
	)
	(segment
		(start 433.6034 -36.195)
		(end 427.354746 -36.195)
		(width 0.17272)
		(layer "F.Cu")
		(net "PWRGD_P52V_HS2_PG")
	)
	(segment
		(start 417.36645 -38.1)
		(end 415.33445 -36.068)
		(width 0.17272)
		(layer "F.Cu")
		(net "PWRGD_P52V_HS2_PG")
	)
	(segment
		(start 421.767 -47.371)
		(end 421.767 -41.915842)
		(width 0.17272)
		(layer "F.Cu")
		(net "PWRGD_P52V_HS2_PG")
	)
	(segment
		(start 427.354746 -36.195)
		(end 424.05681 -39.492936)
		(width 0.17272)
		(layer "F.Cu")
		(net "PWRGD_P52V_HS2_PG")
	)
	(segment
		(start 421.767 -41.915842)
		(end 421.2844 -41.433242)
		(width 0.17272)
		(layer "F.Cu")
		(net "PWRGD_P52V_HS2_PG")
	)
	(segment
		(start 421.2844 -41.433242)
		(end 421.2844 -41.402)
		(width 0.17272)
		(layer "F.Cu")
		(net "PWRGD_P52V_HS2_PG")
	)
	(via
		(at 175.706786 -78.486)
		(size 0.508)
		(drill 0.254)
		(layers "F.Cu" "B.Cu")
		(net "PWRGD_P52V_HS2_PG")
	)
	(via
		(at 220.2434 -8.001)
		(size 0.508)
		(drill 0.254)
		(layers "F.Cu" "B.Cu")
		(net "PWRGD_P52V_HS2_PG")
	)
	(via
		(at 423.5704 -50.419)
		(size 0.762)
		(drill 0.254)
		(layers "F.Cu" "B.Cu")
		(net "PWRGD_P52V_HS2_PG")
	)
	(via
		(at 437.2864 -50.419)
		(size 0.508)
		(drill 0.254)
		(layers "F.Cu" "B.Cu")
		(net "PWRGD_P52V_HS2_PG")
	)
	(via
		(at 433.6034 -36.195)
		(size 0.508)
		(drill 0.254)
		(layers "F.Cu" "B.Cu")
		(net "PWRGD_P52V_HS2_PG")
	)
	(via
		(at 224.8154 -91.821)
		(size 0.508)
		(drill 0.254)
		(layers "F.Cu" "B.Cu")
		(net "PWRGD_P52V_HS2_PG")
	)
	(segment
		(start 176.216056 -74.909934)
		(end 176.049686 -75.076304)
		(width 0.17272)
		(layer "B.Cu")
		(net "PWRGD_P52V_HS2_PG")
	)
	(segment
		(start 433.50688 -41.58488)
		(end 433.50688 -36.29152)
		(width 0.17272)
		(layer "B.Cu")
		(net "PWRGD_P52V_HS2_PG")
	)
	(segment
		(start 224.8154 -91.821)
		(end 220.2434 -87.249)
		(width 0.17272)
		(layer "B.Cu")
		(net "PWRGD_P52V_HS2_PG")
	)
	(segment
		(start 176.216056 -74.06132)
		(end 176.216056 -74.909934)
		(width 0.17272)
		(layer "B.Cu")
		(net "PWRGD_P52V_HS2_PG")
	)
	(segment
		(start 176.049686 -75.076304)
		(end 176.049686 -76.708)
		(width 0.17272)
		(layer "B.Cu")
		(net "PWRGD_P52V_HS2_PG")
	)
	(segment
		(start 435.5211 -43.5991)
		(end 433.50688 -41.58488)
		(width 0.17272)
		(layer "B.Cu")
		(net "PWRGD_P52V_HS2_PG")
	)
	(segment
		(start 437.2864 -50.419)
		(end 438.27192 -49.43348)
		(width 0.17272)
		(layer "B.Cu")
		(net "PWRGD_P52V_HS2_PG")
	)
	(segment
		(start 176.049686 -77.5081)
		(end 175.706786 -77.851)
		(width 0.17272)
		(layer "B.Cu")
		(net "PWRGD_P52V_HS2_PG")
	)
	(segment
		(start 175.706786 -79.04099)
		(end 175.306736 -79.44104)
		(width 0.17272)
		(layer "B.Cu")
		(net "PWRGD_P52V_HS2_PG")
	)
	(segment
		(start 176.049686 -76.708)
		(end 176.049686 -77.5081)
		(width 0.17272)
		(layer "B.Cu")
		(net "PWRGD_P52V_HS2_PG")
	)
	(segment
		(start 175.706786 -78.486)
		(end 175.706786 -79.04099)
		(width 0.17272)
		(layer "B.Cu")
		(net "PWRGD_P52V_HS2_PG")
	)
	(segment
		(start 438.27192 -44.840906)
		(end 437.030114 -43.5991)
		(width 0.17272)
		(layer "B.Cu")
		(net "PWRGD_P52V_HS2_PG")
	)
	(segment
		(start 220.2434 -87.249)
		(end 220.2434 -8.001)
		(width 0.17272)
		(layer "B.Cu")
		(net "PWRGD_P52V_HS2_PG")
	)
	(segment
		(start 175.706786 -77.851)
		(end 175.706786 -78.486)
		(width 0.17272)
		(layer "B.Cu")
		(net "PWRGD_P52V_HS2_PG")
	)
	(segment
		(start 438.27192 -49.43348)
		(end 438.27192 -44.840906)
		(width 0.17272)
		(layer "B.Cu")
		(net "PWRGD_P52V_HS2_PG")
	)
	(segment
		(start 433.50688 -36.29152)
		(end 433.6034 -36.195)
		(width 0.17272)
		(layer "B.Cu")
		(net "PWRGD_P52V_HS2_PG")
	)
	(segment
		(start 437.030114 -43.5991)
		(end 435.5211 -43.5991)
		(width 0.17272)
		(layer "B.Cu")
		(net "PWRGD_P52V_HS2_PG")
	)
	(segment
		(start 432.129946 -35.5092)
		(end 432.129946 -34.306764)
		(width 0.12954)
		(layer "In2.Cu")
		(net "PWRGD_P52V_HS2_PG")
	)
	(segment
		(start 431.01514 -32.522922)
		(end 429.20666 -30.714442)
		(width 0.12954)
		(layer "In2.Cu")
		(net "PWRGD_P52V_HS2_PG")
	)
	(segment
		(start 184.578498 -79.86268)
		(end 201.308462 -79.86268)
		(width 0.12954)
		(layer "In2.Cu")
		(net "PWRGD_P52V_HS2_PG")
	)
	(segment
		(start 429.963072 -52.705)
		(end 432.249072 -50.419)
		(width 0.12954)
		(layer "In2.Cu")
		(net "PWRGD_P52V_HS2_PG")
	)
	(segment
		(start 403.414738 -8.03148)
		(end 395.238478 -16.20774)
		(width 0.12954)
		(layer "In2.Cu")
		(net "PWRGD_P52V_HS2_PG")
	)
	(segment
		(start 410.66339 -8.03148)
		(end 403.414738 -8.03148)
		(width 0.12954)
		(layer "In2.Cu")
		(net "PWRGD_P52V_HS2_PG")
	)
	(segment
		(start 431.01514 -33.191958)
		(end 431.01514 -32.522922)
		(width 0.12954)
		(layer "In2.Cu")
		(net "PWRGD_P52V_HS2_PG")
	)
	(segment
		(start 388.126478 -16.20774)
		(end 379.794008 -24.54021)
		(width 0.12954)
		(layer "In2.Cu")
		(net "PWRGD_P52V_HS2_PG")
	)
	(segment
		(start 201.308462 -79.86268)
		(end 209.791046 -88.345264)
		(width 0.12954)
		(layer "In2.Cu")
		(net "PWRGD_P52V_HS2_PG")
	)
	(segment
		(start 222.445072 -5.799328)
		(end 220.2434 -8.001)
		(width 0.12954)
		(layer "In2.Cu")
		(net "PWRGD_P52V_HS2_PG")
	)
	(segment
		(start 221.339664 -88.345264)
		(end 224.8154 -91.821)
		(width 0.12954)
		(layer "In2.Cu")
		(net "PWRGD_P52V_HS2_PG")
	)
	(segment
		(start 209.791046 -88.345264)
		(end 221.339664 -88.345264)
		(width 0.12954)
		(layer "In2.Cu")
		(net "PWRGD_P52V_HS2_PG")
	)
	(segment
		(start 432.249072 -50.419)
		(end 437.2864 -50.419)
		(width 0.12954)
		(layer "In2.Cu")
		(net "PWRGD_P52V_HS2_PG")
	)
	(segment
		(start 379.794008 -24.54021)
		(end 366.111282 -24.54021)
		(width 0.12954)
		(layer "In2.Cu")
		(net "PWRGD_P52V_HS2_PG")
	)
	(segment
		(start 362.18114 -18.324322)
		(end 349.656146 -5.799328)
		(width 0.12954)
		(layer "In2.Cu")
		(net "PWRGD_P52V_HS2_PG")
	)
	(segment
		(start 423.5704 -50.419)
		(end 425.8564 -52.705)
		(width 0.12954)
		(layer "In2.Cu")
		(net "PWRGD_P52V_HS2_PG")
	)
	(segment
		(start 432.815746 -36.195)
		(end 432.129946 -35.5092)
		(width 0.12954)
		(layer "In2.Cu")
		(net "PWRGD_P52V_HS2_PG")
	)
	(segment
		(start 175.706786 -78.486)
		(end 183.201818 -78.486)
		(width 0.12954)
		(layer "In2.Cu")
		(net "PWRGD_P52V_HS2_PG")
	)
	(segment
		(start 432.129946 -34.306764)
		(end 431.01514 -33.191958)
		(width 0.12954)
		(layer "In2.Cu")
		(net "PWRGD_P52V_HS2_PG")
	)
	(segment
		(start 425.8564 -52.705)
		(end 429.963072 -52.705)
		(width 0.12954)
		(layer "In2.Cu")
		(net "PWRGD_P52V_HS2_PG")
	)
	(segment
		(start 395.238478 -16.20774)
		(end 388.126478 -16.20774)
		(width 0.12954)
		(layer "In2.Cu")
		(net "PWRGD_P52V_HS2_PG")
	)
	(segment
		(start 433.6034 -36.195)
		(end 432.815746 -36.195)
		(width 0.12954)
		(layer "In2.Cu")
		(net "PWRGD_P52V_HS2_PG")
	)
	(segment
		(start 429.20666 -26.57475)
		(end 410.66339 -8.03148)
		(width 0.12954)
		(layer "In2.Cu")
		(net "PWRGD_P52V_HS2_PG")
	)
	(segment
		(start 429.20666 -30.714442)
		(end 429.20666 -26.57475)
		(width 0.12954)
		(layer "In2.Cu")
		(net "PWRGD_P52V_HS2_PG")
	)
	(segment
		(start 366.111282 -24.54021)
		(end 362.18114 -20.610068)
		(width 0.12954)
		(layer "In2.Cu")
		(net "PWRGD_P52V_HS2_PG")
	)
	(segment
		(start 362.18114 -20.610068)
		(end 362.18114 -18.324322)
		(width 0.12954)
		(layer "In2.Cu")
		(net "PWRGD_P52V_HS2_PG")
	)
	(segment
		(start 349.656146 -5.799328)
		(end 222.445072 -5.799328)
		(width 0.12954)
		(layer "In2.Cu")
		(net "PWRGD_P52V_HS2_PG")
	)
	(segment
		(start 183.201818 -78.486)
		(end 184.578498 -79.86268)
		(width 0.12954)
		(layer "In2.Cu")
		(net "PWRGD_P52V_HS2_PG")
	)
	(segment
		(start 420.51605 -50.546)
		(end 422.021 -50.546)
		(width 0.17272)
		(layer "F.Cu")
		(net "PWRGD_P52V_HS1_PG")
	)
	(segment
		(start 424.031156 -38.84295)
		(end 423.291 -38.84295)
		(width 0.17272)
		(layer "F.Cu")
		(net "PWRGD_P52V_HS1_PG")
	)
	(segment
		(start 424.031156 -38.843204)
		(end 424.031156 -38.84295)
		(width 0.17272)
		(layer "F.Cu")
		(net "PWRGD_P52V_HS1_PG")
	)
	(segment
		(start 427.18736 -35.687)
		(end 424.031156 -38.843204)
		(width 0.17272)
		(layer "F.Cu")
		(net "PWRGD_P52V_HS1_PG")
	)
	(segment
		(start 438.105296 -49.46904)
		(end 437.2864 -49.46904)
		(width 0.17272)
		(layer "F.Cu")
		(net "PWRGD_P52V_HS1_PG")
	)
	(segment
		(start 433.0954 -35.687)
		(end 427.18736 -35.687)
		(width 0.17272)
		(layer "F.Cu")
		(net "PWRGD_P52V_HS1_PG")
	)
	(via
		(at 437.2864 -49.46904)
		(size 0.508)
		(drill 0.254)
		(layers "F.Cu" "B.Cu")
		(net "PWRGD_P52V_HS1_PG")
	)
	(via
		(at 220.2434 -7.112)
		(size 0.508)
		(drill 0.254)
		(layers "F.Cu" "B.Cu")
		(net "PWRGD_P52V_HS1_PG")
	)
	(via
		(at 271.91335 -61.722)
		(size 0.508)
		(drill 0.254)
		(layers "F.Cu" "B.Cu")
		(net "PWRGD_P52V_HS1_PG")
	)
	(via
		(at 433.0954 -35.687)
		(size 0.508)
		(drill 0.254)
		(layers "F.Cu" "B.Cu")
		(net "PWRGD_P52V_HS1_PG")
	)
	(via
		(at 225.425 -90.34272)
		(size 0.508)
		(drill 0.254)
		(layers "F.Cu" "B.Cu")
		(net "PWRGD_P52V_HS1_PG")
	)
	(via
		(at 422.021 -50.546)
		(size 0.508)
		(drill 0.254)
		(layers "F.Cu" "B.Cu")
		(net "PWRGD_P52V_HS1_PG")
	)
	(via
		(at 224.19564 -89.11336)
		(size 0.6604)
		(drill 0.3302)
		(layers "F.Cu" "B.Cu")
		(net "PWRGD_P52V_HS1_PG")
	)
	(segment
		(start 271.57045 -62.6999)
		(end 271.91335 -62.357)
		(width 0.17272)
		(layer "B.Cu")
		(net "PWRGD_P52V_HS1_PG")
	)
	(segment
		(start 271.57045 -65.131696)
		(end 271.57045 -63.5)
		(width 0.17272)
		(layer "B.Cu")
		(net "PWRGD_P52V_HS1_PG")
	)
	(segment
		(start 225.425 -90.34272)
		(end 224.19564 -89.11336)
		(width 0.17272)
		(layer "B.Cu")
		(net "PWRGD_P52V_HS1_PG")
	)
	(segment
		(start 271.91335 -62.357)
		(end 271.91335 -61.722)
		(width 0.17272)
		(layer "B.Cu")
		(net "PWRGD_P52V_HS1_PG")
	)
	(segment
		(start 433.02936 -41.792906)
		(end 433.02936 -35.75304)
		(width 0.17272)
		(layer "B.Cu")
		(net "PWRGD_P52V_HS1_PG")
	)
	(segment
		(start 220.7514 -85.66912)
		(end 220.7514 -7.62)
		(width 0.17272)
		(layer "B.Cu")
		(net "PWRGD_P52V_HS1_PG")
	)
	(segment
		(start 437.7944 -45.466)
		(end 437.3118 -44.9834)
		(width 0.17272)
		(layer "B.Cu")
		(net "PWRGD_P52V_HS1_PG")
	)
	(segment
		(start 271.40408 -66.14668)
		(end 271.40408 -65.298066)
		(width 0.17272)
		(layer "B.Cu")
		(net "PWRGD_P52V_HS1_PG")
	)
	(segment
		(start 220.7514 -7.62)
		(end 220.2434 -7.112)
		(width 0.17272)
		(layer "B.Cu")
		(net "PWRGD_P52V_HS1_PG")
	)
	(segment
		(start 271.40408 -65.298066)
		(end 271.57045 -65.131696)
		(width 0.17272)
		(layer "B.Cu")
		(net "PWRGD_P52V_HS1_PG")
	)
	(segment
		(start 271.91335 -61.722)
		(end 271.91335 -61.16701)
		(width 0.17272)
		(layer "B.Cu")
		(net "PWRGD_P52V_HS1_PG")
	)
	(segment
		(start 271.57045 -63.5)
		(end 271.57045 -62.6999)
		(width 0.17272)
		(layer "B.Cu")
		(net "PWRGD_P52V_HS1_PG")
	)
	(segment
		(start 436.219854 -44.9834)
		(end 433.02936 -41.792906)
		(width 0.17272)
		(layer "B.Cu")
		(net "PWRGD_P52V_HS1_PG")
	)
	(segment
		(start 433.02936 -35.75304)
		(end 433.0954 -35.687)
		(width 0.17272)
		(layer "B.Cu")
		(net "PWRGD_P52V_HS1_PG")
	)
	(segment
		(start 224.19564 -89.11336)
		(end 220.7514 -85.66912)
		(width 0.17272)
		(layer "B.Cu")
		(net "PWRGD_P52V_HS1_PG")
	)
	(segment
		(start 271.91335 -61.16701)
		(end 272.3134 -60.76696)
		(width 0.17272)
		(layer "B.Cu")
		(net "PWRGD_P52V_HS1_PG")
	)
	(segment
		(start 437.3118 -44.9834)
		(end 436.219854 -44.9834)
		(width 0.17272)
		(layer "B.Cu")
		(net "PWRGD_P52V_HS1_PG")
	)
	(segment
		(start 437.7944 -48.96104)
		(end 437.7944 -45.466)
		(width 0.17272)
		(layer "B.Cu")
		(net "PWRGD_P52V_HS1_PG")
	)
	(segment
		(start 437.2864 -49.46904)
		(end 437.7944 -48.96104)
		(width 0.17272)
		(layer "B.Cu")
		(net "PWRGD_P52V_HS1_PG")
	)
	(segment
		(start 423.925746 -49.911)
		(end 422.656 -49.911)
		(width 0.12954)
		(layer "In2.Cu")
		(net "PWRGD_P52V_HS1_PG")
	)
	(segment
		(start 433.0954 -35.687)
		(end 433.0954 -34.4424)
		(width 0.12954)
		(layer "In2.Cu")
		(net "PWRGD_P52V_HS1_PG")
	)
	(segment
		(start 387.8834 -15.621)
		(end 379.55093 -23.95347)
		(width 0.12954)
		(layer "In2.Cu")
		(net "PWRGD_P52V_HS1_PG")
	)
	(segment
		(start 270.284956 -63.350394)
		(end 266.207494 -63.350394)
		(width 0.12954)
		(layer "In2.Cu")
		(net "PWRGD_P52V_HS1_PG")
	)
	(segment
		(start 394.9954 -15.621)
		(end 387.8834 -15.621)
		(width 0.12954)
		(layer "In2.Cu")
		(net "PWRGD_P52V_HS1_PG")
	)
	(segment
		(start 262.974582 -66.583306)
		(end 262.974582 -70.901306)
		(width 0.12954)
		(layer "In2.Cu")
		(net "PWRGD_P52V_HS1_PG")
	)
	(segment
		(start 431.60188 -32.94888)
		(end 431.60188 -32.279844)
		(width 0.12954)
		(layer "In2.Cu")
		(net "PWRGD_P52V_HS1_PG")
	)
	(segment
		(start 263.298178 -72.388222)
		(end 257.4544 -78.232)
		(width 0.12954)
		(layer "In2.Cu")
		(net "PWRGD_P52V_HS1_PG")
	)
	(segment
		(start 422.656 -49.911)
		(end 422.021 -50.546)
		(width 0.12954)
		(layer "In2.Cu")
		(net "PWRGD_P52V_HS1_PG")
	)
	(segment
		(start 429.7934 -30.471364)
		(end 429.7934 -26.331672)
		(width 0.12954)
		(layer "In2.Cu")
		(net "PWRGD_P52V_HS1_PG")
	)
	(segment
		(start 228.97846 -86.78926)
		(end 225.425 -90.34272)
		(width 0.12954)
		(layer "In2.Cu")
		(net "PWRGD_P52V_HS1_PG")
	)
	(segment
		(start 349.899224 -5.212588)
		(end 222.142812 -5.212588)
		(width 0.12954)
		(layer "In2.Cu")
		(net "PWRGD_P52V_HS1_PG")
	)
	(segment
		(start 257.4544 -78.232)
		(end 247.650254 -78.232)
		(width 0.12954)
		(layer "In2.Cu")
		(net "PWRGD_P52V_HS1_PG")
	)
	(segment
		(start 431.60188 -32.279844)
		(end 429.7934 -30.471364)
		(width 0.12954)
		(layer "In2.Cu")
		(net "PWRGD_P52V_HS1_PG")
	)
	(segment
		(start 410.906468 -7.44474)
		(end 403.17166 -7.44474)
		(width 0.12954)
		(layer "In2.Cu")
		(net "PWRGD_P52V_HS1_PG")
	)
	(segment
		(start 239.092994 -86.78926)
		(end 228.97846 -86.78926)
		(width 0.12954)
		(layer "In2.Cu")
		(net "PWRGD_P52V_HS1_PG")
	)
	(segment
		(start 266.207494 -63.350394)
		(end 262.974582 -66.583306)
		(width 0.12954)
		(layer "In2.Cu")
		(net "PWRGD_P52V_HS1_PG")
	)
	(segment
		(start 366.35436 -23.95347)
		(end 362.76788 -20.36699)
		(width 0.12954)
		(layer "In2.Cu")
		(net "PWRGD_P52V_HS1_PG")
	)
	(segment
		(start 429.768254 -52.07)
		(end 426.084746 -52.07)
		(width 0.12954)
		(layer "In2.Cu")
		(net "PWRGD_P52V_HS1_PG")
	)
	(segment
		(start 432.369214 -49.46904)
		(end 429.768254 -52.07)
		(width 0.12954)
		(layer "In2.Cu")
		(net "PWRGD_P52V_HS1_PG")
	)
	(segment
		(start 262.974582 -70.901306)
		(end 263.298178 -71.224902)
		(width 0.12954)
		(layer "In2.Cu")
		(net "PWRGD_P52V_HS1_PG")
	)
	(segment
		(start 429.7934 -26.331672)
		(end 410.906468 -7.44474)
		(width 0.12954)
		(layer "In2.Cu")
		(net "PWRGD_P52V_HS1_PG")
	)
	(segment
		(start 362.76788 -10.21588)
		(end 362.1532 -9.6012)
		(width 0.12954)
		(layer "In2.Cu")
		(net "PWRGD_P52V_HS1_PG")
	)
	(segment
		(start 437.2864 -49.46904)
		(end 432.369214 -49.46904)
		(width 0.12954)
		(layer "In2.Cu")
		(net "PWRGD_P52V_HS1_PG")
	)
	(segment
		(start 354.287836 -9.6012)
		(end 349.899224 -5.212588)
		(width 0.12954)
		(layer "In2.Cu")
		(net "PWRGD_P52V_HS1_PG")
	)
	(segment
		(start 362.1532 -9.6012)
		(end 354.287836 -9.6012)
		(width 0.12954)
		(layer "In2.Cu")
		(net "PWRGD_P52V_HS1_PG")
	)
	(segment
		(start 263.298178 -71.224902)
		(end 263.298178 -72.388222)
		(width 0.12954)
		(layer "In2.Cu")
		(net "PWRGD_P52V_HS1_PG")
	)
	(segment
		(start 403.17166 -7.44474)
		(end 394.9954 -15.621)
		(width 0.12954)
		(layer "In2.Cu")
		(net "PWRGD_P52V_HS1_PG")
	)
	(segment
		(start 362.76788 -20.36699)
		(end 362.76788 -10.21588)
		(width 0.12954)
		(layer "In2.Cu")
		(net "PWRGD_P52V_HS1_PG")
	)
	(segment
		(start 379.55093 -23.95347)
		(end 366.35436 -23.95347)
		(width 0.12954)
		(layer "In2.Cu")
		(net "PWRGD_P52V_HS1_PG")
	)
	(segment
		(start 426.084746 -52.07)
		(end 423.925746 -49.911)
		(width 0.12954)
		(layer "In2.Cu")
		(net "PWRGD_P52V_HS1_PG")
	)
	(segment
		(start 433.0954 -34.4424)
		(end 431.60188 -32.94888)
		(width 0.12954)
		(layer "In2.Cu")
		(net "PWRGD_P52V_HS1_PG")
	)
	(segment
		(start 222.142812 -5.212588)
		(end 220.2434 -7.112)
		(width 0.12954)
		(layer "In2.Cu")
		(net "PWRGD_P52V_HS1_PG")
	)
	(segment
		(start 271.91335 -61.722)
		(end 270.284956 -63.350394)
		(width 0.12954)
		(layer "In2.Cu")
		(net "PWRGD_P52V_HS1_PG")
	)
	(segment
		(start 247.650254 -78.232)
		(end 239.092994 -86.78926)
		(width 0.12954)
		(layer "In2.Cu")
		(net "PWRGD_P52V_HS1_PG")
	)
	(segment
		(start 413.004 -42.545)
		(end 412.369 -41.91)
		(width 0.17272)
		(layer "F.Cu")
		(net "PRSNT_FAN_BP0_R_N")
	)
	(segment
		(start 413.61995 -42.545)
		(end 413.004 -42.545)
		(width 0.17272)
		(layer "F.Cu")
		(net "PRSNT_FAN_BP0_R_N")
	)
	(segment
		(start 412.369 -41.91)
		(end 411.861 -41.91)
		(width 0.17272)
		(layer "F.Cu")
		(net "PRSNT_FAN_BP0_R_N")
	)
	(segment
		(start 411.861 -41.91)
		(end 411.49905 -41.91)
		(width 0.17272)
		(layer "F.Cu")
		(net "PRSNT_FAN_BP0_R_N")
	)
	(segment
		(start 411.49905 -41.91)
		(end 410.35605 -43.053)
		(width 0.17272)
		(layer "F.Cu")
		(net "PRSNT_FAN_BP0_R_N")
	)
	(via
		(at 411.861 -41.91)
		(size 0.762)
		(drill 0.381)
		(layers "F.Cu" "B.Cu")
		(net "PRSNT_FAN_BP0_R_N")
	)
	(via
		(at 430.657 -19.431)
		(size 0.508)
		(drill 0.254)
		(layers "F.Cu" "B.Cu")
		(net "PRSNT_FAN_BP0_R_N")
	)
	(via
		(at 432.054 -41.783)
		(size 0.508)
		(drill 0.254)
		(layers "F.Cu" "B.Cu")
		(net "PRSNT_FAN_BP0_R_N")
	)
	(via
		(at 413.004 -42.545)
		(size 0.508)
		(drill 0.254)
		(layers "F.Cu" "B.Cu")
		(net "PRSNT_FAN_BP0_R_N")
	)
	(segment
		(start 430.657 -23.622)
		(end 430.657 -19.431)
		(width 0.17272)
		(layer "B.Cu")
		(net "PRSNT_FAN_BP0_R_N")
	)
	(segment
		(start 432.55184 -41.28516)
		(end 432.55184 -35.44316)
		(width 0.17272)
		(layer "B.Cu")
		(net "PRSNT_FAN_BP0_R_N")
	)
	(segment
		(start 432.054 -41.783)
		(end 432.55184 -41.28516)
		(width 0.17272)
		(layer "B.Cu")
		(net "PRSNT_FAN_BP0_R_N")
	)
	(segment
		(start 434.213 -33.782)
		(end 434.213 -27.178)
		(width 0.17272)
		(layer "B.Cu")
		(net "PRSNT_FAN_BP0_R_N")
	)
	(segment
		(start 432.55184 -35.44316)
		(end 434.213 -33.782)
		(width 0.17272)
		(layer "B.Cu")
		(net "PRSNT_FAN_BP0_R_N")
	)
	(segment
		(start 434.213 -27.178)
		(end 430.657 -23.622)
		(width 0.17272)
		(layer "B.Cu")
		(net "PRSNT_FAN_BP0_R_N")
	)
	(segment
		(start 381.36068 -5.845048)
		(end 375.970038 -5.845048)
		(width 0.12954)
		(layer "In2.Cu")
		(net "PRSNT_FAN_BP0_R_N")
	)
	(segment
		(start 429.641 -42.672)
		(end 413.131 -42.672)
		(width 0.12954)
		(layer "In2.Cu")
		(net "PRSNT_FAN_BP0_R_N")
	)
	(segment
		(start 430.08804 -18.86204)
		(end 428.99584 -18.86204)
		(width 0.12954)
		(layer "In2.Cu")
		(net "PRSNT_FAN_BP0_R_N")
	)
	(segment
		(start 413.131 -42.672)
		(end 413.004 -42.545)
		(width 0.12954)
		(layer "In2.Cu")
		(net "PRSNT_FAN_BP0_R_N")
	)
	(segment
		(start 431.038 -41.275)
		(end 429.641 -42.672)
		(width 0.12954)
		(layer "In2.Cu")
		(net "PRSNT_FAN_BP0_R_N")
	)
	(segment
		(start 412.73984 -2.60604)
		(end 384.599688 -2.60604)
		(width 0.12954)
		(layer "In2.Cu")
		(net "PRSNT_FAN_BP0_R_N")
	)
	(segment
		(start 428.99584 -18.86204)
		(end 412.73984 -2.60604)
		(width 0.12954)
		(layer "In2.Cu")
		(net "PRSNT_FAN_BP0_R_N")
	)
	(segment
		(start 430.657 -19.431)
		(end 430.08804 -18.86204)
		(width 0.12954)
		(layer "In2.Cu")
		(net "PRSNT_FAN_BP0_R_N")
	)
	(segment
		(start 431.546 -41.275)
		(end 431.038 -41.275)
		(width 0.12954)
		(layer "In2.Cu")
		(net "PRSNT_FAN_BP0_R_N")
	)
	(segment
		(start 432.054 -41.783)
		(end 431.546 -41.275)
		(width 0.12954)
		(layer "In2.Cu")
		(net "PRSNT_FAN_BP0_R_N")
	)
	(segment
		(start 384.599688 -2.60604)
		(end 381.36068 -5.845048)
		(width 0.12954)
		(layer "In2.Cu")
		(net "PRSNT_FAN_BP0_R_N")
	)
	(segment
		(start 413.61995 -41.529)
		(end 413.004 -41.529)
		(width 0.17272)
		(layer "F.Cu")
		(net "PRSNT_FAN_BP1_R_N")
	)
	(segment
		(start 411.861 -40.386)
		(end 413.004 -41.529)
		(width 0.17272)
		(layer "F.Cu")
		(net "PRSNT_FAN_BP1_R_N")
	)
	(segment
		(start 410.35605 -42.037)
		(end 410.35605 -41.89095)
		(width 0.17272)
		(layer "F.Cu")
		(net "PRSNT_FAN_BP1_R_N")
	)
	(segment
		(start 410.35605 -41.89095)
		(end 411.861 -40.386)
		(width 0.17272)
		(layer "F.Cu")
		(net "PRSNT_FAN_BP1_R_N")
	)
	(via
		(at 429.768 -19.44878)
		(size 0.508)
		(drill 0.254)
		(layers "F.Cu" "B.Cu")
		(net "PRSNT_FAN_BP1_R_N")
	)
	(via
		(at 413.004 -41.529)
		(size 0.508)
		(drill 0.254)
		(layers "F.Cu" "B.Cu")
		(net "PRSNT_FAN_BP1_R_N")
	)
	(via
		(at 432.054 -40.386)
		(size 0.508)
		(drill 0.254)
		(layers "F.Cu" "B.Cu")
		(net "PRSNT_FAN_BP1_R_N")
	)
	(via
		(at 411.861 -40.386)
		(size 0.762)
		(drill 0.381)
		(layers "F.Cu" "B.Cu")
		(net "PRSNT_FAN_BP1_R_N")
	)
	(segment
		(start 429.768 -19.44878)
		(end 429.768 -23.9903)
		(width 0.17272)
		(layer "B.Cu")
		(net "PRSNT_FAN_BP1_R_N")
	)
	(segment
		(start 432.054 -35.265614)
		(end 432.054 -40.386)
		(width 0.17272)
		(layer "B.Cu")
		(net "PRSNT_FAN_BP1_R_N")
	)
	(segment
		(start 429.768 -23.9903)
		(end 433.705 -27.9273)
		(width 0.17272)
		(layer "B.Cu")
		(net "PRSNT_FAN_BP1_R_N")
	)
	(segment
		(start 433.705 -27.9273)
		(end 433.705 -33.614614)
		(width 0.17272)
		(layer "B.Cu")
		(net "PRSNT_FAN_BP1_R_N")
	)
	(segment
		(start 433.705 -33.614614)
		(end 432.054 -35.265614)
		(width 0.17272)
		(layer "B.Cu")
		(net "PRSNT_FAN_BP1_R_N")
	)
	(segment
		(start 431.165 -39.497)
		(end 427.736 -39.497)
		(width 0.12954)
		(layer "In2.Cu")
		(net "PRSNT_FAN_BP1_R_N")
	)
	(segment
		(start 413.512 -42.037)
		(end 413.004 -41.529)
		(width 0.12954)
		(layer "In2.Cu")
		(net "PRSNT_FAN_BP1_R_N")
	)
	(segment
		(start 381.413766 -6.62178)
		(end 384.842766 -3.19278)
		(width 0.12954)
		(layer "In2.Cu")
		(net "PRSNT_FAN_BP1_R_N")
	)
	(segment
		(start 425.196 -42.037)
		(end 413.512 -42.037)
		(width 0.12954)
		(layer "In2.Cu")
		(net "PRSNT_FAN_BP1_R_N")
	)
	(segment
		(start 384.842766 -3.19278)
		(end 412.496762 -3.19278)
		(width 0.12954)
		(layer "In2.Cu")
		(net "PRSNT_FAN_BP1_R_N")
	)
	(segment
		(start 428.752762 -19.44878)
		(end 429.768 -19.44878)
		(width 0.12954)
		(layer "In2.Cu")
		(net "PRSNT_FAN_BP1_R_N")
	)
	(segment
		(start 73.570084 -5.845048)
		(end 73.570084 -6.104128)
		(width 0.12954)
		(layer "In2.Cu")
		(net "PRSNT_FAN_BP1_R_N")
	)
	(segment
		(start 104.320086 -2.27457)
		(end 358.916224 -2.27457)
		(width 0.12954)
		(layer "In2.Cu")
		(net "PRSNT_FAN_BP1_R_N")
	)
	(segment
		(start 412.496762 -3.19278)
		(end 428.752762 -19.44878)
		(width 0.12954)
		(layer "In2.Cu")
		(net "PRSNT_FAN_BP1_R_N")
	)
	(segment
		(start 432.054 -40.386)
		(end 431.165 -39.497)
		(width 0.12954)
		(layer "In2.Cu")
		(net "PRSNT_FAN_BP1_R_N")
	)
	(segment
		(start 83.2358 -16.2052)
		(end 83.947254 -16.916654)
		(width 0.12954)
		(layer "In2.Cu")
		(net "PRSNT_FAN_BP1_R_N")
	)
	(segment
		(start 73.570084 -6.104128)
		(end 83.2358 -15.769844)
		(width 0.12954)
		(layer "In2.Cu")
		(net "PRSNT_FAN_BP1_R_N")
	)
	(segment
		(start 363.263434 -6.62178)
		(end 381.413766 -6.62178)
		(width 0.12954)
		(layer "In2.Cu")
		(net "PRSNT_FAN_BP1_R_N")
	)
	(segment
		(start 89.678002 -16.916654)
		(end 104.320086 -2.27457)
		(width 0.12954)
		(layer "In2.Cu")
		(net "PRSNT_FAN_BP1_R_N")
	)
	(segment
		(start 427.736 -39.497)
		(end 425.196 -42.037)
		(width 0.12954)
		(layer "In2.Cu")
		(net "PRSNT_FAN_BP1_R_N")
	)
	(segment
		(start 83.2358 -15.769844)
		(end 83.2358 -16.2052)
		(width 0.12954)
		(layer "In2.Cu")
		(net "PRSNT_FAN_BP1_R_N")
	)
	(segment
		(start 358.916224 -2.27457)
		(end 363.263434 -6.62178)
		(width 0.12954)
		(layer "In2.Cu")
		(net "PRSNT_FAN_BP1_R_N")
	)
	(segment
		(start 83.947254 -16.916654)
		(end 89.678002 -16.916654)
		(width 0.12954)
		(layer "In2.Cu")
		(net "PRSNT_FAN_BP1_R_N")
	)
	(segment
		(start 411.72384 -28.252928)
		(end 412.73476 -28.252928)
		(width 0.17272)
		(layer "F.Cu")
		(net "P12V_LED_FB")
	)
	(segment
		(start 412.73476 -28.252928)
		(end 413.75584 -28.252928)
		(width 0.17272)
		(layer "F.Cu")
		(net "P12V_LED_FB")
	)
	(segment
		(start 413.75584 -28.252928)
		(end 414.076134 -28.252928)
		(width 0.17272)
		(layer "F.Cu")
		(net "P12V_LED_FB")
	)
	(segment
		(start 414.613344 -28.10383)
		(end 414.762442 -28.252928)
		(width 0.17272)
		(layer "F.Cu")
		(net "P12V_LED_FB")
	)
	(segment
		(start 414.762442 -28.252928)
		(end 415.150554 -28.252928)
		(width 0.17272)
		(layer "F.Cu")
		(net "P12V_LED_FB")
	)
	(segment
		(start 414.076134 -28.252928)
		(end 414.613344 -27.715718)
		(width 0.17272)
		(layer "F.Cu")
		(net "P12V_LED_FB")
	)
	(segment
		(start 414.613344 -27.715718)
		(end 414.613344 -28.10383)
		(width 0.17272)
		(layer "F.Cu")
		(net "P12V_LED_FB")
	)
	(via
		(at 414.613344 -27.715718)
		(size 0.508)
		(drill 0.254)
		(layers "F.Cu" "B.Cu")
		(net "P12V_LED_FB")
	)
	(segment
		(start 414.249362 -23.09876)
		(end 414.153858 -23.003256)
		(width 0.12954)
		(layer "F.Cu")
		(net "P12V_LED_PD")
	)
	(segment
		(start 415.33953 -23.09876)
		(end 414.249362 -23.09876)
		(width 0.12954)
		(layer "F.Cu")
		(net "P12V_LED_PD")
	)
	(via
		(at 414.153858 -23.003256)
		(size 0.762)
		(drill 0.381)
		(layers "F.Cu" "B.Cu")
		(net "P12V_LED_PD")
	)
	(segment
		(start 414.46958 -32.35071)
		(end 413.45358 -32.35071)
		(width 0.254)
		(layer "F.Cu")
		(net "P12V_LED_IMON")
	)
	(segment
		(start 416.050476 -30.769814)
		(end 414.46958 -32.35071)
		(width 0.254)
		(layer "F.Cu")
		(net "P12V_LED_IMON")
	)
	(segment
		(start 413.45358 -32.35071)
		(end 412.086552 -32.35071)
		(width 0.254)
		(layer "F.Cu")
		(net "P12V_LED_IMON")
	)
	(segment
		(start 416.050476 -30.152848)
		(end 416.050476 -30.769814)
		(width 0.254)
		(layer "F.Cu")
		(net "P12V_LED_IMON")
	)
	(via
		(at 412.086552 -32.35071)
		(size 0.762)
		(drill 0.381)
		(layers "F.Cu" "B.Cu")
		(net "P12V_LED_IMON")
	)
	(segment
		(start 413.245554 -31.0134)
		(end 411.429962 -31.0134)
		(width 0.17272)
		(layer "F.Cu")
		(net "P12V_LED_FLTB")
	)
	(segment
		(start 411.429962 -31.0134)
		(end 411.016958 -30.600396)
		(width 0.17272)
		(layer "F.Cu")
		(net "P12V_LED_FLTB")
	)
	(segment
		(start 413.47263 -30.786324)
		(end 413.245554 -31.0134)
		(width 0.17272)
		(layer "F.Cu")
		(net "P12V_LED_FLTB")
	)
	(segment
		(start 413.47263 -30.26156)
		(end 413.47263 -30.786324)
		(width 0.17272)
		(layer "F.Cu")
		(net "P12V_LED_FLTB")
	)
	(via
		(at 411.016958 -30.600396)
		(size 0.762)
		(drill 0.381)
		(layers "F.Cu" "B.Cu")
		(net "P12V_LED_FLTB")
	)
	(segment
		(start 417.050728 -30.152848)
		(end 417.050728 -31.234126)
		(width 0.17272)
		(layer "F.Cu")
		(net "P12V_LED_SS")
	)
	(segment
		(start 416.24758 -32.35071)
		(end 417.050728 -31.547562)
		(width 0.17272)
		(layer "F.Cu")
		(net "P12V_LED_SS")
	)
	(segment
		(start 417.050728 -31.547562)
		(end 417.050728 -31.234126)
		(width 0.17272)
		(layer "F.Cu")
		(net "P12V_LED_SS")
	)
	(via
		(at 417.050728 -31.234126)
		(size 0.508)
		(drill 0.254)
		(layers "F.Cu" "B.Cu")
		(net "P12V_LED_SS")
	)
	(segment
		(start 417.808918 -32.273748)
		(end 417.808918 -31.643574)
		(width 0.17272)
		(layer "F.Cu")
		(net "P12V_LED_ISET")
	)
	(segment
		(start 417.5506 -31.385256)
		(end 417.5506 -30.152848)
		(width 0.17272)
		(layer "F.Cu")
		(net "P12V_LED_ISET")
	)
	(segment
		(start 417.90112 -32.36595)
		(end 417.808918 -32.273748)
		(width 0.17272)
		(layer "F.Cu")
		(net "P12V_LED_ISET")
	)
	(segment
		(start 417.808918 -31.643574)
		(end 417.5506 -31.385256)
		(width 0.17272)
		(layer "F.Cu")
		(net "P12V_LED_ISET")
	)
	(via
		(at 415.6456 -32.366966)
		(size 0.6604)
		(drill 0.3302)
		(layers "F.Cu" "B.Cu")
		(net "P12V_LED_ISET")
	)
	(via
		(at 417.808918 -31.643574)
		(size 0.508)
		(drill 0.254)
		(layers "F.Cu" "B.Cu")
		(net "P12V_LED_ISET")
	)
	(segment
		(start 417.600892 -31.8516)
		(end 416.160966 -31.8516)
		(width 0.17272)
		(layer "B.Cu")
		(net "P12V_LED_ISET")
	)
	(segment
		(start 416.160966 -31.8516)
		(end 415.6456 -32.366966)
		(width 0.17272)
		(layer "B.Cu")
		(net "P12V_LED_ISET")
	)
	(segment
		(start 416.833558 -32.366966)
		(end 415.6456 -32.366966)
		(width 0.17272)
		(layer "B.Cu")
		(net "P12V_LED_ISET")
	)
	(segment
		(start 417.808918 -31.643574)
		(end 417.600892 -31.8516)
		(width 0.17272)
		(layer "B.Cu")
		(net "P12V_LED_ISET")
	)
	(segment
		(start 419.165532 -31.498286)
		(end 419.43655 -31.769304)
		(width 0.17272)
		(layer "F.Cu")
		(net "P12V_LED_TIMER")
	)
	(segment
		(start 419.213284 -32.35071)
		(end 419.43655 -32.127444)
		(width 0.17272)
		(layer "F.Cu")
		(net "P12V_LED_TIMER")
	)
	(segment
		(start 418.91458 -32.35071)
		(end 419.213284 -32.35071)
		(width 0.17272)
		(layer "F.Cu")
		(net "P12V_LED_TIMER")
	)
	(segment
		(start 419.43655 -32.127444)
		(end 419.43655 -31.769304)
		(width 0.17272)
		(layer "F.Cu")
		(net "P12V_LED_TIMER")
	)
	(segment
		(start 418.364162 -31.498286)
		(end 419.165532 -31.498286)
		(width 0.17272)
		(layer "F.Cu")
		(net "P12V_LED_TIMER")
	)
	(segment
		(start 418.050472 -30.152848)
		(end 418.050472 -31.184596)
		(width 0.17272)
		(layer "F.Cu")
		(net "P12V_LED_TIMER")
	)
	(segment
		(start 418.050472 -31.184596)
		(end 418.364162 -31.498286)
		(width 0.17272)
		(layer "F.Cu")
		(net "P12V_LED_TIMER")
	)
	(via
		(at 419.43655 -31.769304)
		(size 0.508)
		(drill 0.254)
		(layers "F.Cu" "B.Cu")
		(net "P12V_LED_TIMER")
	)
	(segment
		(start 420.12362 -31.071566)
		(end 420.12362 -32.010858)
		(width 0.17272)
		(layer "F.Cu")
		(net "P12V_LED_EN_R")
	)
	(segment
		(start 419.550596 -30.498542)
		(end 420.12362 -31.071566)
		(width 0.17272)
		(layer "F.Cu")
		(net "P12V_LED_EN_R")
	)
	(segment
		(start 420.12362 -32.010858)
		(end 419.93058 -32.203898)
		(width 0.17272)
		(layer "F.Cu")
		(net "P12V_LED_EN_R")
	)
	(segment
		(start 420.790878 -32.35071)
		(end 419.93058 -32.35071)
		(width 0.17272)
		(layer "F.Cu")
		(net "P12V_LED_EN_R")
	)
	(segment
		(start 419.550596 -30.127702)
		(end 419.550596 -30.498542)
		(width 0.17272)
		(layer "F.Cu")
		(net "P12V_LED_EN_R")
	)
	(segment
		(start 419.93058 -32.203898)
		(end 419.93058 -32.35071)
		(width 0.17272)
		(layer "F.Cu")
		(net "P12V_LED_EN_R")
	)
	(via
		(at 420.790878 -32.35071)
		(size 0.508)
		(drill 0.254)
		(layers "F.Cu" "B.Cu")
		(net "P12V_LED_EN_R")
	)
	(via
		(at 279.7048 -90.3224)
		(size 0.6604)
		(drill 0.3302)
		(layers "F.Cu" "B.Cu")
		(net "FM_HS1_EN_BUSBAR")
	)
	(via
		(at 292.989 -86.995)
		(size 0.508)
		(drill 0.254)
		(layers "F.Cu" "B.Cu")
		(net "FM_HS1_EN_BUSBAR")
	)
	(via
		(at 278.003 -90.3224)
		(size 0.508)
		(drill 0.254)
		(layers "F.Cu" "B.Cu")
		(net "FM_HS1_EN_BUSBAR")
	)
	(segment
		(start 292.989 -86.995)
		(end 292.481 -86.487)
		(width 0.17272)
		(layer "B.Cu")
		(net "FM_HS1_EN_BUSBAR")
	)
	(segment
		(start 278.003 -90.3224)
		(end 279.7048 -90.3224)
		(width 0.17272)
		(layer "B.Cu")
		(net "FM_HS1_EN_BUSBAR")
	)
	(segment
		(start 276.7584 -91.567)
		(end 278.003 -90.3224)
		(width 0.17272)
		(layer "B.Cu")
		(net "FM_HS1_EN_BUSBAR")
	)
	(segment
		(start 292.481 -86.487)
		(end 292.16604 -86.487)
		(width 0.17272)
		(layer "B.Cu")
		(net "FM_HS1_EN_BUSBAR")
	)
	(segment
		(start 281.178 -90.3224)
		(end 281.73045 -90.3224)
		(width 0.17272)
		(layer "B.Cu")
		(net "FM_HS1_EN_BUSBAR")
	)
	(segment
		(start 279.7048 -90.3224)
		(end 281.178 -90.3224)
		(width 0.17272)
		(layer "B.Cu")
		(net "FM_HS1_EN_BUSBAR")
	)
	(segment
		(start 282.575 -91.16695)
		(end 283.229304 -91.16695)
		(width 0.17272)
		(layer "B.Cu")
		(net "FM_HS1_EN_BUSBAR")
	)
	(segment
		(start 274.76196 -91.567)
		(end 276.7584 -91.567)
		(width 0.17272)
		(layer "B.Cu")
		(net "FM_HS1_EN_BUSBAR")
	)
	(segment
		(start 283.271214 -91.12504)
		(end 284.169104 -91.12504)
		(width 0.17272)
		(layer "B.Cu")
		(net "FM_HS1_EN_BUSBAR")
	)
	(segment
		(start 281.73045 -90.3224)
		(end 282.575 -91.16695)
		(width 0.17272)
		(layer "B.Cu")
		(net "FM_HS1_EN_BUSBAR")
	)
	(segment
		(start 283.229304 -91.16695)
		(end 283.271214 -91.12504)
		(width 0.17272)
		(layer "B.Cu")
		(net "FM_HS1_EN_BUSBAR")
	)
	(segment
		(start 291.073078 -87.55126)
		(end 290.493958 -86.97214)
		(width 0.12954)
		(layer "In2.Cu")
		(net "FM_HS1_EN_BUSBAR")
	)
	(segment
		(start 281.35326 -86.97214)
		(end 278.003 -90.3224)
		(width 0.12954)
		(layer "In2.Cu")
		(net "FM_HS1_EN_BUSBAR")
	)
	(segment
		(start 290.493958 -86.97214)
		(end 281.35326 -86.97214)
		(width 0.12954)
		(layer "In2.Cu")
		(net "FM_HS1_EN_BUSBAR")
	)
	(segment
		(start 292.43274 -87.55126)
		(end 291.073078 -87.55126)
		(width 0.12954)
		(layer "In2.Cu")
		(net "FM_HS1_EN_BUSBAR")
	)
	(segment
		(start 292.989 -86.995)
		(end 292.43274 -87.55126)
		(width 0.12954)
		(layer "In2.Cu")
		(net "FM_HS1_EN_BUSBAR")
	)
	(via
		(at 287.782 -89.72296)
		(size 0.6604)
		(drill 0.3302)
		(layers "F.Cu" "B.Cu")
		(net "P3V3_AND")
	)
	(segment
		(start 287.782 -89.72296)
		(end 289.306 -91.24696)
		(width 0.4572)
		(layer "B.Cu")
		(net "P3V3_AND")
	)
	(segment
		(start 288.29 -91.67495)
		(end 287.762696 -91.67495)
		(width 0.4572)
		(layer "B.Cu")
		(net "P3V3_AND")
	)
	(segment
		(start 287.212786 -91.12504)
		(end 286.568896 -91.12504)
		(width 0.4572)
		(layer "B.Cu")
		(net "P3V3_AND")
	)
	(segment
		(start 287.762696 -91.67495)
		(end 287.212786 -91.12504)
		(width 0.4572)
		(layer "B.Cu")
		(net "P3V3_AND")
	)
	(segment
		(start 282.702 -89.72296)
		(end 287.782 -89.72296)
		(width 0.4572)
		(layer "B.Cu")
		(net "P3V3_AND")
	)
	(segment
		(start 289.306 -91.24696)
		(end 289.306 -91.67495)
		(width 0.4572)
		(layer "B.Cu")
		(net "P3V3_AND")
	)
	(segment
		(start 289.306 -91.67495)
		(end 288.29 -91.67495)
		(width 0.4572)
		(layer "B.Cu")
		(net "P3V3_AND")
	)
	(segment
		(start 263.474454 -58.871104)
		(end 260.22935 -55.626)
		(width 0.17272)
		(layer "F.Cu")
		(net "FM_HS1_EN_FUSE")
	)
	(segment
		(start 258.627118 -64.628776)
		(end 263.474454 -59.78144)
		(width 0.17272)
		(layer "F.Cu")
		(net "FM_HS1_EN_FUSE")
	)
	(segment
		(start 285.3436 -89.7636)
		(end 279.81148 -84.23148)
		(width 0.17272)
		(layer "F.Cu")
		(net "FM_HS1_EN_FUSE")
	)
	(segment
		(start 263.474454 -59.78144)
		(end 263.474454 -58.871104)
		(width 0.17272)
		(layer "F.Cu")
		(net "FM_HS1_EN_FUSE")
	)
	(segment
		(start 262.72998 -76.507594)
		(end 259.973318 -76.507594)
		(width 0.17272)
		(layer "F.Cu")
		(net "FM_HS1_EN_FUSE")
	)
	(segment
		(start 279.81148 -84.23148)
		(end 270.453866 -84.23148)
		(width 0.17272)
		(layer "F.Cu")
		(net "FM_HS1_EN_FUSE")
	)
	(segment
		(start 285.3436 -90.5002)
		(end 285.3436 -89.7636)
		(width 0.17272)
		(layer "F.Cu")
		(net "FM_HS1_EN_FUSE")
	)
	(segment
		(start 260.22935 -55.626)
		(end 260.22935 -54.61)
		(width 0.17272)
		(layer "F.Cu")
		(net "FM_HS1_EN_FUSE")
	)
	(segment
		(start 259.973318 -76.507594)
		(end 258.627118 -75.161394)
		(width 0.17272)
		(layer "F.Cu")
		(net "FM_HS1_EN_FUSE")
	)
	(segment
		(start 258.627118 -75.161394)
		(end 258.627118 -64.628776)
		(width 0.17272)
		(layer "F.Cu")
		(net "FM_HS1_EN_FUSE")
	)
	(segment
		(start 270.453866 -84.23148)
		(end 262.72998 -76.507594)
		(width 0.17272)
		(layer "F.Cu")
		(net "FM_HS1_EN_FUSE")
	)
	(via
		(at 260.22935 -54.61)
		(size 0.508)
		(drill 0.254)
		(layers "F.Cu" "B.Cu")
		(net "FM_HS1_EN_FUSE")
	)
	(via
		(at 285.3436 -90.5002)
		(size 0.762)
		(drill 0.254)
		(layers "F.Cu" "B.Cu")
		(net "FM_HS1_EN_FUSE")
	)
	(via
		(at 299.4406 -91.34348)
		(size 0.508)
		(drill 0.254)
		(layers "F.Cu" "B.Cu")
		(net "FM_HS1_EN_FUSE")
	)
	(segment
		(start 259.8928 -51.689)
		(end 259.8928 -52.62245)
		(width 0.17272)
		(layer "B.Cu")
		(net "FM_HS1_EN_FUSE")
	)
	(segment
		(start 299.4406 -91.34348)
		(end 299.4406 -91.8972)
		(width 0.17272)
		(layer "B.Cu")
		(net "FM_HS1_EN_FUSE")
	)
	(segment
		(start 259.8928 -52.62245)
		(end 260.22935 -52.959)
		(width 0.17272)
		(layer "B.Cu")
		(net "FM_HS1_EN_FUSE")
	)
	(segment
		(start 284.169104 -92.075)
		(end 285.0134 -92.075)
		(width 0.17272)
		(layer "B.Cu")
		(net "FM_HS1_EN_FUSE")
	)
	(segment
		(start 298.069 -93.2688)
		(end 298.069 -93.65996)
		(width 0.17272)
		(layer "B.Cu")
		(net "FM_HS1_EN_FUSE")
	)
	(segment
		(start 299.4406 -91.8972)
		(end 298.069 -93.2688)
		(width 0.17272)
		(layer "B.Cu")
		(net "FM_HS1_EN_FUSE")
	)
	(segment
		(start 285.0134 -92.075)
		(end 285.3436 -91.7448)
		(width 0.17272)
		(layer "B.Cu")
		(net "FM_HS1_EN_FUSE")
	)
	(segment
		(start 260.22935 -52.959)
		(end 260.22935 -53.975)
		(width 0.17272)
		(layer "B.Cu")
		(net "FM_HS1_EN_FUSE")
	)
	(segment
		(start 260.2484 -50.09896)
		(end 260.2484 -51.3334)
		(width 0.17272)
		(layer "B.Cu")
		(net "FM_HS1_EN_FUSE")
	)
	(segment
		(start 260.22935 -53.975)
		(end 260.22935 -54.61)
		(width 0.17272)
		(layer "B.Cu")
		(net "FM_HS1_EN_FUSE")
	)
	(segment
		(start 260.2484 -51.3334)
		(end 259.8928 -51.689)
		(width 0.17272)
		(layer "B.Cu")
		(net "FM_HS1_EN_FUSE")
	)
	(segment
		(start 285.3436 -91.7448)
		(end 285.3436 -90.5002)
		(width 0.17272)
		(layer "B.Cu")
		(net "FM_HS1_EN_FUSE")
	)
	(segment
		(start 294.767 -90.5002)
		(end 285.3436 -90.5002)
		(width 0.12954)
		(layer "In2.Cu")
		(net "FM_HS1_EN_FUSE")
	)
	(segment
		(start 299.4406 -91.34348)
		(end 295.61028 -91.34348)
		(width 0.12954)
		(layer "In2.Cu")
		(net "FM_HS1_EN_FUSE")
	)
	(segment
		(start 295.61028 -91.34348)
		(end 294.767 -90.5002)
		(width 0.12954)
		(layer "In2.Cu")
		(net "FM_HS1_EN_FUSE")
	)
	(segment
		(start 184.202578 -63.090044)
		(end 180.848 -59.735466)
		(width 0.17272)
		(layer "F.Cu")
		(net "FM_HS2_EN_FUSE")
	)
	(segment
		(start 183.862218 -78.735936)
		(end 184.839356 -78.735936)
		(width 0.17272)
		(layer "F.Cu")
		(net "FM_HS2_EN_FUSE")
	)
	(segment
		(start 186.951112 -79.603854)
		(end 187.823856 -78.73111)
		(width 0.17272)
		(layer "F.Cu")
		(net "FM_HS2_EN_FUSE")
	)
	(segment
		(start 180.848 -59.735466)
		(end 180.848 -54.737)
		(width 0.17272)
		(layer "F.Cu")
		(net "FM_HS2_EN_FUSE")
	)
	(segment
		(start 181.36743 -83.029044)
		(end 180.229764 -83.029044)
		(width 0.17272)
		(layer "F.Cu")
		(net "FM_HS2_EN_FUSE")
	)
	(segment
		(start 186.173364 -63.090044)
		(end 184.202578 -63.090044)
		(width 0.17272)
		(layer "F.Cu")
		(net "FM_HS2_EN_FUSE")
	)
	(segment
		(start 184.839356 -78.735936)
		(end 185.707274 -79.603854)
		(width 0.17272)
		(layer "F.Cu")
		(net "FM_HS2_EN_FUSE")
	)
	(segment
		(start 180.229764 -83.029044)
		(end 178.35372 -81.153)
		(width 0.17272)
		(layer "F.Cu")
		(net "FM_HS2_EN_FUSE")
	)
	(segment
		(start 185.707274 -79.603854)
		(end 186.951112 -79.603854)
		(width 0.17272)
		(layer "F.Cu")
		(net "FM_HS2_EN_FUSE")
	)
	(segment
		(start 183.642 -78.956154)
		(end 183.862218 -78.735936)
		(width 0.17272)
		(layer "F.Cu")
		(net "FM_HS2_EN_FUSE")
	)
	(segment
		(start 187.823856 -64.740536)
		(end 186.173364 -63.090044)
		(width 0.17272)
		(layer "F.Cu")
		(net "FM_HS2_EN_FUSE")
	)
	(segment
		(start 178.35372 -81.153)
		(end 171.266104 -81.153)
		(width 0.17272)
		(layer "F.Cu")
		(net "FM_HS2_EN_FUSE")
	)
	(segment
		(start 183.642 -79.43596)
		(end 183.642 -78.956154)
		(width 0.17272)
		(layer "F.Cu")
		(net "FM_HS2_EN_FUSE")
	)
	(segment
		(start 183.642 -79.43596)
		(end 183.642 -80.754474)
		(width 0.17272)
		(layer "F.Cu")
		(net "FM_HS2_EN_FUSE")
	)
	(segment
		(start 183.642 -80.754474)
		(end 181.36743 -83.029044)
		(width 0.17272)
		(layer "F.Cu")
		(net "FM_HS2_EN_FUSE")
	)
	(segment
		(start 187.823856 -78.73111)
		(end 187.823856 -64.740536)
		(width 0.17272)
		(layer "F.Cu")
		(net "FM_HS2_EN_FUSE")
	)
	(via
		(at 180.848 -54.737)
		(size 0.508)
		(drill 0.254)
		(layers "F.Cu" "B.Cu")
		(net "FM_HS2_EN_FUSE")
	)
	(via
		(at 181.36743 -83.029044)
		(size 0.762)
		(drill 0.381)
		(layers "F.Cu" "B.Cu")
		(net "FM_HS2_EN_FUSE")
	)
	(segment
		(start 179.9844 -51.2064)
		(end 180.34 -51.562)
		(width 0.17272)
		(layer "B.Cu")
		(net "FM_HS2_EN_FUSE")
	)
	(segment
		(start 180.48605 -52.832)
		(end 180.48605 -53.848)
		(width 0.17272)
		(layer "B.Cu")
		(net "FM_HS2_EN_FUSE")
	)
	(segment
		(start 179.9844 -49.97196)
		(end 179.9844 -51.2064)
		(width 0.17272)
		(layer "B.Cu")
		(net "FM_HS2_EN_FUSE")
	)
	(segment
		(start 180.48605 -53.848)
		(end 180.48605 -54.37505)
		(width 0.17272)
		(layer "B.Cu")
		(net "FM_HS2_EN_FUSE")
	)
	(segment
		(start 180.34 -52.246022)
		(end 180.34 -51.562)
		(width 0.17272)
		(layer "B.Cu")
		(net "FM_HS2_EN_FUSE")
	)
	(segment
		(start 180.48605 -54.37505)
		(end 180.848 -54.737)
		(width 0.17272)
		(layer "B.Cu")
		(net "FM_HS2_EN_FUSE")
	)
	(segment
		(start 180.48605 -52.392072)
		(end 180.34 -52.246022)
		(width 0.17272)
		(layer "B.Cu")
		(net "FM_HS2_EN_FUSE")
	)
	(segment
		(start 180.48605 -52.832)
		(end 180.48605 -52.392072)
		(width 0.17272)
		(layer "B.Cu")
		(net "FM_HS2_EN_FUSE")
	)
	(segment
		(start 168.82745 -80.66405)
		(end 168.529 -80.66405)
		(width 0.17272)
		(layer "F.Cu")
		(net "FM_HS2_EN_BUSBAR")
	)
	(segment
		(start 170.26636 -82.10296)
		(end 169.672 -81.5086)
		(width 0.17272)
		(layer "F.Cu")
		(net "FM_HS2_EN_BUSBAR")
	)
	(segment
		(start 171.266104 -82.10296)
		(end 170.26636 -82.10296)
		(width 0.17272)
		(layer "F.Cu")
		(net "FM_HS2_EN_BUSBAR")
	)
	(segment
		(start 166.35095 -78.486)
		(end 168.529 -80.66405)
		(width 0.17272)
		(layer "F.Cu")
		(net "FM_HS2_EN_BUSBAR")
	)
	(segment
		(start 160.274 -78.994)
		(end 160.274 -79.69504)
		(width 0.17272)
		(layer "F.Cu")
		(net "FM_HS2_EN_BUSBAR")
	)
	(segment
		(start 163.89604 -79.69504)
		(end 164.211 -80.01)
		(width 0.17272)
		(layer "F.Cu")
		(net "FM_HS2_EN_BUSBAR")
	)
	(segment
		(start 160.909 -78.359)
		(end 160.274 -78.994)
		(width 0.17272)
		(layer "F.Cu")
		(net "FM_HS2_EN_BUSBAR")
	)
	(segment
		(start 164.973 -78.359)
		(end 160.909 -78.359)
		(width 0.17272)
		(layer "F.Cu")
		(net "FM_HS2_EN_BUSBAR")
	)
	(segment
		(start 165.1 -78.486)
		(end 166.35095 -78.486)
		(width 0.17272)
		(layer "F.Cu")
		(net "FM_HS2_EN_BUSBAR")
	)
	(segment
		(start 169.672 -81.5086)
		(end 168.82745 -80.66405)
		(width 0.17272)
		(layer "F.Cu")
		(net "FM_HS2_EN_BUSBAR")
	)
	(segment
		(start 164.211 -80.01)
		(end 164.211 -80.58404)
		(width 0.17272)
		(layer "F.Cu")
		(net "FM_HS2_EN_BUSBAR")
	)
	(segment
		(start 164.973 -78.359)
		(end 165.1 -78.486)
		(width 0.17272)
		(layer "F.Cu")
		(net "FM_HS2_EN_BUSBAR")
	)
	(segment
		(start 160.274 -79.69504)
		(end 163.89604 -79.69504)
		(width 0.17272)
		(layer "F.Cu")
		(net "FM_HS2_EN_BUSBAR")
	)
	(via
		(at 164.973 -78.359)
		(size 0.762)
		(drill 0.381)
		(layers "F.Cu" "B.Cu")
		(net "FM_HS2_EN_BUSBAR")
	)
	(segment
		(start 172.847 -84.30895)
		(end 172.847 -83.414616)
		(width 0.4572)
		(layer "F.Cu")
		(net "P3V3_2_AND")
	)
	(segment
		(start 173.665896 -82.59572)
		(end 173.665896 -82.10296)
		(width 0.4572)
		(layer "F.Cu")
		(net "P3V3_2_AND")
	)
	(segment
		(start 170.173904 -84.569046)
		(end 170.173904 -87.810594)
		(width 0.4572)
		(layer "F.Cu")
		(net "P3V3_2_AND")
	)
	(segment
		(start 157.479746 -83.693)
		(end 154.87396 -83.693)
		(width 0.4572)
		(layer "F.Cu")
		(net "P3V3_2_AND")
	)
	(segment
		(start 159.512 -89.775792)
		(end 158.129732 -88.393524)
		(width 0.4572)
		(layer "F.Cu")
		(net "P3V3_2_AND")
	)
	(segment
		(start 158.129732 -84.342986)
		(end 157.479746 -83.693)
		(width 0.4572)
		(layer "F.Cu")
		(net "P3V3_2_AND")
	)
	(segment
		(start 154.87396 -83.693)
		(end 151.95296 -80.772)
		(width 0.4572)
		(layer "F.Cu")
		(net "P3V3_2_AND")
	)
	(segment
		(start 172.847 -83.414616)
		(end 173.665896 -82.59572)
		(width 0.4572)
		(layer "F.Cu")
		(net "P3V3_2_AND")
	)
	(segment
		(start 170.173904 -87.810594)
		(end 168.208706 -89.775792)
		(width 0.4572)
		(layer "F.Cu")
		(net "P3V3_2_AND")
	)
	(segment
		(start 158.129732 -88.393524)
		(end 158.129732 -84.342986)
		(width 0.4572)
		(layer "F.Cu")
		(net "P3V3_2_AND")
	)
	(segment
		(start 171.831 -84.30895)
		(end 170.434 -84.30895)
		(width 0.4572)
		(layer "F.Cu")
		(net "P3V3_2_AND")
	)
	(segment
		(start 168.208706 -89.775792)
		(end 159.512 -89.775792)
		(width 0.4572)
		(layer "F.Cu")
		(net "P3V3_2_AND")
	)
	(segment
		(start 172.847 -84.30895)
		(end 171.831 -84.30895)
		(width 0.4572)
		(layer "F.Cu")
		(net "P3V3_2_AND")
	)
	(segment
		(start 170.434 -84.30895)
		(end 170.173904 -84.569046)
		(width 0.4572)
		(layer "F.Cu")
		(net "P3V3_2_AND")
	)
	(via
		(at 170.434 -84.30895)
		(size 0.762)
		(drill 0.381)
		(layers "F.Cu" "B.Cu")
		(net "P3V3_2_AND")
	)
	(segment
		(start 178.87696 -45.212)
		(end 178.87696 -46.99)
		(width 0.17272)
		(layer "F.Cu")
		(net "P52V_2_FUSE_1")
	)
	(via
		(at 191.9224 -47.752)
		(size 0.508)
		(drill 0.254)
		(layers "F.Cu" "B.Cu")
		(net "P52V_2_FUSE_1")
	)
	(via
		(at 185.9534 -46.99)
		(size 0.508)
		(drill 0.254)
		(layers "F.Cu" "B.Cu")
		(net "P52V_2_FUSE_1")
	)
	(via
		(at 191.9224 -46.99)
		(size 0.508)
		(drill 0.254)
		(layers "F.Cu" "B.Cu")
		(net "P52V_2_FUSE_1")
	)
	(via
		(at 183.6674 -46.99)
		(size 0.508)
		(drill 0.254)
		(layers "F.Cu" "B.Cu")
		(net "P52V_2_FUSE_1")
	)
	(via
		(at 189.6364 -46.99)
		(size 0.508)
		(drill 0.254)
		(layers "F.Cu" "B.Cu")
		(net "P52V_2_FUSE_1")
	)
	(via
		(at 182.9054 -47.752)
		(size 0.508)
		(drill 0.254)
		(layers "F.Cu" "B.Cu")
		(net "P52V_2_FUSE_1")
	)
	(via
		(at 184.4294 -46.99)
		(size 0.762)
		(drill 0.254)
		(layers "F.Cu" "B.Cu")
		(net "P52V_2_FUSE_1")
	)
	(via
		(at 192.6844 -46.99)
		(size 0.508)
		(drill 0.254)
		(layers "F.Cu" "B.Cu")
		(net "P52V_2_FUSE_1")
	)
	(via
		(at 178.87696 -46.99)
		(size 0.508)
		(drill 0.254)
		(layers "F.Cu" "B.Cu")
		(net "P52V_2_FUSE_1")
	)
	(via
		(at 185.1914 -47.752)
		(size 0.508)
		(drill 0.254)
		(layers "F.Cu" "B.Cu")
		(net "P52V_2_FUSE_1")
	)
	(via
		(at 190.3984 -46.99)
		(size 0.508)
		(drill 0.254)
		(layers "F.Cu" "B.Cu")
		(net "P52V_2_FUSE_1")
	)
	(via
		(at 183.6674 -47.752)
		(size 0.508)
		(drill 0.254)
		(layers "F.Cu" "B.Cu")
		(net "P52V_2_FUSE_1")
	)
	(via
		(at 182.9054 -46.99)
		(size 0.508)
		(drill 0.254)
		(layers "F.Cu" "B.Cu")
		(net "P52V_2_FUSE_1")
	)
	(via
		(at 190.3984 -47.752)
		(size 0.508)
		(drill 0.254)
		(layers "F.Cu" "B.Cu")
		(net "P52V_2_FUSE_1")
	)
	(via
		(at 189.6364 -47.752)
		(size 0.508)
		(drill 0.254)
		(layers "F.Cu" "B.Cu")
		(net "P52V_2_FUSE_1")
	)
	(via
		(at 185.1914 -46.99)
		(size 0.508)
		(drill 0.254)
		(layers "F.Cu" "B.Cu")
		(net "P52V_2_FUSE_1")
	)
	(via
		(at 185.9534 -47.752)
		(size 0.508)
		(drill 0.254)
		(layers "F.Cu" "B.Cu")
		(net "P52V_2_FUSE_1")
	)
	(via
		(at 192.6844 -47.752)
		(size 0.508)
		(drill 0.254)
		(layers "F.Cu" "B.Cu")
		(net "P52V_2_FUSE_1")
	)
	(via
		(at 184.4294 -47.752)
		(size 0.508)
		(drill 0.254)
		(layers "F.Cu" "B.Cu")
		(net "P52V_2_FUSE_1")
	)
	(via
		(at 191.1604 -46.99)
		(size 0.508)
		(drill 0.254)
		(layers "F.Cu" "B.Cu")
		(net "P52V_2_FUSE_1")
	)
	(via
		(at 191.1604 -47.752)
		(size 0.508)
		(drill 0.254)
		(layers "F.Cu" "B.Cu")
		(net "P52V_2_FUSE_1")
	)
	(segment
		(start 178.87696 -46.99)
		(end 178.90236 -46.99)
		(width 0.17272)
		(layer "B.Cu")
		(net "P52V_2_FUSE_1")
	)
	(segment
		(start 178.90236 -46.99)
		(end 179.9844 -48.07204)
		(width 0.17272)
		(layer "B.Cu")
		(net "P52V_2_FUSE_1")
	)
	(segment
		(start 179.9844 -48.07204)
		(end 181.349904 -48.07204)
		(width 0.17272)
		(layer "B.Cu")
		(net "P52V_2_FUSE_1")
	)
	(segment
		(start 181.349904 -48.07204)
		(end 181.669944 -47.752)
		(width 0.17272)
		(layer "B.Cu")
		(net "P52V_2_FUSE_1")
	)
	(segment
		(start 181.669944 -47.752)
		(end 182.9054 -47.752)
		(width 0.17272)
		(layer "B.Cu")
		(net "P52V_2_FUSE_1")
	)
	(via
		(at 276.843998 -68.89877)
		(size 0.6604)
		(drill 0.3302)
		(layers "F.Cu" "B.Cu")
		(net "SMB_P52V_PDB_SCL_R1")
	)
	(segment
		(start 276.843998 -68.215256)
		(end 277.114254 -67.945)
		(width 0.17272)
		(layer "B.Cu")
		(net "SMB_P52V_PDB_SCL_R1")
	)
	(segment
		(start 277.114254 -67.945)
		(end 278.00935 -67.945)
		(width 0.17272)
		(layer "B.Cu")
		(net "SMB_P52V_PDB_SCL_R1")
	)
	(segment
		(start 274.1041 -68.34632)
		(end 276.291548 -68.34632)
		(width 0.17272)
		(layer "B.Cu")
		(net "SMB_P52V_PDB_SCL_R1")
	)
	(segment
		(start 276.291548 -68.34632)
		(end 276.843998 -68.89877)
		(width 0.17272)
		(layer "B.Cu")
		(net "SMB_P52V_PDB_SCL_R1")
	)
	(segment
		(start 276.843998 -68.89877)
		(end 276.843998 -68.215256)
		(width 0.17272)
		(layer "B.Cu")
		(net "SMB_P52V_PDB_SCL_R1")
	)
	(segment
		(start 278.00935 -68.961)
		(end 278.00935 -67.945)
		(width 0.17272)
		(layer "B.Cu")
		(net "SMB_P52V_PDB_SCL_R1")
	)
	(via
		(at 170.7388 -72.0598)
		(size 0.6604)
		(drill 0.3302)
		(layers "F.Cu" "B.Cu")
		(net "SMB_P52V_PDB_SCL_R2")
	)
	(segment
		(start 171.195746 -72.0598)
		(end 171.393866 -71.86168)
		(width 0.17272)
		(layer "B.Cu")
		(net "SMB_P52V_PDB_SCL_R2")
	)
	(segment
		(start 171.393866 -71.86168)
		(end 173.516036 -71.86168)
		(width 0.17272)
		(layer "B.Cu")
		(net "SMB_P52V_PDB_SCL_R2")
	)
	(segment
		(start 170.5356 -72.263)
		(end 170.7388 -72.0598)
		(width 0.17272)
		(layer "B.Cu")
		(net "SMB_P52V_PDB_SCL_R2")
	)
	(segment
		(start 169.610786 -72.263)
		(end 170.5356 -72.263)
		(width 0.17272)
		(layer "B.Cu")
		(net "SMB_P52V_PDB_SCL_R2")
	)
	(segment
		(start 170.7388 -72.0598)
		(end 171.195746 -72.0598)
		(width 0.17272)
		(layer "B.Cu")
		(net "SMB_P52V_PDB_SCL_R2")
	)
	(segment
		(start 169.610786 -71.247)
		(end 169.610786 -72.263)
		(width 0.17272)
		(layer "B.Cu")
		(net "SMB_P52V_PDB_SCL_R2")
	)
	(segment
		(start 166.143686 -67.564)
		(end 165.3794 -67.564)
		(width 0.4572)
		(layer "F.Cu")
		(net "GND1_FIELD_SIGNAL")
	)
	(segment
		(start 166.143686 -65.024)
		(end 166.143686 -66.167)
		(width 0.4572)
		(layer "F.Cu")
		(net "GND1_FIELD_SIGNAL")
	)
	(segment
		(start 162.8394 -63.881)
		(end 162.8394 -64.634872)
		(width 0.4572)
		(layer "F.Cu")
		(net "GND1_FIELD_SIGNAL")
	)
	(segment
		(start 147.572476 -82.929476)
		(end 132.058664 -82.929476)
		(width 0.4572)
		(layer "F.Cu")
		(net "GND1_FIELD_SIGNAL")
	)
	(segment
		(start 166.143686 -63.881)
		(end 165.1254 -63.881)
		(width 0.4572)
		(layer "F.Cu")
		(net "GND1_FIELD_SIGNAL")
	)
	(segment
		(start 166.143686 -66.167)
		(end 164.99205 -66.167)
		(width 0.4572)
		(layer "F.Cu")
		(net "GND1_FIELD_SIGNAL")
	)
	(segment
		(start 157.099 -84.709)
		(end 149.352 -84.709)
		(width 0.4572)
		(layer "F.Cu")
		(net "GND1_FIELD_SIGNAL")
	)
	(segment
		(start 164.367464 -66.162936)
		(end 164.949886 -66.162936)
		(width 0.4572)
		(layer "F.Cu")
		(net "GND1_FIELD_SIGNAL")
	)
	(segment
		(start 149.352 -84.709)
		(end 147.572476 -82.929476)
		(width 0.4572)
		(layer "F.Cu")
		(net "GND1_FIELD_SIGNAL")
	)
	(segment
		(start 164.99205 -66.167)
		(end 164.973 -66.18605)
		(width 0.4572)
		(layer "F.Cu")
		(net "GND1_FIELD_SIGNAL")
	)
	(segment
		(start 164.973 -66.18605)
		(end 164.973 -67.1576)
		(width 0.4572)
		(layer "F.Cu")
		(net "GND1_FIELD_SIGNAL")
	)
	(segment
		(start 132.058664 -82.929476)
		(end 131.42214 -83.566)
		(width 0.4572)
		(layer "F.Cu")
		(net "GND1_FIELD_SIGNAL")
	)
	(segment
		(start 164.949886 -66.162936)
		(end 164.973 -66.18605)
		(width 0.4572)
		(layer "F.Cu")
		(net "GND1_FIELD_SIGNAL")
	)
	(segment
		(start 164.973 -67.1576)
		(end 165.3794 -67.564)
		(width 0.4572)
		(layer "F.Cu")
		(net "GND1_FIELD_SIGNAL")
	)
	(segment
		(start 162.8394 -64.634872)
		(end 164.367464 -66.162936)
		(width 0.4572)
		(layer "F.Cu")
		(net "GND1_FIELD_SIGNAL")
	)
	(segment
		(start 130.812286 -83.566)
		(end 131.42214 -83.566)
		(width 0.4572)
		(layer "F.Cu")
		(net "GND1_FIELD_SIGNAL")
	)
	(via
		(at 177.401982 -62.768226)
		(size 0.508)
		(drill 0.254)
		(layers "F.Cu" "B.Cu")
		(net "GND1_FIELD_SIGNAL")
	)
	(via
		(at 176.703736 -73.1266)
		(size 0.508)
		(drill 0.254)
		(layers "F.Cu" "B.Cu")
		(net "GND1_FIELD_SIGNAL")
	)
	(via
		(at 176.678336 -68.0974)
		(size 0.508)
		(drill 0.254)
		(layers "F.Cu" "B.Cu")
		(net "GND1_FIELD_SIGNAL")
	)
	(via
		(at 156.510736 -67.818)
		(size 0.508)
		(drill 0.254)
		(layers "F.Cu" "B.Cu")
		(net "GND1_FIELD_SIGNAL")
	)
	(via
		(at 156.510736 -70.104)
		(size 0.508)
		(drill 0.254)
		(layers "F.Cu" "B.Cu")
		(net "GND1_FIELD_SIGNAL")
	)
	(via
		(at 153.589736 -72.39)
		(size 0.508)
		(drill 0.254)
		(layers "F.Cu" "B.Cu")
		(net "GND1_FIELD_SIGNAL")
	)
	(via
		(at 131.42214 -83.566)
		(size 0.508)
		(drill 0.254)
		(layers "F.Cu" "B.Cu")
		(net "GND1_FIELD_SIGNAL")
	)
	(via
		(at 153.589736 -67.818)
		(size 0.508)
		(drill 0.254)
		(layers "F.Cu" "B.Cu")
		(net "GND1_FIELD_SIGNAL")
	)
	(via
		(at 165.3794 -67.564)
		(size 0.508)
		(drill 0.254)
		(layers "F.Cu" "B.Cu")
		(net "GND1_FIELD_SIGNAL")
	)
	(via
		(at 156.510736 -72.39)
		(size 0.508)
		(drill 0.254)
		(layers "F.Cu" "B.Cu")
		(net "GND1_FIELD_SIGNAL")
	)
	(via
		(at 157.099 -84.709)
		(size 0.508)
		(drill 0.254)
		(layers "F.Cu" "B.Cu")
		(net "GND1_FIELD_SIGNAL")
	)
	(via
		(at 174.443136 -68.0974)
		(size 0.508)
		(drill 0.254)
		(layers "F.Cu" "B.Cu")
		(net "GND1_FIELD_SIGNAL")
	)
	(via
		(at 174.443136 -73.1266)
		(size 0.508)
		(drill 0.254)
		(layers "F.Cu" "B.Cu")
		(net "GND1_FIELD_SIGNAL")
	)
	(via
		(at 165.1254 -63.881)
		(size 0.508)
		(drill 0.254)
		(layers "F.Cu" "B.Cu")
		(net "GND1_FIELD_SIGNAL")
	)
	(via
		(at 153.589736 -70.104)
		(size 0.508)
		(drill 0.254)
		(layers "F.Cu" "B.Cu")
		(net "GND1_FIELD_SIGNAL")
	)
	(via
		(at 174.443136 -70.612)
		(size 0.508)
		(drill 0.254)
		(layers "F.Cu" "B.Cu")
		(net "GND1_FIELD_SIGNAL")
	)
	(via
		(at 176.678336 -70.612)
		(size 0.508)
		(drill 0.254)
		(layers "F.Cu" "B.Cu")
		(net "GND1_FIELD_SIGNAL")
	)
	(segment
		(start 177.480722 -62.768226)
		(end 177.401982 -62.768226)
		(width 0.4572)
		(layer "B.Cu")
		(net "GND1_FIELD_SIGNAL")
	)
	(segment
		(start 177.719736 -63.00724)
		(end 177.480722 -62.768226)
		(width 0.4572)
		(layer "B.Cu")
		(net "GND1_FIELD_SIGNAL")
	)
	(segment
		(start 177.719736 -63.35395)
		(end 177.719736 -63.00724)
		(width 0.4572)
		(layer "B.Cu")
		(net "GND1_FIELD_SIGNAL")
	)
	(segment
		(start 448.2084 -87.432134)
		(end 448.2084 -88.138)
		(width 0.1778)
		(layer "F.Cu")
		(net "P3V3_HPDB_PG_R")
	)
	(segment
		(start 449.4784 -89.408)
		(end 449.4784 -89.93505)
		(width 0.1778)
		(layer "F.Cu")
		(net "P3V3_HPDB_PG_R")
	)
	(segment
		(start 448.9704 -88.9)
		(end 449.4784 -89.408)
		(width 0.1778)
		(layer "F.Cu")
		(net "P3V3_HPDB_PG_R")
	)
	(segment
		(start 449.4784 -89.93505)
		(end 450.04355 -90.5002)
		(width 0.1778)
		(layer "F.Cu")
		(net "P3V3_HPDB_PG_R")
	)
	(segment
		(start 443.97295 -50.927)
		(end 443.97295 -51.816)
		(width 0.17272)
		(layer "F.Cu")
		(net "P3V3_HPDB_PG_R")
	)
	(segment
		(start 448.2084 -88.138)
		(end 448.9704 -88.9)
		(width 0.1778)
		(layer "F.Cu")
		(net "P3V3_HPDB_PG_R")
	)
	(segment
		(start 447.73342 -86.957154)
		(end 448.2084 -87.432134)
		(width 0.1778)
		(layer "F.Cu")
		(net "P3V3_HPDB_PG_R")
	)
	(via
		(at 443.97295 -51.816)
		(size 0.508)
		(drill 0.254)
		(layers "F.Cu" "B.Cu")
		(net "P3V3_HPDB_PG_R")
	)
	(via
		(at 448.9704 -88.9)
		(size 0.508)
		(drill 0.254)
		(layers "F.Cu" "B.Cu")
		(net "P3V3_HPDB_PG_R")
	)
	(segment
		(start 456.32116 -68.01612)
		(end 454.41616 -69.92112)
		(width 0.17272)
		(layer "B.Cu")
		(net "P3V3_HPDB_PG_R")
	)
	(segment
		(start 454.41616 -89.93124)
		(end 453.1614 -91.186)
		(width 0.17272)
		(layer "B.Cu")
		(net "P3V3_HPDB_PG_R")
	)
	(segment
		(start 443.97295 -51.816)
		(end 444.754254 -51.816)
		(width 0.17272)
		(layer "B.Cu")
		(net "P3V3_HPDB_PG_R")
	)
	(segment
		(start 451.2564 -91.186)
		(end 448.9704 -88.9)
		(width 0.17272)
		(layer "B.Cu")
		(net "P3V3_HPDB_PG_R")
	)
	(segment
		(start 456.32116 -53.195982)
		(end 456.32116 -68.01612)
		(width 0.17272)
		(layer "B.Cu")
		(net "P3V3_HPDB_PG_R")
	)
	(segment
		(start 446.278254 -50.292)
		(end 453.417178 -50.292)
		(width 0.17272)
		(layer "B.Cu")
		(net "P3V3_HPDB_PG_R")
	)
	(segment
		(start 453.1614 -91.186)
		(end 451.2564 -91.186)
		(width 0.17272)
		(layer "B.Cu")
		(net "P3V3_HPDB_PG_R")
	)
	(segment
		(start 453.417178 -50.292)
		(end 456.32116 -53.195982)
		(width 0.17272)
		(layer "B.Cu")
		(net "P3V3_HPDB_PG_R")
	)
	(segment
		(start 454.41616 -69.92112)
		(end 454.41616 -89.93124)
		(width 0.17272)
		(layer "B.Cu")
		(net "P3V3_HPDB_PG_R")
	)
	(segment
		(start 444.754254 -51.816)
		(end 446.278254 -50.292)
		(width 0.17272)
		(layer "B.Cu")
		(net "P3V3_HPDB_PG_R")
	)
	(segment
		(start 412.0134 -39.606474)
		(end 412.0134 -38.62705)
		(width 0.17272)
		(layer "F.Cu")
		(net "PWRGD_P52V_HS2_4287_PG_N")
	)
	(via
		(at 153.8478 -65.913)
		(size 0.508)
		(drill 0.254)
		(layers "F.Cu" "B.Cu")
		(net "PWRGD_P52V_HS2_4287_PG_N")
	)
	(via
		(at 412.0134 -39.606474)
		(size 0.508)
		(drill 0.254)
		(layers "F.Cu" "B.Cu")
		(net "PWRGD_P52V_HS2_4287_PG_N")
	)
	(segment
		(start 153.8478 -66.703956)
		(end 153.8478 -65.913)
		(width 0.17272)
		(layer "B.Cu")
		(net "PWRGD_P52V_HS2_4287_PG_N")
	)
	(segment
		(start 398.949672 -60.702444)
		(end 375.736866 -60.702444)
		(width 0.12954)
		(layer "In2.Cu")
		(net "PWRGD_P52V_HS2_4287_PG_N")
	)
	(segment
		(start 409.530804 -50.121312)
		(end 398.949672 -60.702444)
		(width 0.12954)
		(layer "In2.Cu")
		(net "PWRGD_P52V_HS2_4287_PG_N")
	)
	(segment
		(start 328.214482 -86.995)
		(end 294.3606 -86.995)
		(width 0.12954)
		(layer "In2.Cu")
		(net "PWRGD_P52V_HS2_4287_PG_N")
	)
	(segment
		(start 224.155 -95.7326)
		(end 222.9866 -95.7326)
		(width 0.12954)
		(layer "In2.Cu")
		(net "PWRGD_P52V_HS2_4287_PG_N")
	)
	(segment
		(start 229.997 -89.8906)
		(end 224.155 -95.7326)
		(width 0.12954)
		(layer "In2.Cu")
		(net "PWRGD_P52V_HS2_4287_PG_N")
	)
	(segment
		(start 221.5896 -91.524836)
		(end 220.361764 -90.297)
		(width 0.12954)
		(layer "In2.Cu")
		(net "PWRGD_P52V_HS2_4287_PG_N")
	)
	(segment
		(start 336.499454 -78.710028)
		(end 328.214482 -86.995)
		(width 0.12954)
		(layer "In2.Cu")
		(net "PWRGD_P52V_HS2_4287_PG_N")
	)
	(segment
		(start 222.9866 -95.7326)
		(end 222.377 -95.123)
		(width 0.12954)
		(layer "In2.Cu")
		(net "PWRGD_P52V_HS2_4287_PG_N")
	)
	(segment
		(start 180.113178 -81.714086)
		(end 178.734974 -80.335882)
		(width 0.12954)
		(layer "In2.Cu")
		(net "PWRGD_P52V_HS2_4287_PG_N")
	)
	(segment
		(start 222.377 -95.123)
		(end 222.377 -93.667072)
		(width 0.12954)
		(layer "In2.Cu")
		(net "PWRGD_P52V_HS2_4287_PG_N")
	)
	(segment
		(start 294.3606 -86.995)
		(end 293.751 -86.3854)
		(width 0.12954)
		(layer "In2.Cu")
		(net "PWRGD_P52V_HS2_4287_PG_N")
	)
	(segment
		(start 222.377 -93.667072)
		(end 221.5896 -92.879672)
		(width 0.12954)
		(layer "In2.Cu")
		(net "PWRGD_P52V_HS2_4287_PG_N")
	)
	(segment
		(start 152.0444 -79.375)
		(end 150.9522 -78.2828)
		(width 0.12954)
		(layer "In2.Cu")
		(net "PWRGD_P52V_HS2_4287_PG_N")
	)
	(segment
		(start 293.751 -86.3854)
		(end 281.0256 -86.3854)
		(width 0.12954)
		(layer "In2.Cu")
		(net "PWRGD_P52V_HS2_4287_PG_N")
	)
	(segment
		(start 150.9522 -78.2828)
		(end 150.9522 -75.5396)
		(width 0.12954)
		(layer "In2.Cu")
		(net "PWRGD_P52V_HS2_4287_PG_N")
	)
	(segment
		(start 279.146 -88.265)
		(end 262.3566 -88.265)
		(width 0.12954)
		(layer "In2.Cu")
		(net "PWRGD_P52V_HS2_4287_PG_N")
	)
	(segment
		(start 163.460684 -74.1426)
		(end 158.228284 -79.375)
		(width 0.12954)
		(layer "In2.Cu")
		(net "PWRGD_P52V_HS2_4287_PG_N")
	)
	(segment
		(start 173.8122 -77.694282)
		(end 170.260518 -74.1426)
		(width 0.12954)
		(layer "In2.Cu")
		(net "PWRGD_P52V_HS2_4287_PG_N")
	)
	(segment
		(start 375.736866 -60.702444)
		(end 357.729282 -78.710028)
		(width 0.12954)
		(layer "In2.Cu")
		(net "PWRGD_P52V_HS2_4287_PG_N")
	)
	(segment
		(start 170.260518 -74.1426)
		(end 163.460684 -74.1426)
		(width 0.12954)
		(layer "In2.Cu")
		(net "PWRGD_P52V_HS2_4287_PG_N")
	)
	(segment
		(start 174.986442 -80.335882)
		(end 173.8122 -79.16164)
		(width 0.12954)
		(layer "In2.Cu")
		(net "PWRGD_P52V_HS2_4287_PG_N")
	)
	(segment
		(start 255.8542 -81.7626)
		(end 247.8532 -81.7626)
		(width 0.12954)
		(layer "In2.Cu")
		(net "PWRGD_P52V_HS2_4287_PG_N")
	)
	(segment
		(start 409.530804 -42.08907)
		(end 409.530804 -50.121312)
		(width 0.12954)
		(layer "In2.Cu")
		(net "PWRGD_P52V_HS2_4287_PG_N")
	)
	(segment
		(start 173.8122 -79.16164)
		(end 173.8122 -77.694282)
		(width 0.12954)
		(layer "In2.Cu")
		(net "PWRGD_P52V_HS2_4287_PG_N")
	)
	(segment
		(start 178.734974 -80.335882)
		(end 174.986442 -80.335882)
		(width 0.12954)
		(layer "In2.Cu")
		(net "PWRGD_P52V_HS2_4287_PG_N")
	)
	(segment
		(start 150.9522 -75.5396)
		(end 152.9588 -73.533)
		(width 0.12954)
		(layer "In2.Cu")
		(net "PWRGD_P52V_HS2_4287_PG_N")
	)
	(segment
		(start 152.9588 -73.533)
		(end 152.9588 -66.802)
		(width 0.12954)
		(layer "In2.Cu")
		(net "PWRGD_P52V_HS2_4287_PG_N")
	)
	(segment
		(start 247.8532 -81.7626)
		(end 239.7252 -89.8906)
		(width 0.12954)
		(layer "In2.Cu")
		(net "PWRGD_P52V_HS2_4287_PG_N")
	)
	(segment
		(start 281.0256 -86.3854)
		(end 279.146 -88.265)
		(width 0.12954)
		(layer "In2.Cu")
		(net "PWRGD_P52V_HS2_4287_PG_N")
	)
	(segment
		(start 357.729282 -78.710028)
		(end 336.499454 -78.710028)
		(width 0.12954)
		(layer "In2.Cu")
		(net "PWRGD_P52V_HS2_4287_PG_N")
	)
	(segment
		(start 158.228284 -79.375)
		(end 152.0444 -79.375)
		(width 0.12954)
		(layer "In2.Cu")
		(net "PWRGD_P52V_HS2_4287_PG_N")
	)
	(segment
		(start 197.969886 -81.714086)
		(end 180.113178 -81.714086)
		(width 0.12954)
		(layer "In2.Cu")
		(net "PWRGD_P52V_HS2_4287_PG_N")
	)
	(segment
		(start 412.0134 -39.606474)
		(end 409.530804 -42.08907)
		(width 0.12954)
		(layer "In2.Cu")
		(net "PWRGD_P52V_HS2_4287_PG_N")
	)
	(segment
		(start 221.5896 -92.879672)
		(end 221.5896 -91.524836)
		(width 0.12954)
		(layer "In2.Cu")
		(net "PWRGD_P52V_HS2_4287_PG_N")
	)
	(segment
		(start 152.9588 -66.802)
		(end 153.8478 -65.913)
		(width 0.12954)
		(layer "In2.Cu")
		(net "PWRGD_P52V_HS2_4287_PG_N")
	)
	(segment
		(start 262.3566 -88.265)
		(end 255.8542 -81.7626)
		(width 0.12954)
		(layer "In2.Cu")
		(net "PWRGD_P52V_HS2_4287_PG_N")
	)
	(segment
		(start 220.361764 -90.297)
		(end 206.5528 -90.297)
		(width 0.12954)
		(layer "In2.Cu")
		(net "PWRGD_P52V_HS2_4287_PG_N")
	)
	(segment
		(start 239.7252 -89.8906)
		(end 229.997 -89.8906)
		(width 0.12954)
		(layer "In2.Cu")
		(net "PWRGD_P52V_HS2_4287_PG_N")
	)
	(segment
		(start 206.5528 -90.297)
		(end 197.969886 -81.714086)
		(width 0.12954)
		(layer "In2.Cu")
		(net "PWRGD_P52V_HS2_4287_PG_N")
	)
	(segment
		(start 433.705 -50.43805)
		(end 433.705 -51.054)
		(width 0.17272)
		(layer "F.Cu")
		(net "PWRGD_P52V_HS_PG_R2")
	)
	(segment
		(start 433.34305 -52.832)
		(end 433.705 -52.47005)
		(width 0.17272)
		(layer "F.Cu")
		(net "PWRGD_P52V_HS_PG_R2")
	)
	(segment
		(start 434.168296 -50.414682)
		(end 433.728368 -50.414682)
		(width 0.17272)
		(layer "F.Cu")
		(net "PWRGD_P52V_HS_PG_R2")
	)
	(segment
		(start 433.705 -52.324)
		(end 434.34 -51.689)
		(width 0.17272)
		(layer "F.Cu")
		(net "PWRGD_P52V_HS_PG_R2")
	)
	(segment
		(start 433.705 -52.47005)
		(end 433.705 -52.324)
		(width 0.17272)
		(layer "F.Cu")
		(net "PWRGD_P52V_HS_PG_R2")
	)
	(segment
		(start 435.705504 -51.36896)
		(end 435.122574 -51.36896)
		(width 0.17272)
		(layer "F.Cu")
		(net "PWRGD_P52V_HS_PG_R2")
	)
	(segment
		(start 433.728368 -50.414682)
		(end 433.705 -50.43805)
		(width 0.17272)
		(layer "F.Cu")
		(net "PWRGD_P52V_HS_PG_R2")
	)
	(segment
		(start 433.705 -51.054)
		(end 434.34 -51.689)
		(width 0.17272)
		(layer "F.Cu")
		(net "PWRGD_P52V_HS_PG_R2")
	)
	(segment
		(start 435.122574 -51.36896)
		(end 434.168296 -50.414682)
		(width 0.17272)
		(layer "F.Cu")
		(net "PWRGD_P52V_HS_PG_R2")
	)
	(via
		(at 434.34 -51.689)
		(size 0.762)
		(drill 0.381)
		(layers "F.Cu" "B.Cu")
		(net "PWRGD_P52V_HS_PG_R2")
	)
	(segment
		(start 145.85442 -34.3662)
		(end 145.85442 -33.6296)
		(width 0.4572)
		(layer "F.Cu")
		(net "P52V_HS2_SENSE_P_R2")
	)
	(segment
		(start 143.003778 -29.077158)
		(end 143.003778 -28.987242)
		(width 0.254)
		(layer "F.Cu")
		(net "P52V_HS2_SENSE_P_R2")
	)
	(segment
		(start 143.46682 -29.5402)
		(end 143.003778 -29.077158)
		(width 0.254)
		(layer "F.Cu")
		(net "P52V_HS2_SENSE_P_R2")
	)
	(segment
		(start 145.85442 -36.1442)
		(end 145.85442 -34.3662)
		(width 0.4572)
		(layer "F.Cu")
		(net "P52V_HS2_SENSE_P_R2")
	)
	(segment
		(start 145.85442 -37.9222)
		(end 145.85442 -36.1442)
		(width 0.4572)
		(layer "F.Cu")
		(net "P52V_HS2_SENSE_P_R2")
	)
	(segment
		(start 143.78051 -29.5402)
		(end 143.46682 -29.5402)
		(width 0.254)
		(layer "F.Cu")
		(net "P52V_HS2_SENSE_P_R2")
	)
	(via
		(at 143.003778 -28.987242)
		(size 0.508)
		(drill 0.254)
		(layers "F.Cu" "B.Cu")
		(net "P52V_HS2_SENSE_P_R2")
	)
	(via
		(at 145.85442 -33.6296)
		(size 0.508)
		(drill 0.254)
		(layers "F.Cu" "B.Cu")
		(net "P52V_HS2_SENSE_P_R2")
	)
	(segment
		(start 145.85442 -33.6296)
		(end 144.130014 -33.6296)
		(width 0.4572)
		(layer "In2.Cu")
		(net "P52V_HS2_SENSE_P_R2")
	)
	(segment
		(start 144.130014 -33.6296)
		(end 143.646906 -33.146492)
		(width 0.4572)
		(layer "In2.Cu")
		(net "P52V_HS2_SENSE_P_R2")
	)
	(segment
		(start 143.646906 -29.63037)
		(end 143.003778 -28.987242)
		(width 0.4572)
		(layer "In2.Cu")
		(net "P52V_HS2_SENSE_P_R2")
	)
	(segment
		(start 143.646906 -33.146492)
		(end 143.646906 -29.63037)
		(width 0.4572)
		(layer "In2.Cu")
		(net "P52V_HS2_SENSE_P_R2")
	)
	(segment
		(start 125.1458 -84.3534)
		(end 125.8062 -83.693)
		(width 0.254)
		(layer "F.Cu")
		(net "P52V_HS2_TEMPN_R")
	)
	(segment
		(start 125.8062 -83.693)
		(end 126.792736 -83.693)
		(width 0.254)
		(layer "F.Cu")
		(net "P52V_HS2_TEMPN_R")
	)
	(segment
		(start 130.012186 -83.110324)
		(end 129.758186 -82.856324)
		(width 0.254)
		(layer "F.Cu")
		(net "P52V_HS2_TEMPN_R")
	)
	(segment
		(start 123.2662 -84.3534)
		(end 125.1458 -84.3534)
		(width 0.254)
		(layer "F.Cu")
		(net "P52V_HS2_TEMPN_R")
	)
	(segment
		(start 130.012186 -83.566)
		(end 130.012186 -83.110324)
		(width 0.254)
		(layer "F.Cu")
		(net "P52V_HS2_TEMPN_R")
	)
	(segment
		(start 129.758186 -82.856324)
		(end 127.629412 -82.856324)
		(width 0.254)
		(layer "F.Cu")
		(net "P52V_HS2_TEMPN_R")
	)
	(segment
		(start 127.629412 -82.856324)
		(end 126.792736 -83.693)
		(width 0.254)
		(layer "F.Cu")
		(net "P52V_HS2_TEMPN_R")
	)
	(via
		(at 123.2662 -84.3534)
		(size 0.762)
		(drill 0.381)
		(layers "F.Cu" "B.Cu")
		(net "P52V_HS2_TEMPN_R")
	)
	(segment
		(start 142.227046 -29.5402)
		(end 142.57782 -29.5402)
		(width 0.254)
		(layer "F.Cu")
		(net "P52V_HS2_SENSE_N_R2")
	)
	(segment
		(start 142.57782 -29.5402)
		(end 143.003778 -29.966158)
		(width 0.254)
		(layer "F.Cu")
		(net "P52V_HS2_SENSE_N_R2")
	)
	(segment
		(start 140.06322 -36.1442)
		(end 140.06322 -34.3662)
		(width 0.4572)
		(layer "F.Cu")
		(net "P52V_HS2_SENSE_N_R2")
	)
	(segment
		(start 140.06322 -36.1442)
		(end 140.06322 -37.9222)
		(width 0.4572)
		(layer "F.Cu")
		(net "P52V_HS2_SENSE_N_R2")
	)
	(segment
		(start 140.06322 -34.3662)
		(end 140.06322 -33.6296)
		(width 0.4572)
		(layer "F.Cu")
		(net "P52V_HS2_SENSE_N_R2")
	)
	(segment
		(start 143.003778 -29.966158)
		(end 143.003778 -30.093158)
		(width 0.254)
		(layer "F.Cu")
		(net "P52V_HS2_SENSE_N_R2")
	)
	(via
		(at 143.003778 -30.093158)
		(size 0.508)
		(drill 0.254)
		(layers "F.Cu" "B.Cu")
		(net "P52V_HS2_SENSE_N_R2")
	)
	(via
		(at 140.06322 -33.6296)
		(size 0.508)
		(drill 0.254)
		(layers "F.Cu" "B.Cu")
		(net "P52V_HS2_SENSE_N_R2")
	)
	(segment
		(start 140.06322 -33.6296)
		(end 142.27048 -33.6296)
		(width 0.4572)
		(layer "In2.Cu")
		(net "P52V_HS2_SENSE_N_R2")
	)
	(segment
		(start 143.003778 -32.896302)
		(end 143.003778 -30.093158)
		(width 0.4572)
		(layer "In2.Cu")
		(net "P52V_HS2_SENSE_N_R2")
	)
	(segment
		(start 142.27048 -33.6296)
		(end 143.003778 -32.896302)
		(width 0.4572)
		(layer "In2.Cu")
		(net "P52V_HS2_SENSE_N_R2")
	)
	(via
		(at 132.609336 -53.6194)
		(size 0.508)
		(drill 0.254)
		(layers "F.Cu" "B.Cu")
		(net "P52V_HS2_DRAIN_1")
	)
	(via
		(at 133.371336 -74.6506)
		(size 0.508)
		(drill 0.254)
		(layers "F.Cu" "B.Cu")
		(net "P52V_HS2_DRAIN_1")
	)
	(via
		(at 132.609336 -64.897)
		(size 0.508)
		(drill 0.254)
		(layers "F.Cu" "B.Cu")
		(net "P52V_HS2_DRAIN_1")
	)
	(via
		(at 132.609336 -64.135)
		(size 0.508)
		(drill 0.254)
		(layers "F.Cu" "B.Cu")
		(net "P52V_HS2_DRAIN_1")
	)
	(via
		(at 133.371336 -52.8574)
		(size 0.508)
		(drill 0.254)
		(layers "F.Cu" "B.Cu")
		(net "P52V_HS2_DRAIN_1")
	)
	(via
		(at 133.371336 -73.8886)
		(size 0.508)
		(drill 0.254)
		(layers "F.Cu" "B.Cu")
		(net "P52V_HS2_DRAIN_1")
	)
	(via
		(at 133.371336 -64.897)
		(size 0.508)
		(drill 0.254)
		(layers "F.Cu" "B.Cu")
		(net "P52V_HS2_DRAIN_1")
	)
	(via
		(at 132.609336 -74.6506)
		(size 0.508)
		(drill 0.254)
		(layers "F.Cu" "B.Cu")
		(net "P52V_HS2_DRAIN_1")
	)
	(via
		(at 134.133336 -61.849)
		(size 0.508)
		(drill 0.254)
		(layers "F.Cu" "B.Cu")
		(net "P52V_HS2_DRAIN_1")
	)
	(via
		(at 134.133336 -75.4126)
		(size 0.508)
		(drill 0.254)
		(layers "F.Cu" "B.Cu")
		(net "P52V_HS2_DRAIN_1")
	)
	(via
		(at 133.371336 -64.135)
		(size 0.508)
		(drill 0.254)
		(layers "F.Cu" "B.Cu")
		(net "P52V_HS2_DRAIN_1")
	)
	(via
		(at 134.133336 -73.8886)
		(size 0.508)
		(drill 0.254)
		(layers "F.Cu" "B.Cu")
		(net "P52V_HS2_DRAIN_1")
	)
	(via
		(at 133.371336 -62.611)
		(size 0.508)
		(drill 0.254)
		(layers "F.Cu" "B.Cu")
		(net "P52V_HS2_DRAIN_1")
	)
	(via
		(at 132.609336 -76.1746)
		(size 0.508)
		(drill 0.254)
		(layers "F.Cu" "B.Cu")
		(net "P52V_HS2_DRAIN_1")
	)
	(via
		(at 134.133336 -64.897)
		(size 0.508)
		(drill 0.254)
		(layers "F.Cu" "B.Cu")
		(net "P52V_HS2_DRAIN_1")
	)
	(via
		(at 133.371336 -51.3334)
		(size 0.508)
		(drill 0.254)
		(layers "F.Cu" "B.Cu")
		(net "P52V_HS2_DRAIN_1")
	)
	(via
		(at 132.609336 -73.1266)
		(size 0.508)
		(drill 0.254)
		(layers "F.Cu" "B.Cu")
		(net "P52V_HS2_DRAIN_1")
	)
	(via
		(at 134.895336 -76.1746)
		(size 0.508)
		(drill 0.254)
		(layers "F.Cu" "B.Cu")
		(net "P52V_HS2_DRAIN_1")
	)
	(via
		(at 134.895336 -73.8886)
		(size 0.508)
		(drill 0.254)
		(layers "F.Cu" "B.Cu")
		(net "P52V_HS2_DRAIN_1")
	)
	(via
		(at 136.398 -57.658)
		(size 0.762)
		(drill 0.381)
		(layers "F.Cu" "B.Cu")
		(net "P52V_HS2_DRAIN_1")
	)
	(via
		(at 132.609336 -62.611)
		(size 0.508)
		(drill 0.254)
		(layers "F.Cu" "B.Cu")
		(net "P52V_HS2_DRAIN_1")
	)
	(via
		(at 138.684 -54.61)
		(size 0.762)
		(drill 0.381)
		(layers "F.Cu" "B.Cu")
		(net "P52V_HS2_DRAIN_1")
	)
	(via
		(at 134.895336 -73.1266)
		(size 0.508)
		(drill 0.254)
		(layers "F.Cu" "B.Cu")
		(net "P52V_HS2_DRAIN_1")
	)
	(via
		(at 133.371336 -75.4126)
		(size 0.508)
		(drill 0.254)
		(layers "F.Cu" "B.Cu")
		(net "P52V_HS2_DRAIN_1")
	)
	(via
		(at 134.133336 -64.135)
		(size 0.508)
		(drill 0.254)
		(layers "F.Cu" "B.Cu")
		(net "P52V_HS2_DRAIN_1")
	)
	(via
		(at 133.371336 -63.373)
		(size 0.508)
		(drill 0.254)
		(layers "F.Cu" "B.Cu")
		(net "P52V_HS2_DRAIN_1")
	)
	(via
		(at 132.609336 -73.8886)
		(size 0.508)
		(drill 0.254)
		(layers "F.Cu" "B.Cu")
		(net "P52V_HS2_DRAIN_1")
	)
	(via
		(at 135.636 -69.85)
		(size 0.762)
		(drill 0.381)
		(layers "F.Cu" "B.Cu")
		(net "P52V_HS2_DRAIN_1")
	)
	(via
		(at 133.371336 -53.6194)
		(size 0.508)
		(drill 0.254)
		(layers "F.Cu" "B.Cu")
		(net "P52V_HS2_DRAIN_1")
	)
	(via
		(at 134.895336 -74.6506)
		(size 0.508)
		(drill 0.254)
		(layers "F.Cu" "B.Cu")
		(net "P52V_HS2_DRAIN_1")
	)
	(via
		(at 133.371336 -61.849)
		(size 0.508)
		(drill 0.254)
		(layers "F.Cu" "B.Cu")
		(net "P52V_HS2_DRAIN_1")
	)
	(via
		(at 134.133336 -76.1746)
		(size 0.508)
		(drill 0.254)
		(layers "F.Cu" "B.Cu")
		(net "P52V_HS2_DRAIN_1")
	)
	(via
		(at 134.133336 -62.611)
		(size 0.508)
		(drill 0.254)
		(layers "F.Cu" "B.Cu")
		(net "P52V_HS2_DRAIN_1")
	)
	(via
		(at 132.609336 -52.0954)
		(size 0.508)
		(drill 0.254)
		(layers "F.Cu" "B.Cu")
		(net "P52V_HS2_DRAIN_1")
	)
	(via
		(at 134.133336 -63.373)
		(size 0.508)
		(drill 0.254)
		(layers "F.Cu" "B.Cu")
		(net "P52V_HS2_DRAIN_1")
	)
	(via
		(at 132.609336 -50.5714)
		(size 0.508)
		(drill 0.254)
		(layers "F.Cu" "B.Cu")
		(net "P52V_HS2_DRAIN_1")
	)
	(via
		(at 132.609336 -75.4126)
		(size 0.508)
		(drill 0.254)
		(layers "F.Cu" "B.Cu")
		(net "P52V_HS2_DRAIN_1")
	)
	(via
		(at 134.133336 -74.6506)
		(size 0.508)
		(drill 0.254)
		(layers "F.Cu" "B.Cu")
		(net "P52V_HS2_DRAIN_1")
	)
	(via
		(at 132.609336 -61.849)
		(size 0.508)
		(drill 0.254)
		(layers "F.Cu" "B.Cu")
		(net "P52V_HS2_DRAIN_1")
	)
	(via
		(at 132.609336 -51.3334)
		(size 0.508)
		(drill 0.254)
		(layers "F.Cu" "B.Cu")
		(net "P52V_HS2_DRAIN_1")
	)
	(via
		(at 138.938 -49.53)
		(size 0.762)
		(drill 0.381)
		(layers "F.Cu" "B.Cu")
		(net "P52V_HS2_DRAIN_1")
	)
	(via
		(at 133.371336 -52.0954)
		(size 0.508)
		(drill 0.254)
		(layers "F.Cu" "B.Cu")
		(net "P52V_HS2_DRAIN_1")
	)
	(via
		(at 134.133336 -73.1266)
		(size 0.508)
		(drill 0.254)
		(layers "F.Cu" "B.Cu")
		(net "P52V_HS2_DRAIN_1")
	)
	(via
		(at 133.371336 -76.1746)
		(size 0.508)
		(drill 0.254)
		(layers "F.Cu" "B.Cu")
		(net "P52V_HS2_DRAIN_1")
	)
	(via
		(at 133.371336 -73.1266)
		(size 0.508)
		(drill 0.254)
		(layers "F.Cu" "B.Cu")
		(net "P52V_HS2_DRAIN_1")
	)
	(via
		(at 132.609336 -52.8574)
		(size 0.508)
		(drill 0.254)
		(layers "F.Cu" "B.Cu")
		(net "P52V_HS2_DRAIN_1")
	)
	(via
		(at 132.609336 -63.373)
		(size 0.508)
		(drill 0.254)
		(layers "F.Cu" "B.Cu")
		(net "P52V_HS2_DRAIN_1")
	)
	(via
		(at 133.371336 -50.5714)
		(size 0.508)
		(drill 0.254)
		(layers "F.Cu" "B.Cu")
		(net "P52V_HS2_DRAIN_1")
	)
	(via
		(at 134.895336 -75.4126)
		(size 0.508)
		(drill 0.254)
		(layers "F.Cu" "B.Cu")
		(net "P52V_HS2_DRAIN_1")
	)
	(via
		(at 133.371336 -28.7782)
		(size 0.508)
		(drill 0.254)
		(layers "F.Cu" "B.Cu")
		(net "P52V_HS2_DRAIN_2")
	)
	(via
		(at 133.371336 -19.0246)
		(size 0.508)
		(drill 0.254)
		(layers "F.Cu" "B.Cu")
		(net "P52V_HS2_DRAIN_2")
	)
	(via
		(at 133.371336 -16.7386)
		(size 0.508)
		(drill 0.254)
		(layers "F.Cu" "B.Cu")
		(net "P52V_HS2_DRAIN_2")
	)
	(via
		(at 132.609336 -39.2938)
		(size 0.508)
		(drill 0.254)
		(layers "F.Cu" "B.Cu")
		(net "P52V_HS2_DRAIN_2")
	)
	(via
		(at 136.144 -14.478)
		(size 0.762)
		(drill 0.381)
		(layers "F.Cu" "B.Cu")
		(net "P52V_HS2_DRAIN_2")
	)
	(via
		(at 132.609336 -18.2626)
		(size 0.508)
		(drill 0.254)
		(layers "F.Cu" "B.Cu")
		(net "P52V_HS2_DRAIN_2")
	)
	(via
		(at 133.371336 -40.8178)
		(size 0.508)
		(drill 0.254)
		(layers "F.Cu" "B.Cu")
		(net "P52V_HS2_DRAIN_2")
	)
	(via
		(at 134.133336 -19.7866)
		(size 0.508)
		(drill 0.254)
		(layers "F.Cu" "B.Cu")
		(net "P52V_HS2_DRAIN_2")
	)
	(via
		(at 132.609336 -17.5006)
		(size 0.508)
		(drill 0.254)
		(layers "F.Cu" "B.Cu")
		(net "P52V_HS2_DRAIN_2")
	)
	(via
		(at 134.895336 -19.7866)
		(size 0.508)
		(drill 0.254)
		(layers "F.Cu" "B.Cu")
		(net "P52V_HS2_DRAIN_2")
	)
	(via
		(at 134.133336 -18.2626)
		(size 0.508)
		(drill 0.254)
		(layers "F.Cu" "B.Cu")
		(net "P52V_HS2_DRAIN_2")
	)
	(via
		(at 134.133336 -29.5402)
		(size 0.508)
		(drill 0.254)
		(layers "F.Cu" "B.Cu")
		(net "P52V_HS2_DRAIN_2")
	)
	(via
		(at 132.609336 -30.3022)
		(size 0.508)
		(drill 0.254)
		(layers "F.Cu" "B.Cu")
		(net "P52V_HS2_DRAIN_2")
	)
	(via
		(at 134.895336 -18.2626)
		(size 0.508)
		(drill 0.254)
		(layers "F.Cu" "B.Cu")
		(net "P52V_HS2_DRAIN_2")
	)
	(via
		(at 133.371336 -42.3418)
		(size 0.508)
		(drill 0.254)
		(layers "F.Cu" "B.Cu")
		(net "P52V_HS2_DRAIN_2")
	)
	(via
		(at 132.609336 -31.0642)
		(size 0.508)
		(drill 0.254)
		(layers "F.Cu" "B.Cu")
		(net "P52V_HS2_DRAIN_2")
	)
	(via
		(at 132.609336 -28.7782)
		(size 0.508)
		(drill 0.254)
		(layers "F.Cu" "B.Cu")
		(net "P52V_HS2_DRAIN_2")
	)
	(via
		(at 132.609336 -42.3418)
		(size 0.508)
		(drill 0.254)
		(layers "F.Cu" "B.Cu")
		(net "P52V_HS2_DRAIN_2")
	)
	(via
		(at 139.192 -17.272)
		(size 0.762)
		(drill 0.381)
		(layers "F.Cu" "B.Cu")
		(net "P52V_HS2_DRAIN_2")
	)
	(via
		(at 132.609336 -19.7866)
		(size 0.508)
		(drill 0.254)
		(layers "F.Cu" "B.Cu")
		(net "P52V_HS2_DRAIN_2")
	)
	(via
		(at 134.133336 -17.5006)
		(size 0.508)
		(drill 0.254)
		(layers "F.Cu" "B.Cu")
		(net "P52V_HS2_DRAIN_2")
	)
	(via
		(at 134.895336 -19.0246)
		(size 0.508)
		(drill 0.254)
		(layers "F.Cu" "B.Cu")
		(net "P52V_HS2_DRAIN_2")
	)
	(via
		(at 133.371336 -41.5798)
		(size 0.508)
		(drill 0.254)
		(layers "F.Cu" "B.Cu")
		(net "P52V_HS2_DRAIN_2")
	)
	(via
		(at 135.382 -39.624)
		(size 0.762)
		(drill 0.381)
		(layers "F.Cu" "B.Cu")
		(net "P52V_HS2_DRAIN_2")
	)
	(via
		(at 134.133336 -30.3022)
		(size 0.508)
		(drill 0.254)
		(layers "F.Cu" "B.Cu")
		(net "P52V_HS2_DRAIN_2")
	)
	(via
		(at 132.609336 -16.7386)
		(size 0.508)
		(drill 0.254)
		(layers "F.Cu" "B.Cu")
		(net "P52V_HS2_DRAIN_2")
	)
	(via
		(at 132.609336 -19.0246)
		(size 0.508)
		(drill 0.254)
		(layers "F.Cu" "B.Cu")
		(net "P52V_HS2_DRAIN_2")
	)
	(via
		(at 133.371336 -31.0642)
		(size 0.508)
		(drill 0.254)
		(layers "F.Cu" "B.Cu")
		(net "P52V_HS2_DRAIN_2")
	)
	(via
		(at 133.371336 -40.0558)
		(size 0.508)
		(drill 0.254)
		(layers "F.Cu" "B.Cu")
		(net "P52V_HS2_DRAIN_2")
	)
	(via
		(at 133.371336 -28.0162)
		(size 0.508)
		(drill 0.254)
		(layers "F.Cu" "B.Cu")
		(net "P52V_HS2_DRAIN_2")
	)
	(via
		(at 138.938 -22.098)
		(size 0.762)
		(drill 0.381)
		(layers "F.Cu" "B.Cu")
		(net "P52V_HS2_DRAIN_2")
	)
	(via
		(at 134.895336 -16.7386)
		(size 0.508)
		(drill 0.254)
		(layers "F.Cu" "B.Cu")
		(net "P52V_HS2_DRAIN_2")
	)
	(via
		(at 134.895336 -17.5006)
		(size 0.508)
		(drill 0.254)
		(layers "F.Cu" "B.Cu")
		(net "P52V_HS2_DRAIN_2")
	)
	(via
		(at 132.609336 -28.0162)
		(size 0.508)
		(drill 0.254)
		(layers "F.Cu" "B.Cu")
		(net "P52V_HS2_DRAIN_2")
	)
	(via
		(at 133.371336 -29.5402)
		(size 0.508)
		(drill 0.254)
		(layers "F.Cu" "B.Cu")
		(net "P52V_HS2_DRAIN_2")
	)
	(via
		(at 134.133336 -31.0642)
		(size 0.508)
		(drill 0.254)
		(layers "F.Cu" "B.Cu")
		(net "P52V_HS2_DRAIN_2")
	)
	(via
		(at 137.922 -43.688)
		(size 0.762)
		(drill 0.381)
		(layers "F.Cu" "B.Cu")
		(net "P52V_HS2_DRAIN_2")
	)
	(via
		(at 133.371336 -17.5006)
		(size 0.508)
		(drill 0.254)
		(layers "F.Cu" "B.Cu")
		(net "P52V_HS2_DRAIN_2")
	)
	(via
		(at 133.371336 -39.2938)
		(size 0.508)
		(drill 0.254)
		(layers "F.Cu" "B.Cu")
		(net "P52V_HS2_DRAIN_2")
	)
	(via
		(at 132.609336 -29.5402)
		(size 0.508)
		(drill 0.254)
		(layers "F.Cu" "B.Cu")
		(net "P52V_HS2_DRAIN_2")
	)
	(via
		(at 132.609336 -40.0558)
		(size 0.508)
		(drill 0.254)
		(layers "F.Cu" "B.Cu")
		(net "P52V_HS2_DRAIN_2")
	)
	(via
		(at 133.371336 -30.3022)
		(size 0.508)
		(drill 0.254)
		(layers "F.Cu" "B.Cu")
		(net "P52V_HS2_DRAIN_2")
	)
	(via
		(at 134.133336 -28.7782)
		(size 0.508)
		(drill 0.254)
		(layers "F.Cu" "B.Cu")
		(net "P52V_HS2_DRAIN_2")
	)
	(via
		(at 134.133336 -28.0162)
		(size 0.508)
		(drill 0.254)
		(layers "F.Cu" "B.Cu")
		(net "P52V_HS2_DRAIN_2")
	)
	(via
		(at 134.133336 -19.0246)
		(size 0.508)
		(drill 0.254)
		(layers "F.Cu" "B.Cu")
		(net "P52V_HS2_DRAIN_2")
	)
	(via
		(at 132.609336 -40.8178)
		(size 0.508)
		(drill 0.254)
		(layers "F.Cu" "B.Cu")
		(net "P52V_HS2_DRAIN_2")
	)
	(via
		(at 132.609336 -41.5798)
		(size 0.508)
		(drill 0.254)
		(layers "F.Cu" "B.Cu")
		(net "P52V_HS2_DRAIN_2")
	)
	(via
		(at 134.133336 -16.7386)
		(size 0.508)
		(drill 0.254)
		(layers "F.Cu" "B.Cu")
		(net "P52V_HS2_DRAIN_2")
	)
	(via
		(at 133.371336 -18.2626)
		(size 0.508)
		(drill 0.254)
		(layers "F.Cu" "B.Cu")
		(net "P52V_HS2_DRAIN_2")
	)
	(via
		(at 133.371336 -19.7866)
		(size 0.508)
		(drill 0.254)
		(layers "F.Cu" "B.Cu")
		(net "P52V_HS2_DRAIN_2")
	)
	(segment
		(start 273.3294 -76.47305)
		(end 273.3294 -74.93)
		(width 0.17272)
		(layer "F.Cu")
		(net "P52V_HS1_UVLO_EN")
	)
	(segment
		(start 271.69745 -79.121)
		(end 271.69745 -81.00695)
		(width 0.17272)
		(layer "F.Cu")
		(net "P52V_HS1_UVLO_EN")
	)
	(segment
		(start 271.69745 -78.105)
		(end 273.3294 -76.47305)
		(width 0.17272)
		(layer "F.Cu")
		(net "P52V_HS1_UVLO_EN")
	)
	(segment
		(start 273.3294 -74.93)
		(end 272.628106 -74.228706)
		(width 0.17272)
		(layer "F.Cu")
		(net "P52V_HS1_UVLO_EN")
	)
	(segment
		(start 271.69745 -81.00695)
		(end 270.4084 -82.296)
		(width 0.17272)
		(layer "F.Cu")
		(net "P52V_HS1_UVLO_EN")
	)
	(segment
		(start 271.69745 -79.121)
		(end 271.69745 -78.105)
		(width 0.17272)
		(layer "F.Cu")
		(net "P52V_HS1_UVLO_EN")
	)
	(via
		(at 270.4084 -82.296)
		(size 0.508)
		(drill 0.254)
		(layers "F.Cu" "B.Cu")
		(net "P52V_HS1_UVLO_EN")
	)
	(via
		(at 272.628106 -74.228706)
		(size 0.508)
		(drill 0.254)
		(layers "F.Cu" "B.Cu")
		(net "P52V_HS1_UVLO_EN")
	)
	(via
		(at 295.469564 -64.848994)
		(size 0.762)
		(drill 0.254)
		(layers "F.Cu" "B.Cu")
		(net "P52V_HS1_UVLO_EN")
	)
	(segment
		(start 272.628106 -74.228706)
		(end 272.40484 -74.00544)
		(width 0.17272)
		(layer "B.Cu")
		(net "P52V_HS1_UVLO_EN")
	)
	(segment
		(start 294.272462 -66.536316)
		(end 295.469564 -65.339214)
		(width 0.17272)
		(layer "B.Cu")
		(net "P52V_HS1_UVLO_EN")
	)
	(segment
		(start 295.469564 -65.339214)
		(end 295.469564 -64.848994)
		(width 0.17272)
		(layer "B.Cu")
		(net "P52V_HS1_UVLO_EN")
	)
	(segment
		(start 272.40484 -74.00544)
		(end 272.40484 -73.04532)
		(width 0.17272)
		(layer "B.Cu")
		(net "P52V_HS1_UVLO_EN")
	)
	(segment
		(start 270.4084 -83.25104)
		(end 270.4084 -82.296)
		(width 0.17272)
		(layer "B.Cu")
		(net "P52V_HS1_UVLO_EN")
	)
	(segment
		(start 294.272462 -66.703956)
		(end 294.272462 -66.536316)
		(width 0.17272)
		(layer "B.Cu")
		(net "P52V_HS1_UVLO_EN")
	)
	(segment
		(start 283.459936 -82.833718)
		(end 274.715478 -74.08926)
		(width 0.12954)
		(layer "In2.Cu")
		(net "P52V_HS1_UVLO_EN")
	)
	(segment
		(start 295.489376 -80.405478)
		(end 295.489376 -82.357976)
		(width 0.12954)
		(layer "In2.Cu")
		(net "P52V_HS1_UVLO_EN")
	)
	(segment
		(start 296.396918 -79.497936)
		(end 295.489376 -80.405478)
		(width 0.12954)
		(layer "In2.Cu")
		(net "P52V_HS1_UVLO_EN")
	)
	(segment
		(start 295.013634 -82.833718)
		(end 283.459936 -82.833718)
		(width 0.12954)
		(layer "In2.Cu")
		(net "P52V_HS1_UVLO_EN")
	)
	(segment
		(start 295.469564 -70.603364)
		(end 296.396918 -71.530718)
		(width 0.12954)
		(layer "In2.Cu")
		(net "P52V_HS1_UVLO_EN")
	)
	(segment
		(start 295.469564 -64.848994)
		(end 295.469564 -70.603364)
		(width 0.12954)
		(layer "In2.Cu")
		(net "P52V_HS1_UVLO_EN")
	)
	(segment
		(start 274.715478 -74.08926)
		(end 272.767552 -74.08926)
		(width 0.12954)
		(layer "In2.Cu")
		(net "P52V_HS1_UVLO_EN")
	)
	(segment
		(start 296.396918 -71.530718)
		(end 296.396918 -79.497936)
		(width 0.12954)
		(layer "In2.Cu")
		(net "P52V_HS1_UVLO_EN")
	)
	(segment
		(start 272.767552 -74.08926)
		(end 272.628106 -74.228706)
		(width 0.12954)
		(layer "In2.Cu")
		(net "P52V_HS1_UVLO_EN")
	)
	(segment
		(start 295.489376 -82.357976)
		(end 295.013634 -82.833718)
		(width 0.12954)
		(layer "In2.Cu")
		(net "P52V_HS1_UVLO_EN")
	)
	(via
		(at 171.1452 -73.5076)
		(size 0.6604)
		(drill 0.3302)
		(layers "F.Cu" "B.Cu")
		(net "SMB_CM_HS2_3V3SB_DATI")
	)
	(segment
		(start 171.905676 -72.36206)
		(end 173.516036 -72.36206)
		(width 0.17272)
		(layer "B.Cu")
		(net "SMB_CM_HS2_3V3SB_DATI")
	)
	(segment
		(start 171.1452 -73.5076)
		(end 171.1452 -73.122536)
		(width 0.17272)
		(layer "B.Cu")
		(net "SMB_CM_HS2_3V3SB_DATI")
	)
	(segment
		(start 169.972736 -74.295)
		(end 169.610786 -74.295)
		(width 0.17272)
		(layer "B.Cu")
		(net "SMB_CM_HS2_3V3SB_DATI")
	)
	(segment
		(start 171.1452 -73.122536)
		(end 171.905676 -72.36206)
		(width 0.17272)
		(layer "B.Cu")
		(net "SMB_CM_HS2_3V3SB_DATI")
	)
	(segment
		(start 171.1452 -73.5076)
		(end 170.760136 -73.5076)
		(width 0.17272)
		(layer "B.Cu")
		(net "SMB_CM_HS2_3V3SB_DATI")
	)
	(segment
		(start 170.760136 -73.5076)
		(end 169.972736 -74.295)
		(width 0.17272)
		(layer "B.Cu")
		(net "SMB_CM_HS2_3V3SB_DATI")
	)
	(via
		(at 179.497736 -69.1896)
		(size 0.508)
		(drill 0.254)
		(layers "F.Cu" "B.Cu")
		(net "P52V_HS2_VCC")
	)
	(via
		(at 178.557936 -72.009)
		(size 0.508)
		(drill 0.254)
		(layers "F.Cu" "B.Cu")
		(net "P52V_HS2_VCC")
	)
	(via
		(at 178.557936 -69.1896)
		(size 0.508)
		(drill 0.254)
		(layers "F.Cu" "B.Cu")
		(net "P52V_HS2_VCC")
	)
	(via
		(at 179.82692 -64.103504)
		(size 0.6604)
		(drill 0.3302)
		(layers "F.Cu" "B.Cu")
		(net "P52V_HS2_VCC")
	)
	(via
		(at 179.497736 -72.009)
		(size 0.508)
		(drill 0.254)
		(layers "F.Cu" "B.Cu")
		(net "P52V_HS2_VCC")
	)
	(segment
		(start 129.212086 -81.788)
		(end 128.602486 -81.788)
		(width 0.254)
		(layer "F.Cu")
		(net "P52V_HS2_TEMPP")
	)
	(via
		(at 175.795686 -62.99708)
		(size 0.508)
		(drill 0.254)
		(layers "F.Cu" "B.Cu")
		(net "P52V_HS2_TEMPP")
	)
	(via
		(at 128.602486 -81.788)
		(size 0.508)
		(drill 0.254)
		(layers "F.Cu" "B.Cu")
		(net "P52V_HS2_TEMPP")
	)
	(segment
		(start 175.795686 -64.135)
		(end 175.996346 -64.33566)
		(width 0.254)
		(layer "B.Cu")
		(net "P52V_HS2_TEMPP")
	)
	(segment
		(start 176.276508 -66.668396)
		(end 176.216056 -66.728848)
		(width 0.254)
		(layer "B.Cu")
		(net "P52V_HS2_TEMPP")
	)
	(segment
		(start 176.216056 -66.728848)
		(end 176.216056 -67.16268)
		(width 0.254)
		(layer "B.Cu")
		(net "P52V_HS2_TEMPP")
	)
	(segment
		(start 175.996346 -64.33566)
		(end 175.996346 -65.171828)
		(width 0.254)
		(layer "B.Cu")
		(net "P52V_HS2_TEMPP")
	)
	(segment
		(start 175.996346 -65.171828)
		(end 176.276508 -65.45199)
		(width 0.254)
		(layer "B.Cu")
		(net "P52V_HS2_TEMPP")
	)
	(segment
		(start 176.276508 -65.45199)
		(end 176.276508 -66.668396)
		(width 0.254)
		(layer "B.Cu")
		(net "P52V_HS2_TEMPP")
	)
	(segment
		(start 175.795686 -63.754)
		(end 175.795686 -64.135)
		(width 0.254)
		(layer "B.Cu")
		(net "P52V_HS2_TEMPP")
	)
	(segment
		(start 175.795686 -63.754)
		(end 175.795686 -62.99708)
		(width 0.254)
		(layer "B.Cu")
		(net "P52V_HS2_TEMPP")
	)
	(segment
		(start 151.562562 -65.490598)
		(end 151.562562 -72.180958)
		(width 0.254)
		(layer "In2.Cu")
		(net "P52V_HS2_TEMPP")
	)
	(segment
		(start 151.562562 -72.180958)
		(end 148.34489 -75.39863)
		(width 0.254)
		(layer "In2.Cu")
		(net "P52V_HS2_TEMPP")
	)
	(segment
		(start 141.943074 -75.39863)
		(end 134.856474 -82.48523)
		(width 0.254)
		(layer "In2.Cu")
		(net "P52V_HS2_TEMPP")
	)
	(segment
		(start 158.461456 -61.640466)
		(end 155.412694 -61.640466)
		(width 0.254)
		(layer "In2.Cu")
		(net "P52V_HS2_TEMPP")
	)
	(segment
		(start 148.34489 -75.39863)
		(end 141.943074 -75.39863)
		(width 0.254)
		(layer "In2.Cu")
		(net "P52V_HS2_TEMPP")
	)
	(segment
		(start 175.744378 -63.813182)
		(end 168.458134 -63.813182)
		(width 0.254)
		(layer "In2.Cu")
		(net "P52V_HS2_TEMPP")
	)
	(segment
		(start 161.851848 -58.250074)
		(end 158.461456 -61.640466)
		(width 0.254)
		(layer "In2.Cu")
		(net "P52V_HS2_TEMPP")
	)
	(segment
		(start 134.856474 -82.48523)
		(end 129.299716 -82.48523)
		(width 0.254)
		(layer "In2.Cu")
		(net "P52V_HS2_TEMPP")
	)
	(segment
		(start 168.458134 -63.813182)
		(end 162.895026 -58.250074)
		(width 0.254)
		(layer "In2.Cu")
		(net "P52V_HS2_TEMPP")
	)
	(segment
		(start 162.895026 -58.250074)
		(end 161.851848 -58.250074)
		(width 0.254)
		(layer "In2.Cu")
		(net "P52V_HS2_TEMPP")
	)
	(segment
		(start 175.998378 -63.199772)
		(end 175.998378 -63.559182)
		(width 0.254)
		(layer "In2.Cu")
		(net "P52V_HS2_TEMPP")
	)
	(segment
		(start 155.412694 -61.640466)
		(end 151.562562 -65.490598)
		(width 0.254)
		(layer "In2.Cu")
		(net "P52V_HS2_TEMPP")
	)
	(segment
		(start 175.795686 -62.99708)
		(end 175.998378 -63.199772)
		(width 0.254)
		(layer "In2.Cu")
		(net "P52V_HS2_TEMPP")
	)
	(segment
		(start 129.299716 -82.48523)
		(end 128.602486 -81.788)
		(width 0.254)
		(layer "In2.Cu")
		(net "P52V_HS2_TEMPP")
	)
	(segment
		(start 175.998378 -63.559182)
		(end 175.744378 -63.813182)
		(width 0.254)
		(layer "In2.Cu")
		(net "P52V_HS2_TEMPP")
	)
	(segment
		(start 174.584106 -66.583814)
		(end 175.444404 -66.583814)
		(width 0.17272)
		(layer "F.Cu")
		(net "P52V_HS2_UVH")
	)
	(segment
		(start 173.147736 -58.62828)
		(end 174.178214 -59.658758)
		(width 0.17272)
		(layer "F.Cu")
		(net "P52V_HS2_UVH")
	)
	(segment
		(start 174.178214 -59.658758)
		(end 174.178214 -66.177922)
		(width 0.17272)
		(layer "F.Cu")
		(net "P52V_HS2_UVH")
	)
	(segment
		(start 174.178214 -66.177922)
		(end 174.584106 -66.583814)
		(width 0.17272)
		(layer "F.Cu")
		(net "P52V_HS2_UVH")
	)
	(segment
		(start 175.444404 -66.583814)
		(end 175.715676 -66.312542)
		(width 0.17272)
		(layer "F.Cu")
		(net "P52V_HS2_UVH")
	)
	(via
		(at 175.715676 -66.312542)
		(size 0.508)
		(drill 0.254)
		(layers "F.Cu" "B.Cu")
		(net "P52V_HS2_UVH")
	)
	(via
		(at 173.147736 -58.62828)
		(size 0.508)
		(drill 0.254)
		(layers "F.Cu" "B.Cu")
		(net "P52V_HS2_UVH")
	)
	(segment
		(start 175.715676 -65.975484)
		(end 175.715676 -66.312542)
		(width 0.17272)
		(layer "B.Cu")
		(net "P52V_HS2_UVH")
	)
	(segment
		(start 174.798736 -65.058544)
		(end 175.715676 -65.975484)
		(width 0.17272)
		(layer "B.Cu")
		(net "P52V_HS2_UVH")
	)
	(segment
		(start 174.798736 -64.15405)
		(end 174.798736 -65.058544)
		(width 0.17272)
		(layer "B.Cu")
		(net "P52V_HS2_UVH")
	)
	(segment
		(start 175.715676 -66.312542)
		(end 175.715676 -67.16268)
		(width 0.17272)
		(layer "B.Cu")
		(net "P52V_HS2_UVH")
	)
	(segment
		(start 173.782736 -64.15405)
		(end 174.798736 -64.15405)
		(width 0.17272)
		(layer "B.Cu")
		(net "P52V_HS2_UVH")
	)
	(segment
		(start 173.147736 -56.95696)
		(end 173.147736 -58.62828)
		(width 0.17272)
		(layer "B.Cu")
		(net "P52V_HS2_UVH")
	)
	(segment
		(start 164.3126 -63.5508)
		(end 164.3126 -63.881)
		(width 0.17272)
		(layer "F.Cu")
		(net "P52V_HS2_ESTART")
	)
	(segment
		(start 165.227 -62.6364)
		(end 164.3126 -63.5508)
		(width 0.17272)
		(layer "F.Cu")
		(net "P52V_HS2_ESTART")
	)
	(segment
		(start 166.308786 -63.246)
		(end 165.8366 -63.246)
		(width 0.17272)
		(layer "F.Cu")
		(net "P52V_HS2_ESTART")
	)
	(segment
		(start 165.8366 -63.246)
		(end 165.227 -62.6364)
		(width 0.17272)
		(layer "F.Cu")
		(net "P52V_HS2_ESTART")
	)
	(segment
		(start 168.556686 -63.881)
		(end 166.943786 -63.881)
		(width 0.17272)
		(layer "F.Cu")
		(net "P52V_HS2_ESTART")
	)
	(segment
		(start 166.943786 -63.881)
		(end 166.308786 -63.246)
		(width 0.17272)
		(layer "F.Cu")
		(net "P52V_HS2_ESTART")
	)
	(via
		(at 165.227 -62.6364)
		(size 0.762)
		(drill 0.381)
		(layers "F.Cu" "B.Cu")
		(net "P52V_HS2_ESTART")
	)
	(via
		(at 183.188356 -72.305164)
		(size 0.6604)
		(drill 0.3302)
		(layers "F.Cu" "B.Cu")
		(net "P52V_HS2_VCP")
	)
	(via
		(at 174.714916 -75.946)
		(size 0.6604)
		(drill 0.3302)
		(layers "F.Cu" "B.Cu")
		(net "P52V_HS2_GPO1")
	)
	(segment
		(start 174.333916 -76.327)
		(end 174.714916 -75.946)
		(width 0.17272)
		(layer "B.Cu")
		(net "P52V_HS2_GPO1")
	)
	(segment
		(start 174.714916 -75.946)
		(end 174.714916 -74.06132)
		(width 0.17272)
		(layer "B.Cu")
		(net "P52V_HS2_GPO1")
	)
	(segment
		(start 169.58945 -77.343)
		(end 169.58945 -78.359)
		(width 0.17272)
		(layer "B.Cu")
		(net "P52V_HS2_GPO1")
	)
	(segment
		(start 169.58945 -77.343)
		(end 170.3324 -77.343)
		(width 0.17272)
		(layer "B.Cu")
		(net "P52V_HS2_GPO1")
	)
	(segment
		(start 171.3484 -76.327)
		(end 174.333916 -76.327)
		(width 0.17272)
		(layer "B.Cu")
		(net "P52V_HS2_GPO1")
	)
	(segment
		(start 170.3324 -77.343)
		(end 171.3484 -76.327)
		(width 0.17272)
		(layer "B.Cu")
		(net "P52V_HS2_GPO1")
	)
	(via
		(at 276.1234 -66.167)
		(size 0.6604)
		(drill 0.3302)
		(layers "F.Cu" "B.Cu")
		(net "SMB_CM_HS1_3V3SB_DATO")
	)
	(segment
		(start 274.94484 -67.34556)
		(end 276.1234 -66.167)
		(width 0.17272)
		(layer "B.Cu")
		(net "SMB_CM_HS1_3V3SB_DATO")
	)
	(segment
		(start 276.95779 -65.33261)
		(end 276.1234 -66.167)
		(width 0.17272)
		(layer "B.Cu")
		(net "SMB_CM_HS1_3V3SB_DATO")
	)
	(segment
		(start 278.00935 -64.897)
		(end 276.95779 -65.33261)
		(width 0.17272)
		(layer "B.Cu")
		(net "SMB_CM_HS1_3V3SB_DATO")
	)
	(segment
		(start 274.1041 -67.34556)
		(end 274.94484 -67.34556)
		(width 0.17272)
		(layer "B.Cu")
		(net "SMB_CM_HS1_3V3SB_DATO")
	)
	(segment
		(start 171.1706 -69.596)
		(end 170.5356 -68.961)
		(width 0.17272)
		(layer "F.Cu")
		(net "P52V_HS2_EFAULT_R")
	)
	(segment
		(start 170.5356 -68.961)
		(end 170.5356 -66.294)
		(width 0.17272)
		(layer "F.Cu")
		(net "P52V_HS2_EFAULT_R")
	)
	(segment
		(start 170.5356 -66.202814)
		(end 169.356786 -65.024)
		(width 0.17272)
		(layer "F.Cu")
		(net "P52V_HS2_EFAULT_R")
	)
	(segment
		(start 170.5356 -66.294)
		(end 170.5356 -66.202814)
		(width 0.17272)
		(layer "F.Cu")
		(net "P52V_HS2_EFAULT_R")
	)
	(segment
		(start 171.750736 -69.596)
		(end 171.1706 -69.596)
		(width 0.17272)
		(layer "F.Cu")
		(net "P52V_HS2_EFAULT_R")
	)
	(via
		(at 171.750736 -69.596)
		(size 0.508)
		(drill 0.254)
		(layers "F.Cu" "B.Cu")
		(net "P52V_HS2_EFAULT_R")
	)
	(via
		(at 170.5356 -66.294)
		(size 0.762)
		(drill 0.381)
		(layers "F.Cu" "B.Cu")
		(net "P52V_HS2_EFAULT_R")
	)
	(segment
		(start 173.516036 -69.8627)
		(end 172.017436 -69.8627)
		(width 0.17272)
		(layer "B.Cu")
		(net "P52V_HS2_EFAULT_R")
	)
	(segment
		(start 172.017436 -69.8627)
		(end 171.750736 -69.596)
		(width 0.17272)
		(layer "B.Cu")
		(net "P52V_HS2_EFAULT_R")
	)
	(via
		(at 170.749468 -74.788268)
		(size 0.6604)
		(drill 0.3302)
		(layers "F.Cu" "B.Cu")
		(net "SMB_CM_HS2_3V3SB_DATO")
	)
	(segment
		(start 170.226736 -75.311)
		(end 169.610786 -75.311)
		(width 0.17272)
		(layer "B.Cu")
		(net "SMB_CM_HS2_3V3SB_DATO")
	)
	(segment
		(start 172.675296 -72.86244)
		(end 173.516036 -72.86244)
		(width 0.17272)
		(layer "B.Cu")
		(net "SMB_CM_HS2_3V3SB_DATO")
	)
	(segment
		(start 170.749468 -74.788268)
		(end 170.226736 -75.311)
		(width 0.17272)
		(layer "B.Cu")
		(net "SMB_CM_HS2_3V3SB_DATO")
	)
	(segment
		(start 171.867068 -74.132948)
		(end 171.867068 -73.670668)
		(width 0.17272)
		(layer "B.Cu")
		(net "SMB_CM_HS2_3V3SB_DATO")
	)
	(segment
		(start 171.211748 -74.788268)
		(end 171.867068 -74.132948)
		(width 0.17272)
		(layer "B.Cu")
		(net "SMB_CM_HS2_3V3SB_DATO")
	)
	(segment
		(start 171.867068 -73.670668)
		(end 172.675296 -72.86244)
		(width 0.17272)
		(layer "B.Cu")
		(net "SMB_CM_HS2_3V3SB_DATO")
	)
	(segment
		(start 170.749468 -74.788268)
		(end 171.211748 -74.788268)
		(width 0.17272)
		(layer "B.Cu")
		(net "SMB_CM_HS2_3V3SB_DATO")
	)
	(segment
		(start 173.833536 -75.819)
		(end 172.89145 -75.819)
		(width 0.17272)
		(layer "F.Cu")
		(net "P52V_HS2_GPO2")
	)
	(segment
		(start 174.214536 -75.438)
		(end 173.833536 -75.819)
		(width 0.17272)
		(layer "F.Cu")
		(net "P52V_HS2_GPO2")
	)
	(segment
		(start 172.89145 -75.819)
		(end 172.89145 -76.835)
		(width 0.17272)
		(layer "F.Cu")
		(net "P52V_HS2_GPO2")
	)
	(via
		(at 174.214536 -75.438)
		(size 0.762)
		(drill 0.254)
		(layers "F.Cu" "B.Cu")
		(net "P52V_HS2_GPO2")
	)
	(segment
		(start 174.214536 -74.06132)
		(end 174.214536 -75.438)
		(width 0.17272)
		(layer "B.Cu")
		(net "P52V_HS2_GPO2")
	)
	(via
		(at 177.418238 -65.462658)
		(size 0.6604)
		(drill 0.3302)
		(layers "F.Cu" "B.Cu")
		(net "P52V_HS2_VREG")
	)
	(segment
		(start 177.418238 -65.462658)
		(end 177.418238 -65.50025)
		(width 0.17272)
		(layer "B.Cu")
		(net "P52V_HS2_VREG")
	)
	(segment
		(start 177.418238 -64.455548)
		(end 177.418238 -65.462658)
		(width 0.17272)
		(layer "B.Cu")
		(net "P52V_HS2_VREG")
	)
	(segment
		(start 177.719736 -64.15405)
		(end 177.418238 -64.455548)
		(width 0.17272)
		(layer "B.Cu")
		(net "P52V_HS2_VREG")
	)
	(segment
		(start 177.418238 -65.50025)
		(end 177.216816 -65.701672)
		(width 0.17272)
		(layer "B.Cu")
		(net "P52V_HS2_VREG")
	)
	(segment
		(start 177.216816 -65.701672)
		(end 177.216816 -67.16268)
		(width 0.17272)
		(layer "B.Cu")
		(net "P52V_HS2_VREG")
	)
	(via
		(at 172.004736 -67.818)
		(size 0.6604)
		(drill 0.3302)
		(layers "F.Cu" "B.Cu")
		(net "P52V_HS2_ISTART")
	)
	(segment
		(start 172.548296 -68.36156)
		(end 172.004736 -67.818)
		(width 0.17272)
		(layer "B.Cu")
		(net "P52V_HS2_ISTART")
	)
	(segment
		(start 169.826686 -68.326)
		(end 169.229786 -68.326)
		(width 0.17272)
		(layer "B.Cu")
		(net "P52V_HS2_ISTART")
	)
	(segment
		(start 173.516036 -68.36156)
		(end 172.548296 -68.36156)
		(width 0.17272)
		(layer "B.Cu")
		(net "P52V_HS2_ISTART")
	)
	(segment
		(start 171.87799 -67.691254)
		(end 170.14952 -67.691254)
		(width 0.17272)
		(layer "B.Cu")
		(net "P52V_HS2_ISTART")
	)
	(segment
		(start 172.004736 -67.818)
		(end 171.87799 -67.691254)
		(width 0.17272)
		(layer "B.Cu")
		(net "P52V_HS2_ISTART")
	)
	(segment
		(start 170.14952 -67.691254)
		(end 169.826686 -68.014088)
		(width 0.17272)
		(layer "B.Cu")
		(net "P52V_HS2_ISTART")
	)
	(segment
		(start 169.229786 -68.326)
		(end 168.721786 -67.818)
		(width 0.17272)
		(layer "B.Cu")
		(net "P52V_HS2_ISTART")
	)
	(segment
		(start 169.826686 -68.014088)
		(end 169.826686 -68.326)
		(width 0.17272)
		(layer "B.Cu")
		(net "P52V_HS2_ISTART")
	)
	(via
		(at 169.164 -61.214)
		(size 0.6604)
		(drill 0.3302)
		(layers "F.Cu" "B.Cu")
		(net "P52V_HS2_ISET")
	)
	(via
		(at 276.0599 -67.5005)
		(size 0.6604)
		(drill 0.3302)
		(layers "F.Cu" "B.Cu")
		(net "SMB_CM_HS1_3V3SB_DATI")
	)
	(segment
		(start 277.6474 -65.913)
		(end 276.0599 -67.5005)
		(width 0.17272)
		(layer "B.Cu")
		(net "SMB_CM_HS1_3V3SB_DATI")
	)
	(segment
		(start 275.71446 -67.84594)
		(end 274.1041 -67.84594)
		(width 0.17272)
		(layer "B.Cu")
		(net "SMB_CM_HS1_3V3SB_DATI")
	)
	(segment
		(start 276.0599 -67.5005)
		(end 275.71446 -67.84594)
		(width 0.17272)
		(layer "B.Cu")
		(net "SMB_CM_HS1_3V3SB_DATI")
	)
	(segment
		(start 278.00935 -65.913)
		(end 277.6474 -65.913)
		(width 0.17272)
		(layer "B.Cu")
		(net "SMB_CM_HS1_3V3SB_DATI")
	)
	(segment
		(start 172.512736 -69.39026)
		(end 172.512736 -67.03695)
		(width 0.17272)
		(layer "F.Cu")
		(net "P52V_HS2_ESTART_R")
	)
	(segment
		(start 172.512736 -67.03695)
		(end 169.356786 -63.881)
		(width 0.17272)
		(layer "F.Cu")
		(net "P52V_HS2_ESTART_R")
	)
	(via
		(at 172.512736 -69.39026)
		(size 0.762)
		(drill 0.254)
		(layers "F.Cu" "B.Cu")
		(net "P52V_HS2_ESTART_R")
	)
	(segment
		(start 173.000416 -69.36232)
		(end 173.516036 -69.36232)
		(width 0.17272)
		(layer "B.Cu")
		(net "P52V_HS2_ESTART_R")
	)
	(segment
		(start 172.512736 -69.39026)
		(end 172.972476 -69.39026)
		(width 0.17272)
		(layer "B.Cu")
		(net "P52V_HS2_ESTART_R")
	)
	(segment
		(start 172.972476 -69.39026)
		(end 173.000416 -69.36232)
		(width 0.17272)
		(layer "B.Cu")
		(net "P52V_HS2_ESTART_R")
	)
	(via
		(at 172.7454 -75.5904)
		(size 0.6604)
		(drill 0.3302)
		(layers "F.Cu" "B.Cu")
		(net "P52V_HS2_MCB")
	)
	(segment
		(start 172.7454 -73.681336)
		(end 173.063916 -73.36282)
		(width 0.17272)
		(layer "B.Cu")
		(net "P52V_HS2_MCB")
	)
	(segment
		(start 173.063916 -73.36282)
		(end 173.516036 -73.36282)
		(width 0.17272)
		(layer "B.Cu")
		(net "P52V_HS2_MCB")
	)
	(segment
		(start 172.7454 -75.5904)
		(end 170.815 -75.5904)
		(width 0.17272)
		(layer "B.Cu")
		(net "P52V_HS2_MCB")
	)
	(segment
		(start 170.815 -75.5904)
		(end 170.0784 -76.327)
		(width 0.17272)
		(layer "B.Cu")
		(net "P52V_HS2_MCB")
	)
	(segment
		(start 170.0784 -76.327)
		(end 169.58945 -76.327)
		(width 0.17272)
		(layer "B.Cu")
		(net "P52V_HS2_MCB")
	)
	(segment
		(start 172.7454 -75.5904)
		(end 172.7454 -73.681336)
		(width 0.17272)
		(layer "B.Cu")
		(net "P52V_HS2_MCB")
	)
	(segment
		(start 164.973 -64.7192)
		(end 164.8968 -64.643)
		(width 0.17272)
		(layer "F.Cu")
		(net "P52V_HS2_EFAULT")
	)
	(segment
		(start 164.8968 -64.643)
		(end 165.00856 -64.53124)
		(width 0.17272)
		(layer "F.Cu")
		(net "P52V_HS2_EFAULT")
	)
	(segment
		(start 165.00856 -64.53124)
		(end 166.451026 -64.53124)
		(width 0.17272)
		(layer "F.Cu")
		(net "P52V_HS2_EFAULT")
	)
	(segment
		(start 168.556686 -65.024)
		(end 166.943786 -65.024)
		(width 0.17272)
		(layer "F.Cu")
		(net "P52V_HS2_EFAULT")
	)
	(segment
		(start 166.451026 -64.53124)
		(end 166.943786 -65.024)
		(width 0.17272)
		(layer "F.Cu")
		(net "P52V_HS2_EFAULT")
	)
	(segment
		(start 164.973 -65.38595)
		(end 164.973 -64.7192)
		(width 0.17272)
		(layer "F.Cu")
		(net "P52V_HS2_EFAULT")
	)
	(via
		(at 164.8968 -64.643)
		(size 0.508)
		(drill 0.254)
		(layers "F.Cu" "B.Cu")
		(net "P52V_HS2_EFAULT")
	)
	(via
		(at 265.515598 -75.888342)
		(size 0.6604)
		(drill 0.3302)
		(layers "F.Cu" "B.Cu")
		(net "P52V_HS1_VCC")
	)
	(via
		(at 268.1224 -68.199)
		(size 0.508)
		(drill 0.254)
		(layers "F.Cu" "B.Cu")
		(net "P52V_HS1_VCC")
	)
	(via
		(at 269.0622 -68.199)
		(size 0.508)
		(drill 0.254)
		(layers "F.Cu" "B.Cu")
		(net "P52V_HS1_VCC")
	)
	(via
		(at 268.1224 -71.0184)
		(size 0.508)
		(drill 0.254)
		(layers "F.Cu" "B.Cu")
		(net "P52V_HS1_VCC")
	)
	(via
		(at 269.0622 -71.0184)
		(size 0.508)
		(drill 0.254)
		(layers "F.Cu" "B.Cu")
		(net "P52V_HS1_VCC")
	)
	(segment
		(start 272.90522 -65.141094)
		(end 273.149314 -64.897)
		(width 0.17272)
		(layer "F.Cu")
		(net "P52V_HS1_GPO1")
	)
	(segment
		(start 273.149314 -64.897)
		(end 274.96135 -64.897)
		(width 0.17272)
		(layer "F.Cu")
		(net "P52V_HS1_GPO1")
	)
	(segment
		(start 274.96135 -63.881)
		(end 274.96135 -64.897)
		(width 0.17272)
		(layer "F.Cu")
		(net "P52V_HS1_GPO1")
	)
	(via
		(at 272.90522 -65.141094)
		(size 0.762)
		(drill 0.254)
		(layers "F.Cu" "B.Cu")
		(net "P52V_HS1_GPO1")
	)
	(segment
		(start 272.90522 -66.14668)
		(end 272.90522 -65.141094)
		(width 0.17272)
		(layer "B.Cu")
		(net "P52V_HS1_GPO1")
	)
	(via
		(at 275.0439 -65.2145)
		(size 0.6604)
		(drill 0.3302)
		(layers "F.Cu" "B.Cu")
		(net "P52V_HS1_MCB")
	)
	(segment
		(start 274.8534 -65.405)
		(end 275.0439 -65.2145)
		(width 0.17272)
		(layer "B.Cu")
		(net "P52V_HS1_MCB")
	)
	(segment
		(start 274.55622 -66.84518)
		(end 274.8534 -66.548)
		(width 0.17272)
		(layer "B.Cu")
		(net "P52V_HS1_MCB")
	)
	(segment
		(start 274.1041 -66.84518)
		(end 274.55622 -66.84518)
		(width 0.17272)
		(layer "B.Cu")
		(net "P52V_HS1_MCB")
	)
	(segment
		(start 276.1869 -65.2145)
		(end 277.5204 -63.881)
		(width 0.17272)
		(layer "B.Cu")
		(net "P52V_HS1_MCB")
	)
	(segment
		(start 274.8534 -66.548)
		(end 274.8534 -65.405)
		(width 0.17272)
		(layer "B.Cu")
		(net "P52V_HS1_MCB")
	)
	(segment
		(start 277.5204 -63.881)
		(end 278.00935 -63.881)
		(width 0.17272)
		(layer "B.Cu")
		(net "P52V_HS1_MCB")
	)
	(segment
		(start 275.0439 -65.2145)
		(end 276.1869 -65.2145)
		(width 0.17272)
		(layer "B.Cu")
		(net "P52V_HS1_MCB")
	)
	(via
		(at 275.724112 -74.784712)
		(size 0.6604)
		(drill 0.3302)
		(layers "F.Cu" "B.Cu")
		(net "P52V_HS1_RND")
	)
	(segment
		(start 275.1074 -74.168)
		(end 273.9644 -74.168)
		(width 0.17272)
		(layer "B.Cu")
		(net "P52V_HS1_RND")
	)
	(segment
		(start 276.8854 -75.946)
		(end 275.724112 -74.784712)
		(width 0.17272)
		(layer "B.Cu")
		(net "P52V_HS1_RND")
	)
	(segment
		(start 276.8854 -76.05395)
		(end 276.8854 -75.946)
		(width 0.17272)
		(layer "B.Cu")
		(net "P52V_HS1_RND")
	)
	(segment
		(start 275.724112 -74.784712)
		(end 275.1074 -74.168)
		(width 0.17272)
		(layer "B.Cu")
		(net "P52V_HS1_RND")
	)
	(segment
		(start 273.9644 -74.168)
		(end 273.4056 -73.6092)
		(width 0.17272)
		(layer "B.Cu")
		(net "P52V_HS1_RND")
	)
	(segment
		(start 273.4056 -73.6092)
		(end 273.4056 -73.04532)
		(width 0.17272)
		(layer "B.Cu")
		(net "P52V_HS1_RND")
	)
	(via
		(at 270.264128 -74.919332)
		(size 0.6604)
		(drill 0.3302)
		(layers "F.Cu" "B.Cu")
		(net "P52V_HS1_VREG")
	)
	(segment
		(start 269.9004 -76.05395)
		(end 269.9004 -75.28306)
		(width 0.17272)
		(layer "B.Cu")
		(net "P52V_HS1_VREG")
	)
	(segment
		(start 270.40332 -74.78014)
		(end 270.40332 -73.04532)
		(width 0.17272)
		(layer "B.Cu")
		(net "P52V_HS1_VREG")
	)
	(segment
		(start 269.9004 -75.28306)
		(end 270.264128 -74.919332)
		(width 0.17272)
		(layer "B.Cu")
		(net "P52V_HS1_VREG")
	)
	(segment
		(start 270.264128 -74.919332)
		(end 270.40332 -74.78014)
		(width 0.17272)
		(layer "B.Cu")
		(net "P52V_HS1_VREG")
	)
	(segment
		(start 278.26335 -75.184)
		(end 276.9108 -73.83145)
		(width 0.17272)
		(layer "F.Cu")
		(net "P52V_HS1_EFAULT_R")
	)
	(segment
		(start 276.9108 -73.3044)
		(end 276.9108 -71.6534)
		(width 0.17272)
		(layer "F.Cu")
		(net "P52V_HS1_EFAULT_R")
	)
	(segment
		(start 276.9108 -73.83145)
		(end 276.9108 -73.3044)
		(width 0.17272)
		(layer "F.Cu")
		(net "P52V_HS1_EFAULT_R")
	)
	(segment
		(start 276.9108 -71.6534)
		(end 275.8694 -70.612)
		(width 0.17272)
		(layer "F.Cu")
		(net "P52V_HS1_EFAULT_R")
	)
	(via
		(at 275.8694 -70.612)
		(size 0.508)
		(drill 0.254)
		(layers "F.Cu" "B.Cu")
		(net "P52V_HS1_EFAULT_R")
	)
	(via
		(at 276.9108 -73.3044)
		(size 0.762)
		(drill 0.381)
		(layers "F.Cu" "B.Cu")
		(net "P52V_HS1_EFAULT_R")
	)
	(segment
		(start 275.6027 -70.3453)
		(end 275.8694 -70.612)
		(width 0.17272)
		(layer "B.Cu")
		(net "P52V_HS1_EFAULT_R")
	)
	(segment
		(start 274.1041 -70.3453)
		(end 275.6027 -70.3453)
		(width 0.17272)
		(layer "B.Cu")
		(net "P52V_HS1_EFAULT_R")
	)
	(via
		(at 264.296906 -67.773804)
		(size 0.6604)
		(drill 0.3302)
		(layers "F.Cu" "B.Cu")
		(net "P52V_HS1_VCP")
	)
	(via
		(at 176.716436 -75.4253)
		(size 0.6604)
		(drill 0.3302)
		(layers "F.Cu" "B.Cu")
		(net "P52V_HS2_PWRGIN")
	)
	(segment
		(start 176.716436 -74.06132)
		(end 176.716436 -75.4253)
		(width 0.17272)
		(layer "B.Cu")
		(net "P52V_HS2_PWRGIN")
	)
	(segment
		(start 176.716436 -76.57465)
		(end 176.849786 -76.708)
		(width 0.17272)
		(layer "B.Cu")
		(net "P52V_HS2_PWRGIN")
	)
	(segment
		(start 177.192686 -79.04099)
		(end 177.592736 -79.44104)
		(width 0.17272)
		(layer "B.Cu")
		(net "P52V_HS2_PWRGIN")
	)
	(segment
		(start 177.192686 -77.851)
		(end 177.192686 -79.04099)
		(width 0.17272)
		(layer "B.Cu")
		(net "P52V_HS2_PWRGIN")
	)
	(segment
		(start 176.716436 -75.4253)
		(end 176.716436 -76.57465)
		(width 0.17272)
		(layer "B.Cu")
		(net "P52V_HS2_PWRGIN")
	)
	(segment
		(start 176.849786 -77.5081)
		(end 177.192686 -77.851)
		(width 0.17272)
		(layer "B.Cu")
		(net "P52V_HS2_PWRGIN")
	)
	(segment
		(start 176.849786 -76.708)
		(end 176.849786 -77.5081)
		(width 0.17272)
		(layer "B.Cu")
		(net "P52V_HS2_PWRGIN")
	)
	(via
		(at 264.62736 -64.45504)
		(size 0.6604)
		(drill 0.3302)
		(layers "F.Cu" "B.Cu")
		(net "P52V_HS1_DV_DT")
	)
	(segment
		(start 264.62736 -62.738)
		(end 264.62736 -64.45504)
		(width 0.17272)
		(layer "B.Cu")
		(net "P52V_HS1_DV_DT")
	)
	(segment
		(start 266.15136 -64.45504)
		(end 264.62736 -64.45504)
		(width 0.17272)
		(layer "B.Cu")
		(net "P52V_HS1_DV_DT")
	)
	(segment
		(start 266.4714 -64.135)
		(end 266.15136 -64.45504)
		(width 0.17272)
		(layer "B.Cu")
		(net "P52V_HS1_DV_DT")
	)
	(segment
		(start 266.4714 -62.738)
		(end 266.4714 -64.135)
		(width 0.17272)
		(layer "B.Cu")
		(net "P52V_HS1_DV_DT")
	)
	(segment
		(start 281.450288 -77.100938)
		(end 280.67635 -76.327)
		(width 0.17272)
		(layer "F.Cu")
		(net "P52V_HS1_ESTART")
	)
	(segment
		(start 283.1084 -76.945744)
		(end 282.482544 -77.5716)
		(width 0.17272)
		(layer "F.Cu")
		(net "P52V_HS1_ESTART")
	)
	(segment
		(start 283.1084 -76.327)
		(end 283.1084 -76.945744)
		(width 0.17272)
		(layer "F.Cu")
		(net "P52V_HS1_ESTART")
	)
	(segment
		(start 282.011882 -77.100938)
		(end 281.450288 -77.100938)
		(width 0.17272)
		(layer "F.Cu")
		(net "P52V_HS1_ESTART")
	)
	(segment
		(start 282.482544 -77.5716)
		(end 282.011882 -77.100938)
		(width 0.17272)
		(layer "F.Cu")
		(net "P52V_HS1_ESTART")
	)
	(segment
		(start 279.06345 -76.327)
		(end 280.67635 -76.327)
		(width 0.17272)
		(layer "F.Cu")
		(net "P52V_HS1_ESTART")
	)
	(via
		(at 282.482544 -77.5716)
		(size 0.762)
		(drill 0.381)
		(layers "F.Cu" "B.Cu")
		(net "P52V_HS1_ESTART")
	)
	(via
		(at 181.148736 -75.819)
		(size 0.6604)
		(drill 0.3302)
		(layers "F.Cu" "B.Cu")
		(net "P52V_HS2_DV_DT")
	)
	(segment
		(start 181.148736 -75.819)
		(end 181.55158 -75.819)
		(width 0.17272)
		(layer "B.Cu")
		(net "P52V_HS2_DV_DT")
	)
	(segment
		(start 181.148736 -77.47)
		(end 181.148736 -75.819)
		(width 0.17272)
		(layer "B.Cu")
		(net "P52V_HS2_DV_DT")
	)
	(segment
		(start 181.55158 -75.819)
		(end 182.992776 -77.260196)
		(width 0.17272)
		(layer "B.Cu")
		(net "P52V_HS2_DV_DT")
	)
	(segment
		(start 182.992776 -77.260196)
		(end 182.992776 -77.47)
		(width 0.17272)
		(layer "B.Cu")
		(net "P52V_HS2_DV_DT")
	)
	(segment
		(start 272.4404 -82.296)
		(end 273.8374 -80.899)
		(width 0.17272)
		(layer "F.Cu")
		(net "P52V_HS1_UVH")
	)
	(segment
		(start 273.8374 -73.9902)
		(end 273.471386 -73.624186)
		(width 0.17272)
		(layer "F.Cu")
		(net "P52V_HS1_UVH")
	)
	(segment
		(start 273.471386 -73.624186)
		(end 272.175732 -73.624186)
		(width 0.17272)
		(layer "F.Cu")
		(net "P52V_HS1_UVH")
	)
	(segment
		(start 272.175732 -73.624186)
		(end 271.90446 -73.895458)
		(width 0.17272)
		(layer "F.Cu")
		(net "P52V_HS1_UVH")
	)
	(segment
		(start 273.8374 -80.899)
		(end 273.8374 -73.9902)
		(width 0.17272)
		(layer "F.Cu")
		(net "P52V_HS1_UVH")
	)
	(via
		(at 271.90446 -73.895458)
		(size 0.508)
		(drill 0.254)
		(layers "F.Cu" "B.Cu")
		(net "P52V_HS1_UVH")
	)
	(via
		(at 272.4404 -82.296)
		(size 0.508)
		(drill 0.254)
		(layers "F.Cu" "B.Cu")
		(net "P52V_HS1_UVH")
	)
	(via
		(at 272.360644 -74.910188)
		(size 0.6604)
		(drill 0.3302)
		(layers "F.Cu" "B.Cu")
		(net "P52V_HS1_UVH")
	)
	(segment
		(start 271.90446 -74.232516)
		(end 272.360644 -74.6887)
		(width 0.17272)
		(layer "B.Cu")
		(net "P52V_HS1_UVH")
	)
	(segment
		(start 272.4404 -83.25104)
		(end 272.4404 -82.296)
		(width 0.17272)
		(layer "B.Cu")
		(net "P52V_HS1_UVH")
	)
	(segment
		(start 272.360644 -74.910188)
		(end 272.8214 -75.370944)
		(width 0.17272)
		(layer "B.Cu")
		(net "P52V_HS1_UVH")
	)
	(segment
		(start 272.8214 -75.370944)
		(end 272.8214 -76.05395)
		(width 0.17272)
		(layer "B.Cu")
		(net "P52V_HS1_UVH")
	)
	(segment
		(start 273.8374 -76.05395)
		(end 272.8214 -76.05395)
		(width 0.17272)
		(layer "B.Cu")
		(net "P52V_HS1_UVH")
	)
	(segment
		(start 271.90446 -73.895458)
		(end 271.90446 -73.04532)
		(width 0.17272)
		(layer "B.Cu")
		(net "P52V_HS1_UVH")
	)
	(segment
		(start 271.90446 -73.895458)
		(end 271.90446 -74.232516)
		(width 0.17272)
		(layer "B.Cu")
		(net "P52V_HS1_UVH")
	)
	(segment
		(start 272.360644 -74.6887)
		(end 272.360644 -74.910188)
		(width 0.17272)
		(layer "B.Cu")
		(net "P52V_HS1_UVH")
	)
	(via
		(at 171.896024 -65.423288)
		(size 0.6604)
		(drill 0.3302)
		(layers "F.Cu" "B.Cu")
		(net "P52V_HS2_RND")
	)
	(segment
		(start 174.214536 -66.84772)
		(end 174.214536 -67.16268)
		(width 0.17272)
		(layer "B.Cu")
		(net "P52V_HS2_RND")
	)
	(segment
		(start 173.482 -66.675)
		(end 174.041816 -66.675)
		(width 0.17272)
		(layer "B.Cu")
		(net "P52V_HS2_RND")
	)
	(segment
		(start 170.734736 -64.262)
		(end 171.896024 -65.423288)
		(width 0.17272)
		(layer "B.Cu")
		(net "P52V_HS2_RND")
	)
	(segment
		(start 170.734736 -64.15405)
		(end 170.734736 -64.262)
		(width 0.17272)
		(layer "B.Cu")
		(net "P52V_HS2_RND")
	)
	(segment
		(start 171.896024 -65.423288)
		(end 172.230288 -65.423288)
		(width 0.17272)
		(layer "B.Cu")
		(net "P52V_HS2_RND")
	)
	(segment
		(start 172.230288 -65.423288)
		(end 173.482 -66.675)
		(width 0.17272)
		(layer "B.Cu")
		(net "P52V_HS2_RND")
	)
	(segment
		(start 174.041816 -66.675)
		(end 174.214536 -66.84772)
		(width 0.17272)
		(layer "B.Cu")
		(net "P52V_HS2_RND")
	)
	(via
		(at 273.8374 -64.389)
		(size 0.6604)
		(drill 0.3302)
		(layers "F.Cu" "B.Cu")
		(net "P52V_HS1_GPO2")
	)
	(segment
		(start 273.8374 -64.389)
		(end 275.9964 -64.389)
		(width 0.17272)
		(layer "B.Cu")
		(net "P52V_HS1_GPO2")
	)
	(segment
		(start 273.4056 -66.14668)
		(end 273.4056 -64.8208)
		(width 0.17272)
		(layer "B.Cu")
		(net "P52V_HS1_GPO2")
	)
	(segment
		(start 278.00935 -61.849)
		(end 278.00935 -62.865)
		(width 0.17272)
		(layer "B.Cu")
		(net "P52V_HS1_GPO2")
	)
	(segment
		(start 277.5204 -62.865)
		(end 278.00935 -62.865)
		(width 0.17272)
		(layer "B.Cu")
		(net "P52V_HS1_GPO2")
	)
	(segment
		(start 275.9964 -64.389)
		(end 277.5204 -62.865)
		(width 0.17272)
		(layer "B.Cu")
		(net "P52V_HS1_GPO2")
	)
	(segment
		(start 273.4056 -64.8208)
		(end 273.8374 -64.389)
		(width 0.17272)
		(layer "B.Cu")
		(net "P52V_HS1_GPO2")
	)
	(segment
		(start 182.748936 -72.893936)
		(end 182.748936 -70.86092)
		(width 0.17272)
		(layer "F.Cu")
		(net "P52V_HS2_DV_DT_R")
	)
	(segment
		(start 184.15 -74.295)
		(end 182.748936 -72.893936)
		(width 0.17272)
		(layer "F.Cu")
		(net "P52V_HS2_DV_DT_R")
	)
	(via
		(at 184.15 -74.295)
		(size 0.508)
		(drill 0.254)
		(layers "F.Cu" "B.Cu")
		(net "P52V_HS2_DV_DT_R")
	)
	(via
		(at 182.748936 -70.86092)
		(size 0.508)
		(drill 0.254)
		(layers "F.Cu" "B.Cu")
		(net "P52V_HS2_DV_DT_R")
	)
	(segment
		(start 184.15 -74.295)
		(end 185.166 -75.311)
		(width 0.17272)
		(layer "B.Cu")
		(net "P52V_HS2_DV_DT_R")
	)
	(segment
		(start 184.892696 -76.727304)
		(end 184.892696 -77.47)
		(width 0.17272)
		(layer "B.Cu")
		(net "P52V_HS2_DV_DT_R")
	)
	(segment
		(start 185.166 -75.311)
		(end 185.166 -76.454)
		(width 0.17272)
		(layer "B.Cu")
		(net "P52V_HS2_DV_DT_R")
	)
	(segment
		(start 185.166 -76.454)
		(end 184.892696 -76.727304)
		(width 0.17272)
		(layer "B.Cu")
		(net "P52V_HS2_DV_DT_R")
	)
	(segment
		(start 181.415436 -70.86092)
		(end 182.748936 -70.86092)
		(width 0.17272)
		(layer "B.Cu")
		(net "P52V_HS2_DV_DT_R")
	)
	(segment
		(start 275.4884 -71.19874)
		(end 275.4884 -72.136)
		(width 0.17272)
		(layer "F.Cu")
		(net "P52V_HS1_ESTART_R")
	)
	(segment
		(start 275.1074 -70.81774)
		(end 275.4884 -71.19874)
		(width 0.17272)
		(layer "F.Cu")
		(net "P52V_HS1_ESTART_R")
	)
	(segment
		(start 275.4884 -72.136)
		(end 276.1234 -72.771)
		(width 0.17272)
		(layer "F.Cu")
		(net "P52V_HS1_ESTART_R")
	)
	(segment
		(start 276.1234 -72.771)
		(end 276.1234 -74.18705)
		(width 0.17272)
		(layer "F.Cu")
		(net "P52V_HS1_ESTART_R")
	)
	(segment
		(start 276.1234 -74.18705)
		(end 278.26335 -76.327)
		(width 0.17272)
		(layer "F.Cu")
		(net "P52V_HS1_ESTART_R")
	)
	(via
		(at 275.1074 -70.81774)
		(size 0.762)
		(drill 0.254)
		(layers "F.Cu" "B.Cu")
		(net "P52V_HS1_ESTART_R")
	)
	(segment
		(start 274.61972 -70.84568)
		(end 274.1041 -70.84568)
		(width 0.17272)
		(layer "B.Cu")
		(net "P52V_HS1_ESTART_R")
	)
	(segment
		(start 274.64766 -70.81774)
		(end 274.61972 -70.84568)
		(width 0.17272)
		(layer "B.Cu")
		(net "P52V_HS1_ESTART_R")
	)
	(segment
		(start 275.1074 -70.81774)
		(end 274.64766 -70.81774)
		(width 0.17272)
		(layer "B.Cu")
		(net "P52V_HS1_ESTART_R")
	)
	(segment
		(start 142.917164 -67.691)
		(end 142.409164 -68.199)
		(width 0.4572)
		(layer "F.Cu")
		(net "P52V_HS2_1272_S_N")
	)
	(segment
		(start 142.409164 -68.199)
		(end 141.53642 -68.199)
		(width 0.4572)
		(layer "F.Cu")
		(net "P52V_HS2_1272_S_N")
	)
	(segment
		(start 142.95882 -67.691)
		(end 142.917164 -67.691)
		(width 0.4572)
		(layer "F.Cu")
		(net "P52V_HS2_1272_S_N")
	)
	(segment
		(start 142.57782 -36.1442)
		(end 142.95882 -36.5252)
		(width 0.4572)
		(layer "F.Cu")
		(net "P52V_HS2_1272_S_N")
	)
	(segment
		(start 141.53642 -36.1442)
		(end 142.57782 -36.1442)
		(width 0.4572)
		(layer "F.Cu")
		(net "P52V_HS2_1272_S_N")
	)
	(via
		(at 142.95882 -36.5252)
		(size 0.508)
		(drill 0.254)
		(layers "F.Cu" "B.Cu")
		(net "P52V_HS2_1272_S_N")
	)
	(via
		(at 180.361336 -66.3194)
		(size 0.508)
		(drill 0.254)
		(layers "F.Cu" "B.Cu")
		(net "P52V_HS2_1272_S_N")
	)
	(via
		(at 142.95882 -67.691)
		(size 0.508)
		(drill 0.254)
		(layers "F.Cu" "B.Cu")
		(net "P52V_HS2_1272_S_N")
	)
	(segment
		(start 143.002508 -36.481512)
		(end 142.95882 -36.5252)
		(width 0.4572)
		(layer "B.Cu")
		(net "P52V_HS2_1272_S_N")
	)
	(segment
		(start 143.893032 -65.186306)
		(end 143.977614 -65.101724)
		(width 0.4572)
		(layer "B.Cu")
		(net "P52V_HS2_1272_S_N")
	)
	(segment
		(start 180.216556 -66.46418)
		(end 180.361336 -66.3194)
		(width 0.254)
		(layer "B.Cu")
		(net "P52V_HS2_1272_S_N")
	)
	(segment
		(start 143.893032 -67.535044)
		(end 143.893032 -65.186306)
		(width 0.4572)
		(layer "B.Cu")
		(net "P52V_HS2_1272_S_N")
	)
	(segment
		(start 143.560292 -67.867784)
		(end 143.893032 -67.535044)
		(width 0.4572)
		(layer "B.Cu")
		(net "P52V_HS2_1272_S_N")
	)
	(segment
		(start 143.977614 -36.973002)
		(end 143.486124 -36.481512)
		(width 0.4572)
		(layer "B.Cu")
		(net "P52V_HS2_1272_S_N")
	)
	(segment
		(start 143.977614 -65.101724)
		(end 143.977614 -36.973002)
		(width 0.4572)
		(layer "B.Cu")
		(net "P52V_HS2_1272_S_N")
	)
	(segment
		(start 143.135604 -67.867784)
		(end 143.560292 -67.867784)
		(width 0.4572)
		(layer "B.Cu")
		(net "P52V_HS2_1272_S_N")
	)
	(segment
		(start 142.95882 -67.691)
		(end 143.135604 -67.867784)
		(width 0.4572)
		(layer "B.Cu")
		(net "P52V_HS2_1272_S_N")
	)
	(segment
		(start 143.486124 -36.481512)
		(end 143.002508 -36.481512)
		(width 0.4572)
		(layer "B.Cu")
		(net "P52V_HS2_1272_S_N")
	)
	(segment
		(start 180.216556 -67.16268)
		(end 180.216556 -66.46418)
		(width 0.254)
		(layer "B.Cu")
		(net "P52V_HS2_1272_S_N")
	)
	(segment
		(start 149.536912 -67.54749)
		(end 149.536912 -64.561212)
		(width 0.4572)
		(layer "In2.Cu")
		(net "P52V_HS2_1272_S_N")
	)
	(segment
		(start 149.536912 -64.561212)
		(end 157.314138 -56.783986)
		(width 0.4572)
		(layer "In2.Cu")
		(net "P52V_HS2_1272_S_N")
	)
	(segment
		(start 157.314138 -56.783986)
		(end 166.571168 -56.783986)
		(width 0.4572)
		(layer "In2.Cu")
		(net "P52V_HS2_1272_S_N")
	)
	(segment
		(start 166.571168 -56.783986)
		(end 170.82008 -61.032898)
		(width 0.4572)
		(layer "In2.Cu")
		(net "P52V_HS2_1272_S_N")
	)
	(segment
		(start 146.380454 -69.042534)
		(end 148.041868 -69.042534)
		(width 0.4572)
		(layer "In2.Cu")
		(net "P52V_HS2_1272_S_N")
	)
	(segment
		(start 143.10741 -67.83959)
		(end 145.17751 -67.83959)
		(width 0.4572)
		(layer "In2.Cu")
		(net "P52V_HS2_1272_S_N")
	)
	(segment
		(start 178.113182 -61.032898)
		(end 180.269388 -63.189104)
		(width 0.4572)
		(layer "In2.Cu")
		(net "P52V_HS2_1272_S_N")
	)
	(segment
		(start 148.041868 -69.042534)
		(end 149.536912 -67.54749)
		(width 0.4572)
		(layer "In2.Cu")
		(net "P52V_HS2_1272_S_N")
	)
	(segment
		(start 180.269388 -63.189104)
		(end 180.269388 -66.227452)
		(width 0.4572)
		(layer "In2.Cu")
		(net "P52V_HS2_1272_S_N")
	)
	(segment
		(start 180.269388 -66.227452)
		(end 180.361336 -66.3194)
		(width 0.4572)
		(layer "In2.Cu")
		(net "P52V_HS2_1272_S_N")
	)
	(segment
		(start 170.82008 -61.032898)
		(end 178.113182 -61.032898)
		(width 0.4572)
		(layer "In2.Cu")
		(net "P52V_HS2_1272_S_N")
	)
	(segment
		(start 145.17751 -67.83959)
		(end 146.380454 -69.042534)
		(width 0.4572)
		(layer "In2.Cu")
		(net "P52V_HS2_1272_S_N")
	)
	(segment
		(start 142.95882 -67.691)
		(end 143.10741 -67.83959)
		(width 0.4572)
		(layer "In2.Cu")
		(net "P52V_HS2_1272_S_N")
	)
	(via
		(at 276.987 -73.787)
		(size 0.6604)
		(drill 0.3302)
		(layers "F.Cu" "B.Cu")
		(net "P52V_HS1_ISET")
	)
	(segment
		(start 281.47645 -75.184)
		(end 282.448 -75.184)
		(width 0.17272)
		(layer "F.Cu")
		(net "P52V_HS1_EFAULT")
	)
	(segment
		(start 282.448 -75.184)
		(end 283.21635 -75.184)
		(width 0.17272)
		(layer "F.Cu")
		(net "P52V_HS1_EFAULT")
	)
	(segment
		(start 279.06345 -75.184)
		(end 279.146 -75.184)
		(width 0.17272)
		(layer "F.Cu")
		(net "P52V_HS1_EFAULT")
	)
	(segment
		(start 279.63876 -75.67676)
		(end 281.142186 -75.67676)
		(width 0.17272)
		(layer "F.Cu")
		(net "P52V_HS1_EFAULT")
	)
	(segment
		(start 279.146 -75.184)
		(end 279.63876 -75.67676)
		(width 0.17272)
		(layer "F.Cu")
		(net "P52V_HS1_EFAULT")
	)
	(segment
		(start 281.47645 -75.342496)
		(end 281.47645 -75.184)
		(width 0.17272)
		(layer "F.Cu")
		(net "P52V_HS1_EFAULT")
	)
	(segment
		(start 281.142186 -75.67676)
		(end 281.47645 -75.342496)
		(width 0.17272)
		(layer "F.Cu")
		(net "P52V_HS1_EFAULT")
	)
	(via
		(at 282.448 -75.184)
		(size 0.508)
		(drill 0.254)
		(layers "F.Cu" "B.Cu")
		(net "P52V_HS1_EFAULT")
	)
	(segment
		(start 142.95882 -35.6362)
		(end 143.000984 -35.6362)
		(width 0.4572)
		(layer "F.Cu")
		(net "P52V_HS2_1272_S_P")
	)
	(segment
		(start 143.33982 -68.199)
		(end 142.95882 -68.58)
		(width 0.4572)
		(layer "F.Cu")
		(net "P52V_HS2_1272_S_P")
	)
	(segment
		(start 143.508984 -36.1442)
		(end 144.38122 -36.1442)
		(width 0.4572)
		(layer "F.Cu")
		(net "P52V_HS2_1272_S_P")
	)
	(segment
		(start 143.000984 -35.6362)
		(end 143.508984 -36.1442)
		(width 0.4572)
		(layer "F.Cu")
		(net "P52V_HS2_1272_S_P")
	)
	(segment
		(start 144.38122 -68.199)
		(end 143.33982 -68.199)
		(width 0.4572)
		(layer "F.Cu")
		(net "P52V_HS2_1272_S_P")
	)
	(via
		(at 142.95882 -35.6362)
		(size 0.508)
		(drill 0.254)
		(layers "F.Cu" "B.Cu")
		(net "P52V_HS2_1272_S_P")
	)
	(via
		(at 179.573936 -66.3194)
		(size 0.508)
		(drill 0.254)
		(layers "F.Cu" "B.Cu")
		(net "P52V_HS2_1272_S_P")
	)
	(via
		(at 142.95882 -68.58)
		(size 0.508)
		(drill 0.254)
		(layers "F.Cu" "B.Cu")
		(net "P52V_HS2_1272_S_P")
	)
	(segment
		(start 143.219932 -35.897312)
		(end 143.728186 -35.897312)
		(width 0.4572)
		(layer "B.Cu")
		(net "P52V_HS2_1272_S_P")
	)
	(segment
		(start 144.561814 -65.320164)
		(end 144.477232 -65.404746)
		(width 0.4572)
		(layer "B.Cu")
		(net "P52V_HS2_1272_S_P")
	)
	(segment
		(start 143.728186 -35.897312)
		(end 144.561814 -36.73094)
		(width 0.4572)
		(layer "B.Cu")
		(net "P52V_HS2_1272_S_P")
	)
	(segment
		(start 179.716176 -67.16268)
		(end 179.716176 -66.46164)
		(width 0.254)
		(layer "B.Cu")
		(net "P52V_HS2_1272_S_P")
	)
	(segment
		(start 143.083788 -68.455032)
		(end 142.95882 -68.58)
		(width 0.4572)
		(layer "B.Cu")
		(net "P52V_HS2_1272_S_P")
	)
	(segment
		(start 144.477232 -67.77736)
		(end 143.79956 -68.455032)
		(width 0.4572)
		(layer "B.Cu")
		(net "P52V_HS2_1272_S_P")
	)
	(segment
		(start 144.561814 -36.73094)
		(end 144.561814 -65.320164)
		(width 0.4572)
		(layer "B.Cu")
		(net "P52V_HS2_1272_S_P")
	)
	(segment
		(start 142.95882 -35.6362)
		(end 143.219932 -35.897312)
		(width 0.4572)
		(layer "B.Cu")
		(net "P52V_HS2_1272_S_P")
	)
	(segment
		(start 179.716176 -66.46164)
		(end 179.573936 -66.3194)
		(width 0.254)
		(layer "B.Cu")
		(net "P52V_HS2_1272_S_P")
	)
	(segment
		(start 144.477232 -65.404746)
		(end 144.477232 -67.77736)
		(width 0.4572)
		(layer "B.Cu")
		(net "P52V_HS2_1272_S_P")
	)
	(segment
		(start 143.79956 -68.455032)
		(end 143.083788 -68.455032)
		(width 0.4572)
		(layer "B.Cu")
		(net "P52V_HS2_1272_S_P")
	)
	(segment
		(start 166.329106 -57.368186)
		(end 170.578018 -61.617098)
		(width 0.4572)
		(layer "In2.Cu")
		(net "P52V_HS2_1272_S_P")
	)
	(segment
		(start 148.28393 -69.626734)
		(end 150.121112 -67.789552)
		(width 0.4572)
		(layer "In2.Cu")
		(net "P52V_HS2_1272_S_P")
	)
	(segment
		(start 150.121112 -67.789552)
		(end 150.121112 -64.803274)
		(width 0.4572)
		(layer "In2.Cu")
		(net "P52V_HS2_1272_S_P")
	)
	(segment
		(start 179.685188 -66.208148)
		(end 179.573936 -66.3194)
		(width 0.4572)
		(layer "In2.Cu")
		(net "P52V_HS2_1272_S_P")
	)
	(segment
		(start 146.138392 -69.626734)
		(end 148.28393 -69.626734)
		(width 0.4572)
		(layer "In2.Cu")
		(net "P52V_HS2_1272_S_P")
	)
	(segment
		(start 144.935448 -68.42379)
		(end 146.138392 -69.626734)
		(width 0.4572)
		(layer "In2.Cu")
		(net "P52V_HS2_1272_S_P")
	)
	(segment
		(start 142.95882 -68.58)
		(end 143.11503 -68.42379)
		(width 0.4572)
		(layer "In2.Cu")
		(net "P52V_HS2_1272_S_P")
	)
	(segment
		(start 177.87112 -61.617098)
		(end 179.685188 -63.431166)
		(width 0.4572)
		(layer "In2.Cu")
		(net "P52V_HS2_1272_S_P")
	)
	(segment
		(start 170.578018 -61.617098)
		(end 177.87112 -61.617098)
		(width 0.4572)
		(layer "In2.Cu")
		(net "P52V_HS2_1272_S_P")
	)
	(segment
		(start 157.5562 -57.368186)
		(end 166.329106 -57.368186)
		(width 0.4572)
		(layer "In2.Cu")
		(net "P52V_HS2_1272_S_P")
	)
	(segment
		(start 150.121112 -64.803274)
		(end 157.5562 -57.368186)
		(width 0.4572)
		(layer "In2.Cu")
		(net "P52V_HS2_1272_S_P")
	)
	(segment
		(start 143.11503 -68.42379)
		(end 144.935448 -68.42379)
		(width 0.4572)
		(layer "In2.Cu")
		(net "P52V_HS2_1272_S_P")
	)
	(segment
		(start 179.685188 -63.431166)
		(end 179.685188 -66.208148)
		(width 0.4572)
		(layer "In2.Cu")
		(net "P52V_HS2_1272_S_P")
	)
	(via
		(at 275.6154 -72.39)
		(size 0.6604)
		(drill 0.3302)
		(layers "F.Cu" "B.Cu")
		(net "P52V_HS1_ISTART")
	)
	(segment
		(start 275.6154 -72.39)
		(end 277.28545 -72.39)
		(width 0.17272)
		(layer "B.Cu")
		(net "P52V_HS1_ISTART")
	)
	(segment
		(start 278.89835 -72.39)
		(end 278.39035 -71.882)
		(width 0.17272)
		(layer "B.Cu")
		(net "P52V_HS1_ISTART")
	)
	(segment
		(start 274.1041 -71.84644)
		(end 275.07184 -71.84644)
		(width 0.17272)
		(layer "B.Cu")
		(net "P52V_HS1_ISTART")
	)
	(segment
		(start 278.39035 -71.882)
		(end 277.79345 -71.882)
		(width 0.17272)
		(layer "B.Cu")
		(net "P52V_HS1_ISTART")
	)
	(segment
		(start 277.28545 -72.39)
		(end 277.79345 -71.882)
		(width 0.17272)
		(layer "B.Cu")
		(net "P52V_HS1_ISTART")
	)
	(segment
		(start 275.07184 -71.84644)
		(end 275.6154 -72.39)
		(width 0.17272)
		(layer "B.Cu")
		(net "P52V_HS1_ISTART")
	)
	(via
		(at 111.2774 -43.18)
		(size 0.508)
		(drill 0.254)
		(layers "F.Cu" "B.Cu")
		(net "P52V_HS2_1272_GATE")
	)
	(via
		(at 111.2774 -54.483)
		(size 0.508)
		(drill 0.254)
		(layers "F.Cu" "B.Cu")
		(net "P52V_HS2_1272_GATE")
	)
	(via
		(at 182.215536 -69.4436)
		(size 0.762)
		(drill 0.254)
		(layers "F.Cu" "B.Cu")
		(net "P52V_HS2_1272_GATE")
	)
	(segment
		(start 111.2774 -43.94835)
		(end 111.2774 -43.18)
		(width 0.508)
		(layer "B.Cu")
		(net "P52V_HS2_1272_GATE")
	)
	(segment
		(start 181.796436 -69.8627)
		(end 181.415436 -69.8627)
		(width 0.17272)
		(layer "B.Cu")
		(net "P52V_HS2_1272_GATE")
	)
	(segment
		(start 111.2774 -55.22595)
		(end 111.2774 -54.483)
		(width 0.508)
		(layer "B.Cu")
		(net "P52V_HS2_1272_GATE")
	)
	(segment
		(start 182.215536 -69.4436)
		(end 181.796436 -69.8627)
		(width 0.17272)
		(layer "B.Cu")
		(net "P52V_HS2_1272_GATE")
	)
	(segment
		(start 264.8712 -66.65976)
		(end 264.8712 -69.34708)
		(width 0.17272)
		(layer "F.Cu")
		(net "P52V_HS1_DV_DT_R")
	)
	(segment
		(start 262.72744 -64.516)
		(end 264.8712 -66.65976)
		(width 0.17272)
		(layer "F.Cu")
		(net "P52V_HS1_DV_DT_R")
	)
	(via
		(at 264.8712 -69.34708)
		(size 0.508)
		(drill 0.254)
		(layers "F.Cu" "B.Cu")
		(net "P52V_HS1_DV_DT_R")
	)
	(via
		(at 262.72744 -64.516)
		(size 0.508)
		(drill 0.254)
		(layers "F.Cu" "B.Cu")
		(net "P52V_HS1_DV_DT_R")
	)
	(segment
		(start 266.2047 -69.34708)
		(end 264.8712 -69.34708)
		(width 0.17272)
		(layer "B.Cu")
		(net "P52V_HS1_DV_DT_R")
	)
	(segment
		(start 262.72744 -62.738)
		(end 262.72744 -64.516)
		(width 0.17272)
		(layer "B.Cu")
		(net "P52V_HS1_DV_DT_R")
	)
	(segment
		(start 129.212086 -83.566)
		(end 128.602486 -83.566)
		(width 0.254)
		(layer "F.Cu")
		(net "P52V_HS2_TEMPN")
	)
	(via
		(at 176.595786 -62.99708)
		(size 0.508)
		(drill 0.254)
		(layers "F.Cu" "B.Cu")
		(net "P52V_HS2_TEMPN")
	)
	(via
		(at 128.602486 -83.566)
		(size 0.508)
		(drill 0.254)
		(layers "F.Cu" "B.Cu")
		(net "P52V_HS2_TEMPN")
	)
	(segment
		(start 176.657508 -66.671952)
		(end 176.716436 -66.73088)
		(width 0.254)
		(layer "B.Cu")
		(net "P52V_HS2_TEMPN")
	)
	(segment
		(start 176.595786 -63.754)
		(end 176.595786 -64.135)
		(width 0.254)
		(layer "B.Cu")
		(net "P52V_HS2_TEMPN")
	)
	(segment
		(start 176.595786 -64.135)
		(end 176.377346 -64.35344)
		(width 0.254)
		(layer "B.Cu")
		(net "P52V_HS2_TEMPN")
	)
	(segment
		(start 176.377346 -65.01384)
		(end 176.657508 -65.294002)
		(width 0.254)
		(layer "B.Cu")
		(net "P52V_HS2_TEMPN")
	)
	(segment
		(start 176.595786 -63.754)
		(end 176.595786 -62.99708)
		(width 0.254)
		(layer "B.Cu")
		(net "P52V_HS2_TEMPN")
	)
	(segment
		(start 176.657508 -65.294002)
		(end 176.657508 -66.671952)
		(width 0.254)
		(layer "B.Cu")
		(net "P52V_HS2_TEMPN")
	)
	(segment
		(start 176.716436 -66.73088)
		(end 176.716436 -67.16268)
		(width 0.254)
		(layer "B.Cu")
		(net "P52V_HS2_TEMPN")
	)
	(segment
		(start 176.377346 -64.35344)
		(end 176.377346 -65.01384)
		(width 0.254)
		(layer "B.Cu")
		(net "P52V_HS2_TEMPN")
	)
	(segment
		(start 142.101062 -75.77963)
		(end 135.014462 -82.86623)
		(width 0.254)
		(layer "In2.Cu")
		(net "P52V_HS2_TEMPN")
	)
	(segment
		(start 162.009836 -58.631074)
		(end 158.619444 -62.021466)
		(width 0.254)
		(layer "In2.Cu")
		(net "P52V_HS2_TEMPN")
	)
	(segment
		(start 162.737038 -58.631074)
		(end 162.009836 -58.631074)
		(width 0.254)
		(layer "In2.Cu")
		(net "P52V_HS2_TEMPN")
	)
	(segment
		(start 129.302256 -82.86623)
		(end 128.602486 -83.566)
		(width 0.254)
		(layer "In2.Cu")
		(net "P52V_HS2_TEMPN")
	)
	(segment
		(start 175.902366 -64.194182)
		(end 168.300146 -64.194182)
		(width 0.254)
		(layer "In2.Cu")
		(net "P52V_HS2_TEMPN")
	)
	(segment
		(start 168.300146 -64.194182)
		(end 162.737038 -58.631074)
		(width 0.254)
		(layer "In2.Cu")
		(net "P52V_HS2_TEMPN")
	)
	(segment
		(start 151.943562 -72.338946)
		(end 148.502878 -75.77963)
		(width 0.254)
		(layer "In2.Cu")
		(net "P52V_HS2_TEMPN")
	)
	(segment
		(start 176.595786 -62.99708)
		(end 176.379378 -63.213488)
		(width 0.254)
		(layer "In2.Cu")
		(net "P52V_HS2_TEMPN")
	)
	(segment
		(start 155.570682 -62.021466)
		(end 151.943562 -65.648586)
		(width 0.254)
		(layer "In2.Cu")
		(net "P52V_HS2_TEMPN")
	)
	(segment
		(start 176.379378 -63.71717)
		(end 175.902366 -64.194182)
		(width 0.254)
		(layer "In2.Cu")
		(net "P52V_HS2_TEMPN")
	)
	(segment
		(start 151.943562 -65.648586)
		(end 151.943562 -72.338946)
		(width 0.254)
		(layer "In2.Cu")
		(net "P52V_HS2_TEMPN")
	)
	(segment
		(start 176.379378 -63.213488)
		(end 176.379378 -63.71717)
		(width 0.254)
		(layer "In2.Cu")
		(net "P52V_HS2_TEMPN")
	)
	(segment
		(start 135.014462 -82.86623)
		(end 129.302256 -82.86623)
		(width 0.254)
		(layer "In2.Cu")
		(net "P52V_HS2_TEMPN")
	)
	(segment
		(start 148.502878 -75.77963)
		(end 142.101062 -75.77963)
		(width 0.254)
		(layer "In2.Cu")
		(net "P52V_HS2_TEMPN")
	)
	(segment
		(start 158.619444 -62.021466)
		(end 155.570682 -62.021466)
		(width 0.254)
		(layer "In2.Cu")
		(net "P52V_HS2_TEMPN")
	)
	(via
		(at 270.9037 -64.7827)
		(size 0.6604)
		(drill 0.3302)
		(layers "F.Cu" "B.Cu")
		(net "P52V_HS1_PWRGIN")
	)
	(segment
		(start 270.9037 -66.14668)
		(end 270.9037 -64.7827)
		(width 0.17272)
		(layer "B.Cu")
		(net "P52V_HS1_PWRGIN")
	)
	(segment
		(start 270.9037 -64.7827)
		(end 270.9037 -63.63335)
		(width 0.17272)
		(layer "B.Cu")
		(net "P52V_HS1_PWRGIN")
	)
	(segment
		(start 270.77035 -62.6999)
		(end 270.42745 -62.357)
		(width 0.17272)
		(layer "B.Cu")
		(net "P52V_HS1_PWRGIN")
	)
	(segment
		(start 270.42745 -61.16701)
		(end 270.42745 -62.357)
		(width 0.17272)
		(layer "B.Cu")
		(net "P52V_HS1_PWRGIN")
	)
	(segment
		(start 270.77035 -63.5)
		(end 270.77035 -62.6999)
		(width 0.17272)
		(layer "B.Cu")
		(net "P52V_HS1_PWRGIN")
	)
	(segment
		(start 270.9037 -63.63335)
		(end 270.77035 -63.5)
		(width 0.17272)
		(layer "B.Cu")
		(net "P52V_HS1_PWRGIN")
	)
	(segment
		(start 270.0274 -60.76696)
		(end 270.42745 -61.16701)
		(width 0.17272)
		(layer "B.Cu")
		(net "P52V_HS1_PWRGIN")
	)
	(via
		(at 104.648 -44.45)
		(size 0.6604)
		(drill 0.3302)
		(layers "F.Cu" "B.Cu")
		(net "P52V_HS2_4287_GATE2_RC")
	)
	(segment
		(start 105.9434 -44.45)
		(end 104.648 -44.45)
		(width 0.508)
		(layer "B.Cu")
		(net "P52V_HS2_4287_GATE2_RC")
	)
	(segment
		(start 104.648 -44.45)
		(end 104.7496 -44.3484)
		(width 0.508)
		(layer "B.Cu")
		(net "P52V_HS2_4287_GATE2_RC")
	)
	(segment
		(start 104.7496 -44.3484)
		(end 104.7496 -43.053)
		(width 0.508)
		(layer "B.Cu")
		(net "P52V_HS2_4287_GATE2_RC")
	)
	(segment
		(start 106.045 -44.5516)
		(end 105.9434 -44.45)
		(width 0.508)
		(layer "B.Cu")
		(net "P52V_HS2_4287_GATE2_RC")
	)
	(via
		(at 105.9942 -47.0408)
		(size 0.6604)
		(drill 0.3302)
		(layers "F.Cu" "B.Cu")
		(net "P52V_HS2_GATE2_R1")
	)
	(segment
		(start 107.188 -43.96105)
		(end 107.188 -44.40301)
		(width 0.4572)
		(layer "B.Cu")
		(net "P52V_HS2_GATE2_R1")
	)
	(segment
		(start 107.188 -44.40301)
		(end 106.934 -44.65701)
		(width 0.508)
		(layer "B.Cu")
		(net "P52V_HS2_GATE2_R1")
	)
	(segment
		(start 106.934 -46.101)
		(end 105.9942 -47.0408)
		(width 0.508)
		(layer "B.Cu")
		(net "P52V_HS2_GATE2_R1")
	)
	(segment
		(start 106.934 -45.7454)
		(end 106.934 -46.101)
		(width 0.508)
		(layer "B.Cu")
		(net "P52V_HS2_GATE2_R1")
	)
	(segment
		(start 106.934 -44.65701)
		(end 106.934 -45.7454)
		(width 0.508)
		(layer "B.Cu")
		(net "P52V_HS2_GATE2_R1")
	)
	(segment
		(start 108.7374 -45.4406)
		(end 107.7722 -45.4406)
		(width 0.508)
		(layer "B.Cu")
		(net "P52V_HS2_GATE2_R1")
	)
	(segment
		(start 107.4674 -45.7454)
		(end 106.934 -45.7454)
		(width 0.508)
		(layer "B.Cu")
		(net "P52V_HS2_GATE2_R1")
	)
	(segment
		(start 107.7722 -45.4406)
		(end 107.4674 -45.7454)
		(width 0.508)
		(layer "B.Cu")
		(net "P52V_HS2_GATE2_R1")
	)
	(segment
		(start 143.237458 -39.350188)
		(end 143.33347 -39.4462)
		(width 0.4572)
		(layer "F.Cu")
		(net "P52V_HS2_4287_S2P")
	)
	(segment
		(start 143.237458 -38.1762)
		(end 143.237458 -39.350188)
		(width 0.4572)
		(layer "F.Cu")
		(net "P52V_HS2_4287_S2P")
	)
	(segment
		(start 143.491458 -37.9222)
		(end 143.237458 -38.1762)
		(width 0.4572)
		(layer "F.Cu")
		(net "P52V_HS2_4287_S2P")
	)
	(segment
		(start 143.33347 -39.4462)
		(end 143.33347 -40.839136)
		(width 0.4572)
		(layer "F.Cu")
		(net "P52V_HS2_4287_S2P")
	)
	(segment
		(start 144.38122 -37.9222)
		(end 143.491458 -37.9222)
		(width 0.4572)
		(layer "F.Cu")
		(net "P52V_HS2_4287_S2P")
	)
	(via
		(at 143.33347 -40.839136)
		(size 0.762)
		(drill 0.254)
		(layers "F.Cu" "B.Cu")
		(net "P52V_HS2_4287_S2P")
	)
	(segment
		(start 149.996652 -72.803258)
		(end 150.222204 -72.803258)
		(width 0.254)
		(layer "B.Cu")
		(net "P52V_HS2_4287_S2P")
	)
	(segment
		(start 150.222204 -72.803258)
		(end 150.273004 -72.854058)
		(width 0.254)
		(layer "B.Cu")
		(net "P52V_HS2_4287_S2P")
	)
	(segment
		(start 138.564112 -76.454762)
		(end 141.061694 -78.952344)
		(width 0.4572)
		(layer "B.Cu")
		(net "P52V_HS2_4287_S2P")
	)
	(segment
		(start 142.553436 -38.462204)
		(end 141.59992 -38.462204)
		(width 0.4572)
		(layer "B.Cu")
		(net "P52V_HS2_4287_S2P")
	)
	(segment
		(start 143.33347 -40.839136)
		(end 143.22679 -40.732456)
		(width 0.4572)
		(layer "B.Cu")
		(net "P52V_HS2_4287_S2P")
	)
	(segment
		(start 150.273004 -72.854058)
		(end 150.672292 -72.854058)
		(width 0.254)
		(layer "B.Cu")
		(net "P52V_HS2_4287_S2P")
	)
	(segment
		(start 138.564112 -41.498012)
		(end 138.564112 -76.454762)
		(width 0.4572)
		(layer "B.Cu")
		(net "P52V_HS2_4287_S2P")
	)
	(segment
		(start 146.858228 -78.952344)
		(end 148.347938 -77.462634)
		(width 0.4572)
		(layer "B.Cu")
		(net "P52V_HS2_4287_S2P")
	)
	(segment
		(start 141.59992 -38.462204)
		(end 138.564112 -41.498012)
		(width 0.4572)
		(layer "B.Cu")
		(net "P52V_HS2_4287_S2P")
	)
	(segment
		(start 143.22679 -40.732456)
		(end 143.22679 -39.135558)
		(width 0.4572)
		(layer "B.Cu")
		(net "P52V_HS2_4287_S2P")
	)
	(segment
		(start 148.347938 -77.462634)
		(end 148.347938 -74.588116)
		(width 0.4572)
		(layer "B.Cu")
		(net "P52V_HS2_4287_S2P")
	)
	(segment
		(start 143.22679 -39.135558)
		(end 142.553436 -38.462204)
		(width 0.4572)
		(layer "B.Cu")
		(net "P52V_HS2_4287_S2P")
	)
	(segment
		(start 148.347938 -74.588116)
		(end 149.319234 -73.61682)
		(width 0.4572)
		(layer "B.Cu")
		(net "P52V_HS2_4287_S2P")
	)
	(segment
		(start 149.319234 -73.480676)
		(end 149.996652 -72.803258)
		(width 0.254)
		(layer "B.Cu")
		(net "P52V_HS2_4287_S2P")
	)
	(segment
		(start 141.061694 -78.952344)
		(end 146.858228 -78.952344)
		(width 0.4572)
		(layer "B.Cu")
		(net "P52V_HS2_4287_S2P")
	)
	(segment
		(start 149.319234 -73.61682)
		(end 149.319234 -73.480676)
		(width 0.254)
		(layer "B.Cu")
		(net "P52V_HS2_4287_S2P")
	)
	(via
		(at 146.763232 -70.63359)
		(size 0.6604)
		(drill 0.3302)
		(layers "F.Cu" "B.Cu")
		(net "P52V_HS2_4287_GATE_R")
	)
	(via
		(at 109.374432 -53.692806)
		(size 0.508)
		(drill 0.254)
		(layers "F.Cu" "B.Cu")
		(net "P52V_HS2_4287_GATE_R")
	)
	(via
		(at 144.892522 -76.886308)
		(size 0.508)
		(drill 0.254)
		(layers "F.Cu" "B.Cu")
		(net "P52V_HS2_4287_GATE_R")
	)
	(segment
		(start 110.2614 -54.579774)
		(end 110.2614 -55.22595)
		(width 0.508)
		(layer "B.Cu")
		(net "P52V_HS2_4287_GATE_R")
	)
	(segment
		(start 147.746466 -70.63359)
		(end 150.026116 -68.35394)
		(width 0.2794)
		(layer "B.Cu")
		(net "P52V_HS2_4287_GATE_R")
	)
	(segment
		(start 108.66755 -54.46395)
		(end 108.7374 -54.5338)
		(width 0.508)
		(layer "B.Cu")
		(net "P52V_HS2_4287_GATE_R")
	)
	(segment
		(start 106.85145 -54.1274)
		(end 106.172 -54.1274)
		(width 0.508)
		(layer "B.Cu")
		(net "P52V_HS2_4287_GATE_R")
	)
	(segment
		(start 106.0704 -53.086)
		(end 106.0704 -54.229)
		(width 0.508)
		(layer "B.Cu")
		(net "P52V_HS2_4287_GATE_R")
	)
	(segment
		(start 109.374432 -53.692806)
		(end 110.2614 -54.579774)
		(width 0.508)
		(layer "B.Cu")
		(net "P52V_HS2_4287_GATE_R")
	)
	(segment
		(start 106.045 -53.0606)
		(end 106.0704 -53.086)
		(width 0.508)
		(layer "B.Cu")
		(net "P52V_HS2_4287_GATE_R")
	)
	(segment
		(start 145.76298 -70.63359)
		(end 146.763232 -70.63359)
		(width 0.508)
		(layer "B.Cu")
		(net "P52V_HS2_4287_GATE_R")
	)
	(segment
		(start 143.272764 -74.935334)
		(end 143.272764 -73.123806)
		(width 0.508)
		(layer "B.Cu")
		(net "P52V_HS2_4287_GATE_R")
	)
	(segment
		(start 106.0704 -54.229)
		(end 106.045 -54.2544)
		(width 0.17272)
		(layer "B.Cu")
		(net "P52V_HS2_4287_GATE_R")
	)
	(segment
		(start 146.763232 -70.63359)
		(end 147.746466 -70.63359)
		(width 0.2794)
		(layer "B.Cu")
		(net "P52V_HS2_4287_GATE_R")
	)
	(segment
		(start 106.172 -54.1274)
		(end 106.0704 -54.229)
		(width 0.508)
		(layer "B.Cu")
		(net "P52V_HS2_4287_GATE_R")
	)
	(segment
		(start 143.272764 -73.123806)
		(end 145.76298 -70.63359)
		(width 0.508)
		(layer "B.Cu")
		(net "P52V_HS2_4287_GATE_R")
	)
	(segment
		(start 150.026116 -68.35394)
		(end 150.697692 -68.35394)
		(width 0.2794)
		(layer "B.Cu")
		(net "P52V_HS2_4287_GATE_R")
	)
	(segment
		(start 144.892522 -76.555092)
		(end 143.272764 -74.935334)
		(width 0.508)
		(layer "B.Cu")
		(net "P52V_HS2_4287_GATE_R")
	)
	(segment
		(start 107.188 -54.46395)
		(end 108.66755 -54.46395)
		(width 0.4572)
		(layer "B.Cu")
		(net "P52V_HS2_4287_GATE_R")
	)
	(segment
		(start 109.42955 -55.22595)
		(end 108.7374 -54.5338)
		(width 0.508)
		(layer "B.Cu")
		(net "P52V_HS2_4287_GATE_R")
	)
	(segment
		(start 144.892522 -76.886308)
		(end 144.892522 -76.555092)
		(width 0.508)
		(layer "B.Cu")
		(net "P52V_HS2_4287_GATE_R")
	)
	(segment
		(start 110.2614 -55.22595)
		(end 109.42955 -55.22595)
		(width 0.508)
		(layer "B.Cu")
		(net "P52V_HS2_4287_GATE_R")
	)
	(segment
		(start 107.188 -54.46395)
		(end 106.85145 -54.1274)
		(width 0.4572)
		(layer "B.Cu")
		(net "P52V_HS2_4287_GATE_R")
	)
	(segment
		(start 109.846364 -53.220874)
		(end 109.374432 -53.692806)
		(width 0.762)
		(layer "In2.Cu")
		(net "P52V_HS2_4287_GATE_R")
	)
	(segment
		(start 126.994158 -86.50224)
		(end 120.549162 -80.057244)
		(width 0.762)
		(layer "In2.Cu")
		(net "P52V_HS2_4287_GATE_R")
	)
	(segment
		(start 135.977122 -86.50224)
		(end 126.994158 -86.50224)
		(width 0.762)
		(layer "In2.Cu")
		(net "P52V_HS2_4287_GATE_R")
	)
	(segment
		(start 144.892522 -77.58684)
		(end 135.977122 -86.50224)
		(width 0.762)
		(layer "In2.Cu")
		(net "P52V_HS2_4287_GATE_R")
	)
	(segment
		(start 120.549162 -54.386988)
		(end 119.383048 -53.220874)
		(width 0.762)
		(layer "In2.Cu")
		(net "P52V_HS2_4287_GATE_R")
	)
	(segment
		(start 120.549162 -80.057244)
		(end 120.549162 -54.386988)
		(width 0.762)
		(layer "In2.Cu")
		(net "P52V_HS2_4287_GATE_R")
	)
	(segment
		(start 119.383048 -53.220874)
		(end 109.846364 -53.220874)
		(width 0.762)
		(layer "In2.Cu")
		(net "P52V_HS2_4287_GATE_R")
	)
	(segment
		(start 144.892522 -76.886308)
		(end 144.892522 -77.58684)
		(width 0.762)
		(layer "In2.Cu")
		(net "P52V_HS2_4287_GATE_R")
	)
	(segment
		(start 143.33347 -73.175876)
		(end 143.33347 -73.025)
		(width 0.4572)
		(layer "F.Cu")
		(net "P52V_HS2_4287_S1P")
	)
	(segment
		(start 145.029428 -73.56475)
		(end 143.722344 -73.56475)
		(width 0.4572)
		(layer "F.Cu")
		(net "P52V_HS2_4287_S1P")
	)
	(segment
		(start 144.38122 -71.755)
		(end 143.481806 -71.755)
		(width 0.4572)
		(layer "F.Cu")
		(net "P52V_HS2_4287_S1P")
	)
	(segment
		(start 143.481806 -71.755)
		(end 143.227806 -72.009)
		(width 0.4572)
		(layer "F.Cu")
		(net "P52V_HS2_4287_S1P")
	)
	(segment
		(start 143.227806 -72.919336)
		(end 143.33347 -73.025)
		(width 0.4572)
		(layer "F.Cu")
		(net "P52V_HS2_4287_S1P")
	)
	(segment
		(start 143.227806 -72.009)
		(end 143.227806 -72.919336)
		(width 0.4572)
		(layer "F.Cu")
		(net "P52V_HS2_4287_S1P")
	)
	(segment
		(start 143.722344 -73.56475)
		(end 143.33347 -73.175876)
		(width 0.4572)
		(layer "F.Cu")
		(net "P52V_HS2_4287_S1P")
	)
	(segment
		(start 145.171668 -73.42251)
		(end 145.029428 -73.56475)
		(width 0.4572)
		(layer "F.Cu")
		(net "P52V_HS2_4287_S1P")
	)
	(via
		(at 145.171668 -73.42251)
		(size 0.508)
		(drill 0.254)
		(layers "F.Cu" "B.Cu")
		(net "P52V_HS2_4287_S1P")
	)
	(segment
		(start 150.190454 -71.2724)
		(end 150.271988 -71.353934)
		(width 0.254)
		(layer "B.Cu")
		(net "P52V_HS2_4287_S1P")
	)
	(segment
		(start 148.862288 -71.2724)
		(end 150.190454 -71.2724)
		(width 0.254)
		(layer "B.Cu")
		(net "P52V_HS2_4287_S1P")
	)
	(segment
		(start 145.171668 -73.42251)
		(end 146.328892 -72.265286)
		(width 0.4572)
		(layer "B.Cu")
		(net "P52V_HS2_4287_S1P")
	)
	(segment
		(start 148.56079 -71.573898)
		(end 148.862288 -71.2724)
		(width 0.254)
		(layer "B.Cu")
		(net "P52V_HS2_4287_S1P")
	)
	(segment
		(start 148.01215 -72.265286)
		(end 148.56079 -71.717154)
		(width 0.4572)
		(layer "B.Cu")
		(net "P52V_HS2_4287_S1P")
	)
	(segment
		(start 146.328892 -72.265286)
		(end 148.01215 -72.265286)
		(width 0.4572)
		(layer "B.Cu")
		(net "P52V_HS2_4287_S1P")
	)
	(segment
		(start 148.56079 -71.717154)
		(end 148.56079 -71.573898)
		(width 0.254)
		(layer "B.Cu")
		(net "P52V_HS2_4287_S1P")
	)
	(segment
		(start 150.271988 -71.353934)
		(end 150.697692 -71.353934)
		(width 0.254)
		(layer "B.Cu")
		(net "P52V_HS2_4287_S1P")
	)
	(via
		(at 160.193736 -68.326)
		(size 0.6604)
		(drill 0.3302)
		(layers "F.Cu" "B.Cu")
		(net "SMB_P52V_PDB_SCL_R4")
	)
	(segment
		(start 158.90367 -68.854066)
		(end 157.49778 -68.854066)
		(width 0.17272)
		(layer "B.Cu")
		(net "SMB_P52V_PDB_SCL_R4")
	)
	(segment
		(start 159.431736 -68.326)
		(end 158.90367 -68.854066)
		(width 0.17272)
		(layer "B.Cu")
		(net "SMB_P52V_PDB_SCL_R4")
	)
	(segment
		(start 160.193736 -68.326)
		(end 159.431736 -68.326)
		(width 0.17272)
		(layer "B.Cu")
		(net "SMB_P52V_PDB_SCL_R4")
	)
	(segment
		(start 161.317686 -68.326)
		(end 160.193736 -68.326)
		(width 0.17272)
		(layer "B.Cu")
		(net "SMB_P52V_PDB_SCL_R4")
	)
	(segment
		(start 175.77435 -64.897)
		(end 175.77435 -65.196974)
		(width 0.17272)
		(layer "F.Cu")
		(net "P52V_HS2_UVLO_EN")
	)
	(segment
		(start 175.179736 -58.613548)
		(end 175.179736 -63.286386)
		(width 0.17272)
		(layer "F.Cu")
		(net "P52V_HS2_UVLO_EN")
	)
	(segment
		(start 175.77435 -64.897)
		(end 175.77435 -63.881)
		(width 0.17272)
		(layer "F.Cu")
		(net "P52V_HS2_UVLO_EN")
	)
	(segment
		(start 175.77435 -65.196974)
		(end 174.99203 -65.979294)
		(width 0.17272)
		(layer "F.Cu")
		(net "P52V_HS2_UVLO_EN")
	)
	(segment
		(start 175.179736 -63.286386)
		(end 175.77435 -63.881)
		(width 0.17272)
		(layer "F.Cu")
		(net "P52V_HS2_UVLO_EN")
	)
	(via
		(at 175.179736 -58.613548)
		(size 0.508)
		(drill 0.254)
		(layers "F.Cu" "B.Cu")
		(net "P52V_HS2_UVLO_EN")
	)
	(via
		(at 174.99203 -65.979294)
		(size 0.508)
		(drill 0.254)
		(layers "F.Cu" "B.Cu")
		(net "P52V_HS2_UVLO_EN")
	)
	(via
		(at 152.62225 -75.167998)
		(size 0.508)
		(drill 0.254)
		(layers "F.Cu" "B.Cu")
		(net "P52V_HS2_UVLO_EN")
	)
	(segment
		(start 152.62225 -74.373232)
		(end 153.347674 -73.647808)
		(width 0.17272)
		(layer "B.Cu")
		(net "P52V_HS2_UVLO_EN")
	)
	(segment
		(start 174.99203 -65.979294)
		(end 175.215296 -66.20256)
		(width 0.17272)
		(layer "B.Cu")
		(net "P52V_HS2_UVLO_EN")
	)
	(segment
		(start 153.347674 -73.647808)
		(end 153.347674 -73.504044)
		(width 0.17272)
		(layer "B.Cu")
		(net "P52V_HS2_UVLO_EN")
	)
	(segment
		(start 175.215296 -66.20256)
		(end 175.215296 -67.16268)
		(width 0.17272)
		(layer "B.Cu")
		(net "P52V_HS2_UVLO_EN")
	)
	(segment
		(start 175.179736 -56.95696)
		(end 175.179736 -58.613548)
		(width 0.17272)
		(layer "B.Cu")
		(net "P52V_HS2_UVLO_EN")
	)
	(segment
		(start 152.62225 -75.167998)
		(end 152.62225 -74.373232)
		(width 0.17272)
		(layer "B.Cu")
		(net "P52V_HS2_UVLO_EN")
	)
	(segment
		(start 152.62225 -75.167998)
		(end 151.76754 -76.022708)
		(width 0.12954)
		(layer "In2.Cu")
		(net "P52V_HS2_UVLO_EN")
	)
	(segment
		(start 173.734476 -67.236848)
		(end 174.99203 -65.979294)
		(width 0.12954)
		(layer "In2.Cu")
		(net "P52V_HS2_UVLO_EN")
	)
	(segment
		(start 151.76754 -78.077568)
		(end 152.471882 -78.78191)
		(width 0.12954)
		(layer "In2.Cu")
		(net "P52V_HS2_UVLO_EN")
	)
	(segment
		(start 172.7962 -70.2056)
		(end 173.734476 -69.267324)
		(width 0.12954)
		(layer "In2.Cu")
		(net "P52V_HS2_UVLO_EN")
	)
	(segment
		(start 166.567866 -70.2056)
		(end 172.7962 -70.2056)
		(width 0.12954)
		(layer "In2.Cu")
		(net "P52V_HS2_UVLO_EN")
	)
	(segment
		(start 152.471882 -78.78191)
		(end 155.298648 -78.78191)
		(width 0.12954)
		(layer "In2.Cu")
		(net "P52V_HS2_UVLO_EN")
	)
	(segment
		(start 155.298648 -78.78191)
		(end 157.469078 -76.61148)
		(width 0.12954)
		(layer "In2.Cu")
		(net "P52V_HS2_UVLO_EN")
	)
	(segment
		(start 160.161986 -76.61148)
		(end 166.567866 -70.2056)
		(width 0.12954)
		(layer "In2.Cu")
		(net "P52V_HS2_UVLO_EN")
	)
	(segment
		(start 157.469078 -76.61148)
		(end 160.161986 -76.61148)
		(width 0.12954)
		(layer "In2.Cu")
		(net "P52V_HS2_UVLO_EN")
	)
	(segment
		(start 151.76754 -76.022708)
		(end 151.76754 -78.077568)
		(width 0.12954)
		(layer "In2.Cu")
		(net "P52V_HS2_UVLO_EN")
	)
	(segment
		(start 173.734476 -69.267324)
		(end 173.734476 -67.236848)
		(width 0.12954)
		(layer "In2.Cu")
		(net "P52V_HS2_UVLO_EN")
	)
	(segment
		(start 142.57782 -34.3662)
		(end 142.95882 -34.7472)
		(width 0.4572)
		(layer "F.Cu")
		(net "P52V_HS2_4287_ADC_N")
	)
	(segment
		(start 141.53642 -34.3662)
		(end 142.57782 -34.3662)
		(width 0.4572)
		(layer "F.Cu")
		(net "P52V_HS2_4287_ADC_N")
	)
	(segment
		(start 142.924784 -69.469)
		(end 142.416784 -69.977)
		(width 0.4572)
		(layer "F.Cu")
		(net "P52V_HS2_4287_ADC_N")
	)
	(segment
		(start 142.416784 -69.977)
		(end 141.53642 -69.977)
		(width 0.4572)
		(layer "F.Cu")
		(net "P52V_HS2_4287_ADC_N")
	)
	(segment
		(start 142.95882 -69.469)
		(end 142.924784 -69.469)
		(width 0.4572)
		(layer "F.Cu")
		(net "P52V_HS2_4287_ADC_N")
	)
	(via
		(at 149.935692 -70.353936)
		(size 0.762)
		(drill 0.254)
		(layers "F.Cu" "B.Cu")
		(net "P52V_HS2_4287_ADC_N")
	)
	(via
		(at 142.95882 -34.7472)
		(size 0.508)
		(drill 0.254)
		(layers "F.Cu" "B.Cu")
		(net "P52V_HS2_4287_ADC_N")
	)
	(via
		(at 142.95882 -69.469)
		(size 0.508)
		(drill 0.254)
		(layers "F.Cu" "B.Cu")
		(net "P52V_HS2_4287_ADC_N")
	)
	(segment
		(start 142.95882 -69.469)
		(end 143.087344 -69.597524)
		(width 0.4572)
		(layer "B.Cu")
		(net "P52V_HS2_4287_ADC_N")
	)
	(segment
		(start 145.19783 -68.106036)
		(end 145.19783 -66.426588)
		(width 0.4572)
		(layer "B.Cu")
		(net "P52V_HS2_4287_ADC_N")
	)
	(segment
		(start 145.587466 -66.036952)
		(end 145.587466 -35.630104)
		(width 0.4572)
		(layer "B.Cu")
		(net "P52V_HS2_4287_ADC_N")
	)
	(segment
		(start 144.551654 -34.594292)
		(end 143.111728 -34.594292)
		(width 0.4572)
		(layer "B.Cu")
		(net "P52V_HS2_4287_ADC_N")
	)
	(segment
		(start 145.19783 -66.426588)
		(end 145.587466 -66.036952)
		(width 0.4572)
		(layer "B.Cu")
		(net "P52V_HS2_4287_ADC_N")
	)
	(segment
		(start 143.706342 -69.597524)
		(end 145.19783 -68.106036)
		(width 0.4572)
		(layer "B.Cu")
		(net "P52V_HS2_4287_ADC_N")
	)
	(segment
		(start 145.587466 -35.630104)
		(end 144.551654 -34.594292)
		(width 0.4572)
		(layer "B.Cu")
		(net "P52V_HS2_4287_ADC_N")
	)
	(segment
		(start 143.087344 -69.597524)
		(end 143.706342 -69.597524)
		(width 0.4572)
		(layer "B.Cu")
		(net "P52V_HS2_4287_ADC_N")
	)
	(segment
		(start 143.111728 -34.594292)
		(end 142.95882 -34.7472)
		(width 0.4572)
		(layer "B.Cu")
		(net "P52V_HS2_4287_ADC_N")
	)
	(segment
		(start 150.697692 -70.353936)
		(end 149.935692 -70.353936)
		(width 0.254)
		(layer "B.Cu")
		(net "P52V_HS2_4287_ADC_N")
	)
	(segment
		(start 149.935692 -70.353936)
		(end 149.484842 -70.804786)
		(width 0.4572)
		(layer "In2.Cu")
		(net "P52V_HS2_4287_ADC_N")
	)
	(segment
		(start 144.91716 -69.555868)
		(end 143.045688 -69.555868)
		(width 0.4572)
		(layer "In2.Cu")
		(net "P52V_HS2_4287_ADC_N")
	)
	(segment
		(start 146.557746 -71.196454)
		(end 144.91716 -69.555868)
		(width 0.4572)
		(layer "In2.Cu")
		(net "P52V_HS2_4287_ADC_N")
	)
	(segment
		(start 148.526246 -70.804786)
		(end 148.134578 -71.196454)
		(width 0.4572)
		(layer "In2.Cu")
		(net "P52V_HS2_4287_ADC_N")
	)
	(segment
		(start 148.134578 -71.196454)
		(end 146.557746 -71.196454)
		(width 0.4572)
		(layer "In2.Cu")
		(net "P52V_HS2_4287_ADC_N")
	)
	(segment
		(start 143.045688 -69.555868)
		(end 142.95882 -69.469)
		(width 0.4572)
		(layer "In2.Cu")
		(net "P52V_HS2_4287_ADC_N")
	)
	(segment
		(start 149.484842 -70.804786)
		(end 148.526246 -70.804786)
		(width 0.4572)
		(layer "In2.Cu")
		(net "P52V_HS2_4287_ADC_N")
	)
	(segment
		(start 141.53642 -37.9222)
		(end 142.399004 -37.9222)
		(width 0.4572)
		(layer "F.Cu")
		(net "P52V_HS2_4287_S2N")
	)
	(segment
		(start 142.653004 -39.326566)
		(end 142.53337 -39.4462)
		(width 0.4572)
		(layer "F.Cu")
		(net "P52V_HS2_4287_S2N")
	)
	(segment
		(start 142.53337 -39.4462)
		(end 142.53337 -40.839136)
		(width 0.4572)
		(layer "F.Cu")
		(net "P52V_HS2_4287_S2N")
	)
	(segment
		(start 142.399004 -37.9222)
		(end 142.653004 -38.1762)
		(width 0.4572)
		(layer "F.Cu")
		(net "P52V_HS2_4287_S2N")
	)
	(segment
		(start 142.653004 -38.1762)
		(end 142.653004 -39.326566)
		(width 0.4572)
		(layer "F.Cu")
		(net "P52V_HS2_4287_S2N")
	)
	(via
		(at 142.53337 -40.839136)
		(size 0.508)
		(drill 0.254)
		(layers "F.Cu" "B.Cu")
		(net "P52V_HS2_4287_S2N")
	)
	(segment
		(start 139.148312 -41.740328)
		(end 139.148312 -76.212446)
		(width 0.4572)
		(layer "B.Cu")
		(net "P52V_HS2_4287_S2N")
	)
	(segment
		(start 142.53337 -40.839136)
		(end 142.64259 -40.729916)
		(width 0.4572)
		(layer "B.Cu")
		(net "P52V_HS2_4287_S2N")
	)
	(segment
		(start 146.616166 -78.368144)
		(end 147.763738 -77.220572)
		(width 0.4572)
		(layer "B.Cu")
		(net "P52V_HS2_4287_S2N")
	)
	(segment
		(start 142.64259 -40.729916)
		(end 142.64259 -39.377874)
		(width 0.4572)
		(layer "B.Cu")
		(net "P52V_HS2_4287_S2N")
	)
	(segment
		(start 149.838918 -72.399144)
		(end 150.231856 -72.399144)
		(width 0.254)
		(layer "B.Cu")
		(net "P52V_HS2_4287_S2N")
	)
	(segment
		(start 141.30401 -78.368144)
		(end 146.616166 -78.368144)
		(width 0.4572)
		(layer "B.Cu")
		(net "P52V_HS2_4287_S2N")
	)
	(segment
		(start 147.763738 -74.3458)
		(end 148.905976 -73.203562)
		(width 0.4572)
		(layer "B.Cu")
		(net "P52V_HS2_4287_S2N")
	)
	(segment
		(start 150.231856 -72.399144)
		(end 150.277068 -72.353932)
		(width 0.254)
		(layer "B.Cu")
		(net "P52V_HS2_4287_S2N")
	)
	(segment
		(start 142.31112 -39.046404)
		(end 141.842236 -39.046404)
		(width 0.4572)
		(layer "B.Cu")
		(net "P52V_HS2_4287_S2N")
	)
	(segment
		(start 149.0345 -73.203562)
		(end 149.838918 -72.399144)
		(width 0.254)
		(layer "B.Cu")
		(net "P52V_HS2_4287_S2N")
	)
	(segment
		(start 147.763738 -77.220572)
		(end 147.763738 -74.3458)
		(width 0.4572)
		(layer "B.Cu")
		(net "P52V_HS2_4287_S2N")
	)
	(segment
		(start 150.277068 -72.353932)
		(end 150.697692 -72.353932)
		(width 0.254)
		(layer "B.Cu")
		(net "P52V_HS2_4287_S2N")
	)
	(segment
		(start 141.842236 -39.046404)
		(end 139.148312 -41.740328)
		(width 0.4572)
		(layer "B.Cu")
		(net "P52V_HS2_4287_S2N")
	)
	(segment
		(start 148.905976 -73.203562)
		(end 149.0345 -73.203562)
		(width 0.254)
		(layer "B.Cu")
		(net "P52V_HS2_4287_S2N")
	)
	(segment
		(start 139.148312 -76.212446)
		(end 141.30401 -78.368144)
		(width 0.4572)
		(layer "B.Cu")
		(net "P52V_HS2_4287_S2N")
	)
	(segment
		(start 142.64259 -39.377874)
		(end 142.31112 -39.046404)
		(width 0.4572)
		(layer "B.Cu")
		(net "P52V_HS2_4287_S2N")
	)
	(segment
		(start 145.045938 -74.289666)
		(end 143.45412 -74.289666)
		(width 0.4572)
		(layer "F.Cu")
		(net "P52V_HS2_4287_S1N")
	)
	(segment
		(start 145.11655 -74.360278)
		(end 145.045938 -74.289666)
		(width 0.4572)
		(layer "F.Cu")
		(net "P52V_HS2_4287_S1N")
	)
	(segment
		(start 142.386304 -71.755)
		(end 142.640304 -72.009)
		(width 0.4572)
		(layer "F.Cu")
		(net "P52V_HS2_4287_S1N")
	)
	(segment
		(start 142.640304 -72.009)
		(end 142.640304 -72.918066)
		(width 0.4572)
		(layer "F.Cu")
		(net "P52V_HS2_4287_S1N")
	)
	(segment
		(start 143.45412 -74.289666)
		(end 142.53337 -73.368916)
		(width 0.4572)
		(layer "F.Cu")
		(net "P52V_HS2_4287_S1N")
	)
	(segment
		(start 141.53642 -71.755)
		(end 142.386304 -71.755)
		(width 0.4572)
		(layer "F.Cu")
		(net "P52V_HS2_4287_S1N")
	)
	(segment
		(start 142.640304 -72.918066)
		(end 142.53337 -73.025)
		(width 0.4572)
		(layer "F.Cu")
		(net "P52V_HS2_4287_S1N")
	)
	(segment
		(start 142.53337 -73.368916)
		(end 142.53337 -73.025)
		(width 0.4572)
		(layer "F.Cu")
		(net "P52V_HS2_4287_S1N")
	)
	(via
		(at 145.11655 -74.360278)
		(size 0.762)
		(drill 0.254)
		(layers "F.Cu" "B.Cu")
		(net "P52V_HS2_4287_S1N")
	)
	(segment
		(start 145.11655 -74.360278)
		(end 144.935194 -74.360278)
		(width 0.4572)
		(layer "B.Cu")
		(net "P52V_HS2_4287_S1N")
	)
	(segment
		(start 144.360138 -73.785222)
		(end 144.360138 -73.146666)
		(width 0.4572)
		(layer "B.Cu")
		(net "P52V_HS2_4287_S1N")
	)
	(segment
		(start 150.240746 -70.8914)
		(end 150.278084 -70.854062)
		(width 0.254)
		(layer "B.Cu")
		(net "P52V_HS2_4287_S1N")
	)
	(segment
		(start 144.935194 -74.360278)
		(end 144.360138 -73.785222)
		(width 0.4572)
		(layer "B.Cu")
		(net "P52V_HS2_4287_S1N")
	)
	(segment
		(start 148.6789 -70.8914)
		(end 150.240746 -70.8914)
		(width 0.254)
		(layer "B.Cu")
		(net "P52V_HS2_4287_S1N")
	)
	(segment
		(start 148.315172 -71.255128)
		(end 148.6789 -70.8914)
		(width 0.254)
		(layer "B.Cu")
		(net "P52V_HS2_4287_S1N")
	)
	(segment
		(start 147.770088 -71.681086)
		(end 148.196046 -71.255128)
		(width 0.4572)
		(layer "B.Cu")
		(net "P52V_HS2_4287_S1N")
	)
	(segment
		(start 144.360138 -73.146666)
		(end 145.825718 -71.681086)
		(width 0.4572)
		(layer "B.Cu")
		(net "P52V_HS2_4287_S1N")
	)
	(segment
		(start 148.196046 -71.255128)
		(end 148.315172 -71.255128)
		(width 0.254)
		(layer "B.Cu")
		(net "P52V_HS2_4287_S1N")
	)
	(segment
		(start 150.278084 -70.854062)
		(end 150.697692 -70.854062)
		(width 0.254)
		(layer "B.Cu")
		(net "P52V_HS2_4287_S1N")
	)
	(segment
		(start 145.825718 -71.681086)
		(end 147.770088 -71.681086)
		(width 0.4572)
		(layer "B.Cu")
		(net "P52V_HS2_4287_S1N")
	)
	(via
		(at 108.782358 -42.432224)
		(size 0.508)
		(drill 0.254)
		(layers "F.Cu" "B.Cu")
		(net "P52V_HS2_4287_GATE2_R")
	)
	(via
		(at 147.716748 -69.08927)
		(size 0.6604)
		(drill 0.3302)
		(layers "F.Cu" "B.Cu")
		(net "P52V_HS2_4287_GATE2_R")
	)
	(via
		(at 143.533114 -76.858368)
		(size 0.508)
		(drill 0.254)
		(layers "F.Cu" "B.Cu")
		(net "P52V_HS2_4287_GATE2_R")
	)
	(segment
		(start 109.42955 -43.94835)
		(end 110.2614 -43.94835)
		(width 0.508)
		(layer "B.Cu")
		(net "P52V_HS2_4287_GATE2_R")
	)
	(segment
		(start 142.248636 -75.57389)
		(end 142.248636 -72.926448)
		(width 0.508)
		(layer "B.Cu")
		(net "P52V_HS2_4287_GATE2_R")
	)
	(segment
		(start 150.697692 -67.854068)
		(end 148.95195 -67.854068)
		(width 0.2794)
		(layer "B.Cu")
		(net "P52V_HS2_4287_GATE2_R")
	)
	(segment
		(start 107.188 -43.16095)
		(end 108.64215 -43.16095)
		(width 0.4572)
		(layer "B.Cu")
		(net "P52V_HS2_4287_GATE2_R")
	)
	(segment
		(start 106.045 -42.0116)
		(end 106.045 -43.0784)
		(width 0.508)
		(layer "B.Cu")
		(net "P52V_HS2_4287_GATE2_R")
	)
	(segment
		(start 148.95195 -67.854068)
		(end 147.716748 -69.08927)
		(width 0.2794)
		(layer "B.Cu")
		(net "P52V_HS2_4287_GATE2_R")
	)
	(segment
		(start 110.2614 -42.939208)
		(end 109.754416 -42.432224)
		(width 0.508)
		(layer "B.Cu")
		(net "P52V_HS2_4287_GATE2_R")
	)
	(segment
		(start 109.754416 -42.432224)
		(end 108.782358 -42.432224)
		(width 0.508)
		(layer "B.Cu")
		(net "P52V_HS2_4287_GATE2_R")
	)
	(segment
		(start 108.64215 -43.16095)
		(end 108.7374 -43.2562)
		(width 0.4572)
		(layer "B.Cu")
		(net "P52V_HS2_4287_GATE2_R")
	)
	(segment
		(start 145.494756 -69.680328)
		(end 147.12569 -69.680328)
		(width 0.508)
		(layer "B.Cu")
		(net "P52V_HS2_4287_GATE2_R")
	)
	(segment
		(start 143.533114 -76.858368)
		(end 142.248636 -75.57389)
		(width 0.508)
		(layer "B.Cu")
		(net "P52V_HS2_4287_GATE2_R")
	)
	(segment
		(start 147.12569 -69.680328)
		(end 147.716748 -69.08927)
		(width 0.508)
		(layer "B.Cu")
		(net "P52V_HS2_4287_GATE2_R")
	)
	(segment
		(start 142.248636 -72.926448)
		(end 145.494756 -69.680328)
		(width 0.508)
		(layer "B.Cu")
		(net "P52V_HS2_4287_GATE2_R")
	)
	(segment
		(start 110.2614 -43.94835)
		(end 110.2614 -42.939208)
		(width 0.508)
		(layer "B.Cu")
		(net "P52V_HS2_4287_GATE2_R")
	)
	(segment
		(start 106.12755 -43.16095)
		(end 107.188 -43.16095)
		(width 0.4572)
		(layer "B.Cu")
		(net "P52V_HS2_4287_GATE2_R")
	)
	(segment
		(start 108.7374 -43.2562)
		(end 109.42955 -43.94835)
		(width 0.508)
		(layer "B.Cu")
		(net "P52V_HS2_4287_GATE2_R")
	)
	(segment
		(start 106.045 -43.0784)
		(end 106.12755 -43.16095)
		(width 0.4572)
		(layer "B.Cu")
		(net "P52V_HS2_4287_GATE2_R")
	)
	(segment
		(start 105.918 -41.8846)
		(end 106.045 -42.0116)
		(width 0.508)
		(layer "B.Cu")
		(net "P52V_HS2_4287_GATE2_R")
	)
	(segment
		(start 135.26008 -85.131402)
		(end 143.533114 -76.858368)
		(width 0.762)
		(layer "In2.Cu")
		(net "P52V_HS2_4287_GATE2_R")
	)
	(segment
		(start 122.03049 -44.537884)
		(end 122.03049 -79.663036)
		(width 0.762)
		(layer "In2.Cu")
		(net "P52V_HS2_4287_GATE2_R")
	)
	(segment
		(start 127.498856 -85.131402)
		(end 135.26008 -85.131402)
		(width 0.762)
		(layer "In2.Cu")
		(net "P52V_HS2_4287_GATE2_R")
	)
	(segment
		(start 109.332014 -41.882568)
		(end 119.375174 -41.882568)
		(width 0.762)
		(layer "In2.Cu")
		(net "P52V_HS2_4287_GATE2_R")
	)
	(segment
		(start 122.03049 -79.663036)
		(end 127.498856 -85.131402)
		(width 0.762)
		(layer "In2.Cu")
		(net "P52V_HS2_4287_GATE2_R")
	)
	(segment
		(start 108.782358 -42.432224)
		(end 109.332014 -41.882568)
		(width 0.762)
		(layer "In2.Cu")
		(net "P52V_HS2_4287_GATE2_R")
	)
	(segment
		(start 119.375174 -41.882568)
		(end 122.03049 -44.537884)
		(width 0.762)
		(layer "In2.Cu")
		(net "P52V_HS2_4287_GATE2_R")
	)
	(segment
		(start 142.991332 -33.8582)
		(end 142.95882 -33.8582)
		(width 0.4572)
		(layer "F.Cu")
		(net "P52V_HS2_4287_ADC_P")
	)
	(segment
		(start 143.499332 -34.3662)
		(end 142.991332 -33.8582)
		(width 0.4572)
		(layer "F.Cu")
		(net "P52V_HS2_4287_ADC_P")
	)
	(segment
		(start 144.38122 -34.3662)
		(end 143.499332 -34.3662)
		(width 0.4572)
		(layer "F.Cu")
		(net "P52V_HS2_4287_ADC_P")
	)
	(segment
		(start 143.33982 -69.977)
		(end 142.95882 -70.358)
		(width 0.4572)
		(layer "F.Cu")
		(net "P52V_HS2_4287_ADC_P")
	)
	(segment
		(start 144.38122 -69.977)
		(end 143.33982 -69.977)
		(width 0.4572)
		(layer "F.Cu")
		(net "P52V_HS2_4287_ADC_P")
	)
	(via
		(at 142.95882 -33.8582)
		(size 0.508)
		(drill 0.254)
		(layers "F.Cu" "B.Cu")
		(net "P52V_HS2_4287_ADC_P")
	)
	(via
		(at 142.95882 -70.358)
		(size 0.508)
		(drill 0.254)
		(layers "F.Cu" "B.Cu")
		(net "P52V_HS2_4287_ADC_P")
	)
	(via
		(at 149.935692 -71.85406)
		(size 0.762)
		(drill 0.254)
		(layers "F.Cu" "B.Cu")
		(net "P52V_HS2_4287_ADC_P")
	)
	(segment
		(start 146.171666 -35.387788)
		(end 144.79397 -34.010092)
		(width 0.4572)
		(layer "B.Cu")
		(net "P52V_HS2_4287_ADC_P")
	)
	(segment
		(start 145.78203 -66.668904)
		(end 146.171666 -66.279268)
		(width 0.4572)
		(layer "B.Cu")
		(net "P52V_HS2_4287_ADC_P")
	)
	(segment
		(start 150.697692 -71.85406)
		(end 149.935692 -71.85406)
		(width 0.254)
		(layer "B.Cu")
		(net "P52V_HS2_4287_ADC_P")
	)
	(segment
		(start 144.79397 -34.010092)
		(end 143.110712 -34.010092)
		(width 0.4572)
		(layer "B.Cu")
		(net "P52V_HS2_4287_ADC_P")
	)
	(segment
		(start 143.938752 -70.19163)
		(end 145.78203 -68.348352)
		(width 0.4572)
		(layer "B.Cu")
		(net "P52V_HS2_4287_ADC_P")
	)
	(segment
		(start 146.171666 -66.279268)
		(end 146.171666 -35.387788)
		(width 0.4572)
		(layer "B.Cu")
		(net "P52V_HS2_4287_ADC_P")
	)
	(segment
		(start 142.95882 -70.358)
		(end 143.12519 -70.19163)
		(width 0.4572)
		(layer "B.Cu")
		(net "P52V_HS2_4287_ADC_P")
	)
	(segment
		(start 143.12519 -70.19163)
		(end 143.938752 -70.19163)
		(width 0.4572)
		(layer "B.Cu")
		(net "P52V_HS2_4287_ADC_P")
	)
	(segment
		(start 145.78203 -68.348352)
		(end 145.78203 -66.668904)
		(width 0.4572)
		(layer "B.Cu")
		(net "P52V_HS2_4287_ADC_P")
	)
	(segment
		(start 143.110712 -34.010092)
		(end 142.95882 -33.8582)
		(width 0.4572)
		(layer "B.Cu")
		(net "P52V_HS2_4287_ADC_P")
	)
	(segment
		(start 148.768308 -71.388986)
		(end 148.37664 -71.780654)
		(width 0.4572)
		(layer "In2.Cu")
		(net "P52V_HS2_4287_ADC_P")
	)
	(segment
		(start 144.675098 -70.140068)
		(end 143.176752 -70.140068)
		(width 0.4572)
		(layer "In2.Cu")
		(net "P52V_HS2_4287_ADC_P")
	)
	(segment
		(start 148.37664 -71.780654)
		(end 146.315684 -71.780654)
		(width 0.4572)
		(layer "In2.Cu")
		(net "P52V_HS2_4287_ADC_P")
	)
	(segment
		(start 149.470618 -71.388986)
		(end 148.768308 -71.388986)
		(width 0.4572)
		(layer "In2.Cu")
		(net "P52V_HS2_4287_ADC_P")
	)
	(segment
		(start 149.935692 -71.85406)
		(end 149.470618 -71.388986)
		(width 0.4572)
		(layer "In2.Cu")
		(net "P52V_HS2_4287_ADC_P")
	)
	(segment
		(start 143.176752 -70.140068)
		(end 142.95882 -70.358)
		(width 0.4572)
		(layer "In2.Cu")
		(net "P52V_HS2_4287_ADC_P")
	)
	(segment
		(start 146.315684 -71.780654)
		(end 144.675098 -70.140068)
		(width 0.4572)
		(layer "In2.Cu")
		(net "P52V_HS2_4287_ADC_P")
	)
	(segment
		(start 111.2266 -44.2468)
		(end 111.7854 -44.2468)
		(width 0.17272)
		(layer "F.Cu")
		(net "P52V_HS2_GATE4")
	)
	(segment
		(start 111.7854 -44.2468)
		(end 112.6744 -43.3578)
		(width 0.17272)
		(layer "F.Cu")
		(net "P52V_HS2_GATE4")
	)
	(segment
		(start 112.988852 -43.3578)
		(end 112.6744 -43.3578)
		(width 0.17272)
		(layer "F.Cu")
		(net "P52V_HS2_GATE4")
	)
	(segment
		(start 110.871 -44.6024)
		(end 111.2266 -44.2468)
		(width 0.17272)
		(layer "F.Cu")
		(net "P52V_HS2_GATE4")
	)
	(via
		(at 110.871 -44.6024)
		(size 0.762)
		(drill 0.381)
		(layers "F.Cu" "B.Cu")
		(net "P52V_HS2_GATE4")
	)
	(segment
		(start 112.988852 -65.913)
		(end 111.4552 -65.913)
		(width 0.17272)
		(layer "F.Cu")
		(net "P52V_HS2_GATE2")
	)
	(via
		(at 111.4552 -65.913)
		(size 0.762)
		(drill 0.381)
		(layers "F.Cu" "B.Cu")
		(net "P52V_HS2_GATE2")
	)
	(segment
		(start 112.988852 -32.0802)
		(end 111.633 -32.0802)
		(width 0.17272)
		(layer "F.Cu")
		(net "P52V_HS2_GATE5")
	)
	(via
		(at 111.633 -32.0802)
		(size 0.762)
		(drill 0.381)
		(layers "F.Cu" "B.Cu")
		(net "P52V_HS2_GATE5")
	)
	(segment
		(start 112.988852 -54.6354)
		(end 112.6236 -54.6354)
		(width 0.17272)
		(layer "F.Cu")
		(net "P52V_HS2_GATE3")
	)
	(segment
		(start 111.0488 -55.6514)
		(end 111.6076 -55.6514)
		(width 0.17272)
		(layer "F.Cu")
		(net "P52V_HS2_GATE3")
	)
	(segment
		(start 111.6076 -55.6514)
		(end 112.6236 -54.6354)
		(width 0.17272)
		(layer "F.Cu")
		(net "P52V_HS2_GATE3")
	)
	(via
		(at 111.0488 -55.6514)
		(size 0.762)
		(drill 0.381)
		(layers "F.Cu" "B.Cu")
		(net "P52V_HS2_GATE3")
	)
	(segment
		(start 112.988852 -22.2758)
		(end 112.252252 -22.2758)
		(width 0.4572)
		(layer "F.Cu")
		(net "P52V_HS2_GATE2_R")
	)
	(segment
		(start 112.252252 -33.5534)
		(end 112.988852 -33.5534)
		(width 0.4572)
		(layer "F.Cu")
		(net "P52V_HS2_GATE2_R")
	)
	(segment
		(start 112.988852 -44.831)
		(end 112.252252 -44.831)
		(width 0.4572)
		(layer "F.Cu")
		(net "P52V_HS2_GATE2_R")
	)
	(via
		(at 112.252252 -44.831)
		(size 0.508)
		(drill 0.254)
		(layers "F.Cu" "B.Cu")
		(net "P52V_HS2_GATE2_R")
	)
	(via
		(at 112.252252 -33.5534)
		(size 0.508)
		(drill 0.254)
		(layers "F.Cu" "B.Cu")
		(net "P52V_HS2_GATE2_R")
	)
	(via
		(at 112.252252 -22.2758)
		(size 0.508)
		(drill 0.254)
		(layers "F.Cu" "B.Cu")
		(net "P52V_HS2_GATE2_R")
	)
	(segment
		(start 112.169702 -44.74845)
		(end 112.252252 -44.831)
		(width 0.4572)
		(layer "B.Cu")
		(net "P52V_HS2_GATE2_R")
	)
	(segment
		(start 110.2614 -44.74845)
		(end 111.2774 -44.74845)
		(width 0.4572)
		(layer "B.Cu")
		(net "P52V_HS2_GATE2_R")
	)
	(segment
		(start 111.2774 -44.74845)
		(end 112.169702 -44.74845)
		(width 0.4572)
		(layer "B.Cu")
		(net "P52V_HS2_GATE2_R")
	)
	(segment
		(start 112.988852 -78.6638)
		(end 112.252252 -78.6638)
		(width 0.4572)
		(layer "F.Cu")
		(net "P52V_HS2_GATE1_R")
	)
	(segment
		(start 112.988852 -67.3862)
		(end 112.252252 -67.3862)
		(width 0.4572)
		(layer "F.Cu")
		(net "P52V_HS2_GATE1_R")
	)
	(segment
		(start 112.988852 -56.1086)
		(end 112.252252 -56.1086)
		(width 0.4572)
		(layer "F.Cu")
		(net "P52V_HS2_GATE1_R")
	)
	(via
		(at 112.252252 -78.6638)
		(size 0.508)
		(drill 0.254)
		(layers "F.Cu" "B.Cu")
		(net "P52V_HS2_GATE1_R")
	)
	(via
		(at 112.252252 -56.1086)
		(size 0.508)
		(drill 0.254)
		(layers "F.Cu" "B.Cu")
		(net "P52V_HS2_GATE1_R")
	)
	(via
		(at 112.252252 -67.3862)
		(size 0.508)
		(drill 0.254)
		(layers "F.Cu" "B.Cu")
		(net "P52V_HS2_GATE1_R")
	)
	(segment
		(start 112.169702 -56.02605)
		(end 112.252252 -56.1086)
		(width 0.4572)
		(layer "B.Cu")
		(net "P52V_HS2_GATE1_R")
	)
	(segment
		(start 110.2614 -56.02605)
		(end 111.2774 -56.02605)
		(width 0.4572)
		(layer "B.Cu")
		(net "P52V_HS2_GATE1_R")
	)
	(segment
		(start 111.2774 -56.02605)
		(end 112.169702 -56.02605)
		(width 0.4572)
		(layer "B.Cu")
		(net "P52V_HS2_GATE1_R")
	)
	(segment
		(start 112.988852 -77.1906)
		(end 111.5314 -77.1906)
		(width 0.17272)
		(layer "F.Cu")
		(net "P52V_HS2_GATE1")
	)
	(via
		(at 111.5314 -77.1906)
		(size 0.762)
		(drill 0.381)
		(layers "F.Cu" "B.Cu")
		(net "P52V_HS2_GATE1")
	)
	(segment
		(start 112.988852 -20.8026)
		(end 111.6076 -20.8026)
		(width 0.17272)
		(layer "F.Cu")
		(net "P52V_HS2_GATE6")
	)
	(via
		(at 111.6076 -20.8026)
		(size 0.762)
		(drill 0.381)
		(layers "F.Cu" "B.Cu")
		(net "P52V_HS2_GATE6")
	)
	(via
		(at 315.0108 -61.849)
		(size 0.508)
		(drill 0.254)
		(layers "F.Cu" "B.Cu")
		(net "P52V_HS1_DRAIN_1")
	)
	(via
		(at 313.4868 -74.6506)
		(size 0.508)
		(drill 0.254)
		(layers "F.Cu" "B.Cu")
		(net "P52V_HS1_DRAIN_1")
	)
	(via
		(at 312.7248 -74.6506)
		(size 0.508)
		(drill 0.254)
		(layers "F.Cu" "B.Cu")
		(net "P52V_HS1_DRAIN_1")
	)
	(via
		(at 314.2488 -52.0954)
		(size 0.508)
		(drill 0.254)
		(layers "F.Cu" "B.Cu")
		(net "P52V_HS1_DRAIN_1")
	)
	(via
		(at 315.0108 -52.8574)
		(size 0.508)
		(drill 0.254)
		(layers "F.Cu" "B.Cu")
		(net "P52V_HS1_DRAIN_1")
	)
	(via
		(at 315.0108 -52.0954)
		(size 0.508)
		(drill 0.254)
		(layers "F.Cu" "B.Cu")
		(net "P52V_HS1_DRAIN_1")
	)
	(via
		(at 315.0108 -64.897)
		(size 0.508)
		(drill 0.254)
		(layers "F.Cu" "B.Cu")
		(net "P52V_HS1_DRAIN_1")
	)
	(via
		(at 315.0108 -63.373)
		(size 0.508)
		(drill 0.254)
		(layers "F.Cu" "B.Cu")
		(net "P52V_HS1_DRAIN_1")
	)
	(via
		(at 313.4868 -76.1746)
		(size 0.508)
		(drill 0.254)
		(layers "F.Cu" "B.Cu")
		(net "P52V_HS1_DRAIN_1")
	)
	(via
		(at 315.0108 -64.135)
		(size 0.508)
		(drill 0.254)
		(layers "F.Cu" "B.Cu")
		(net "P52V_HS1_DRAIN_1")
	)
	(via
		(at 315.0108 -51.3334)
		(size 0.508)
		(drill 0.254)
		(layers "F.Cu" "B.Cu")
		(net "P52V_HS1_DRAIN_1")
	)
	(via
		(at 312.7248 -73.1266)
		(size 0.508)
		(drill 0.254)
		(layers "F.Cu" "B.Cu")
		(net "P52V_HS1_DRAIN_1")
	)
	(via
		(at 315.0108 -50.5714)
		(size 0.508)
		(drill 0.254)
		(layers "F.Cu" "B.Cu")
		(net "P52V_HS1_DRAIN_1")
	)
	(via
		(at 314.2488 -64.135)
		(size 0.508)
		(drill 0.254)
		(layers "F.Cu" "B.Cu")
		(net "P52V_HS1_DRAIN_1")
	)
	(via
		(at 314.2488 -61.849)
		(size 0.508)
		(drill 0.254)
		(layers "F.Cu" "B.Cu")
		(net "P52V_HS1_DRAIN_1")
	)
	(via
		(at 315.0108 -73.1266)
		(size 0.508)
		(drill 0.254)
		(layers "F.Cu" "B.Cu")
		(net "P52V_HS1_DRAIN_1")
	)
	(via
		(at 311.658 -56.642)
		(size 0.762)
		(drill 0.381)
		(layers "F.Cu" "B.Cu")
		(net "P52V_HS1_DRAIN_1")
	)
	(via
		(at 311.404 -63.754)
		(size 0.762)
		(drill 0.381)
		(layers "F.Cu" "B.Cu")
		(net "P52V_HS1_DRAIN_1")
	)
	(via
		(at 313.4868 -63.373)
		(size 0.508)
		(drill 0.254)
		(layers "F.Cu" "B.Cu")
		(net "P52V_HS1_DRAIN_1")
	)
	(via
		(at 313.4868 -64.897)
		(size 0.508)
		(drill 0.254)
		(layers "F.Cu" "B.Cu")
		(net "P52V_HS1_DRAIN_1")
	)
	(via
		(at 314.2488 -76.1746)
		(size 0.508)
		(drill 0.254)
		(layers "F.Cu" "B.Cu")
		(net "P52V_HS1_DRAIN_1")
	)
	(via
		(at 314.2488 -73.8886)
		(size 0.508)
		(drill 0.254)
		(layers "F.Cu" "B.Cu")
		(net "P52V_HS1_DRAIN_1")
	)
	(via
		(at 315.0108 -73.8886)
		(size 0.508)
		(drill 0.254)
		(layers "F.Cu" "B.Cu")
		(net "P52V_HS1_DRAIN_1")
	)
	(via
		(at 314.2488 -63.373)
		(size 0.508)
		(drill 0.254)
		(layers "F.Cu" "B.Cu")
		(net "P52V_HS1_DRAIN_1")
	)
	(via
		(at 312.7248 -75.4126)
		(size 0.508)
		(drill 0.254)
		(layers "F.Cu" "B.Cu")
		(net "P52V_HS1_DRAIN_1")
	)
	(via
		(at 315.0108 -75.4126)
		(size 0.508)
		(drill 0.254)
		(layers "F.Cu" "B.Cu")
		(net "P52V_HS1_DRAIN_1")
	)
	(via
		(at 314.2488 -74.6506)
		(size 0.508)
		(drill 0.254)
		(layers "F.Cu" "B.Cu")
		(net "P52V_HS1_DRAIN_1")
	)
	(via
		(at 315.0108 -74.6506)
		(size 0.508)
		(drill 0.254)
		(layers "F.Cu" "B.Cu")
		(net "P52V_HS1_DRAIN_1")
	)
	(via
		(at 313.4868 -73.1266)
		(size 0.508)
		(drill 0.254)
		(layers "F.Cu" "B.Cu")
		(net "P52V_HS1_DRAIN_1")
	)
	(via
		(at 313.4868 -75.4126)
		(size 0.508)
		(drill 0.254)
		(layers "F.Cu" "B.Cu")
		(net "P52V_HS1_DRAIN_1")
	)
	(via
		(at 314.2488 -50.5714)
		(size 0.508)
		(drill 0.254)
		(layers "F.Cu" "B.Cu")
		(net "P52V_HS1_DRAIN_1")
	)
	(via
		(at 314.2488 -64.897)
		(size 0.508)
		(drill 0.254)
		(layers "F.Cu" "B.Cu")
		(net "P52V_HS1_DRAIN_1")
	)
	(via
		(at 310.642 -50.038)
		(size 0.762)
		(drill 0.381)
		(layers "F.Cu" "B.Cu")
		(net "P52V_HS1_DRAIN_1")
	)
	(via
		(at 312.7248 -73.8886)
		(size 0.508)
		(drill 0.254)
		(layers "F.Cu" "B.Cu")
		(net "P52V_HS1_DRAIN_1")
	)
	(via
		(at 314.2488 -51.3334)
		(size 0.508)
		(drill 0.254)
		(layers "F.Cu" "B.Cu")
		(net "P52V_HS1_DRAIN_1")
	)
	(via
		(at 313.4868 -62.611)
		(size 0.508)
		(drill 0.254)
		(layers "F.Cu" "B.Cu")
		(net "P52V_HS1_DRAIN_1")
	)
	(via
		(at 314.2488 -53.6194)
		(size 0.508)
		(drill 0.254)
		(layers "F.Cu" "B.Cu")
		(net "P52V_HS1_DRAIN_1")
	)
	(via
		(at 314.2488 -75.4126)
		(size 0.508)
		(drill 0.254)
		(layers "F.Cu" "B.Cu")
		(net "P52V_HS1_DRAIN_1")
	)
	(via
		(at 311.912 -69.596)
		(size 0.762)
		(drill 0.381)
		(layers "F.Cu" "B.Cu")
		(net "P52V_HS1_DRAIN_1")
	)
	(via
		(at 314.2488 -73.1266)
		(size 0.508)
		(drill 0.254)
		(layers "F.Cu" "B.Cu")
		(net "P52V_HS1_DRAIN_1")
	)
	(via
		(at 313.4868 -61.849)
		(size 0.508)
		(drill 0.254)
		(layers "F.Cu" "B.Cu")
		(net "P52V_HS1_DRAIN_1")
	)
	(via
		(at 315.0108 -62.611)
		(size 0.508)
		(drill 0.254)
		(layers "F.Cu" "B.Cu")
		(net "P52V_HS1_DRAIN_1")
	)
	(via
		(at 313.4868 -73.8886)
		(size 0.508)
		(drill 0.254)
		(layers "F.Cu" "B.Cu")
		(net "P52V_HS1_DRAIN_1")
	)
	(via
		(at 312.7248 -76.1746)
		(size 0.508)
		(drill 0.254)
		(layers "F.Cu" "B.Cu")
		(net "P52V_HS1_DRAIN_1")
	)
	(via
		(at 315.0108 -53.6194)
		(size 0.508)
		(drill 0.254)
		(layers "F.Cu" "B.Cu")
		(net "P52V_HS1_DRAIN_1")
	)
	(via
		(at 314.2488 -62.611)
		(size 0.508)
		(drill 0.254)
		(layers "F.Cu" "B.Cu")
		(net "P52V_HS1_DRAIN_1")
	)
	(via
		(at 307.848 -54.61)
		(size 0.762)
		(drill 0.381)
		(layers "F.Cu" "B.Cu")
		(net "P52V_HS1_DRAIN_1")
	)
	(via
		(at 315.0108 -76.1746)
		(size 0.508)
		(drill 0.254)
		(layers "F.Cu" "B.Cu")
		(net "P52V_HS1_DRAIN_1")
	)
	(via
		(at 314.2488 -52.8574)
		(size 0.508)
		(drill 0.254)
		(layers "F.Cu" "B.Cu")
		(net "P52V_HS1_DRAIN_1")
	)
	(via
		(at 313.4868 -64.135)
		(size 0.508)
		(drill 0.254)
		(layers "F.Cu" "B.Cu")
		(net "P52V_HS1_DRAIN_1")
	)
	(segment
		(start 335.3562 -49.6062)
		(end 336.296 -50.546)
		(width 0.17272)
		(layer "F.Cu")
		(net "P52V_HS1_GATE3")
	)
	(segment
		(start 334.631284 -49.6062)
		(end 335.3562 -49.6062)
		(width 0.17272)
		(layer "F.Cu")
		(net "P52V_HS1_GATE3")
	)
	(via
		(at 336.296 -50.546)
		(size 0.762)
		(drill 0.381)
		(layers "F.Cu" "B.Cu")
		(net "P52V_HS1_GATE3")
	)
	(segment
		(start 304.254662 -39.337488)
		(end 304.254662 -38.1762)
		(width 0.4572)
		(layer "F.Cu")
		(net "P52V_HS_4287_S2P")
	)
	(segment
		(start 304.254662 -38.1762)
		(end 304.000662 -37.9222)
		(width 0.4572)
		(layer "F.Cu")
		(net "P52V_HS_4287_S2P")
	)
	(segment
		(start 304.000662 -37.9222)
		(end 303.149 -37.9222)
		(width 0.4572)
		(layer "F.Cu")
		(net "P52V_HS_4287_S2P")
	)
	(segment
		(start 304.14595 -39.4462)
		(end 304.254662 -39.337488)
		(width 0.4572)
		(layer "F.Cu")
		(net "P52V_HS_4287_S2P")
	)
	(segment
		(start 304.14595 -40.712136)
		(end 304.14595 -39.4462)
		(width 0.4572)
		(layer "F.Cu")
		(net "P52V_HS_4287_S2P")
	)
	(via
		(at 304.14595 -40.712136)
		(size 0.508)
		(drill 0.254)
		(layers "F.Cu" "B.Cu")
		(net "P52V_HS_4287_S2P")
	)
	(segment
		(start 304.14595 -40.712136)
		(end 304.14595 -41.201086)
		(width 0.4572)
		(layer "B.Cu")
		(net "P52V_HS_4287_S2P")
	)
	(segment
		(start 305.524916 -42.580052)
		(end 305.524916 -64.688974)
		(width 0.4572)
		(layer "B.Cu")
		(net "P52V_HS_4287_S2P")
	)
	(segment
		(start 297.351958 -67.353942)
		(end 296.947844 -67.353942)
		(width 0.254)
		(layer "B.Cu")
		(net "P52V_HS_4287_S2P")
	)
	(segment
		(start 305.524916 -64.688974)
		(end 301.840392 -68.373498)
		(width 0.4572)
		(layer "B.Cu")
		(net "P52V_HS_4287_S2P")
	)
	(segment
		(start 299.532548 -67.322446)
		(end 298.433236 -67.322446)
		(width 0.4572)
		(layer "B.Cu")
		(net "P52V_HS_4287_S2P")
	)
	(segment
		(start 298.433236 -67.322446)
		(end 298.345352 -67.41033)
		(width 0.254)
		(layer "B.Cu")
		(net "P52V_HS_4287_S2P")
	)
	(segment
		(start 301.840392 -68.373498)
		(end 300.5836 -68.373498)
		(width 0.4572)
		(layer "B.Cu")
		(net "P52V_HS_4287_S2P")
	)
	(segment
		(start 300.5836 -68.373498)
		(end 299.532548 -67.322446)
		(width 0.4572)
		(layer "B.Cu")
		(net "P52V_HS_4287_S2P")
	)
	(segment
		(start 298.345352 -67.41033)
		(end 297.408346 -67.41033)
		(width 0.254)
		(layer "B.Cu")
		(net "P52V_HS_4287_S2P")
	)
	(segment
		(start 297.408346 -67.41033)
		(end 297.351958 -67.353942)
		(width 0.254)
		(layer "B.Cu")
		(net "P52V_HS_4287_S2P")
	)
	(segment
		(start 304.14595 -41.201086)
		(end 305.524916 -42.580052)
		(width 0.4572)
		(layer "B.Cu")
		(net "P52V_HS_4287_S2P")
	)
	(via
		(at 338.87156 -37.247068)
		(size 0.508)
		(drill 0.254)
		(layers "F.Cu" "B.Cu")
		(net "P52V_HS1_4287_GATE2_R")
	)
	(via
		(at 304.070258 -79.823056)
		(size 0.508)
		(drill 0.254)
		(layers "F.Cu" "B.Cu")
		(net "P52V_HS1_4287_GATE2_R")
	)
	(via
		(at 299.925232 -75.67803)
		(size 0.6604)
		(drill 0.3302)
		(layers "F.Cu" "B.Cu")
		(net "P52V_HS1_4287_GATE2_R")
	)
	(segment
		(start 337.918298 -37.247068)
		(end 337.3374 -37.827966)
		(width 0.508)
		(layer "B.Cu")
		(net "P52V_HS1_4287_GATE2_R")
	)
	(segment
		(start 337.3374 -38.96995)
		(end 338.04225 -38.96995)
		(width 0.508)
		(layer "B.Cu")
		(net "P52V_HS1_4287_GATE2_R")
	)
	(segment
		(start 341.5792 -38.0492)
		(end 341.49665 -38.13175)
		(width 0.4572)
		(layer "B.Cu")
		(net "P52V_HS1_4287_GATE2_R")
	)
	(segment
		(start 341.5284 -36.9062)
		(end 341.5284 -37.9984)
		(width 0.508)
		(layer "B.Cu")
		(net "P52V_HS1_4287_GATE2_R")
	)
	(segment
		(start 338.04225 -38.96995)
		(end 338.8614 -38.1508)
		(width 0.508)
		(layer "B.Cu")
		(net "P52V_HS1_4287_GATE2_R")
	)
	(segment
		(start 299.925232 -73.74636)
		(end 298.85386 -72.674988)
		(width 0.508)
		(layer "B.Cu")
		(net "P52V_HS1_4287_GATE2_R")
	)
	(segment
		(start 341.63 -36.8046)
		(end 341.5284 -36.9062)
		(width 0.508)
		(layer "B.Cu")
		(net "P52V_HS1_4287_GATE2_R")
	)
	(segment
		(start 341.5284 -37.9984)
		(end 341.5792 -38.0492)
		(width 0.508)
		(layer "B.Cu")
		(net "P52V_HS1_4287_GATE2_R")
	)
	(segment
		(start 304.070258 -79.823056)
		(end 299.925232 -75.67803)
		(width 0.508)
		(layer "B.Cu")
		(net "P52V_HS1_4287_GATE2_R")
	)
	(segment
		(start 341.49665 -38.13175)
		(end 340.3854 -38.13175)
		(width 0.4572)
		(layer "B.Cu")
		(net "P52V_HS1_4287_GATE2_R")
	)
	(segment
		(start 338.8614 -38.1508)
		(end 338.88045 -38.13175)
		(width 0.4572)
		(layer "B.Cu")
		(net "P52V_HS1_4287_GATE2_R")
	)
	(segment
		(start 338.88045 -38.13175)
		(end 340.3854 -38.13175)
		(width 0.4572)
		(layer "B.Cu")
		(net "P52V_HS1_4287_GATE2_R")
	)
	(segment
		(start 338.87156 -37.247068)
		(end 337.918298 -37.247068)
		(width 0.508)
		(layer "B.Cu")
		(net "P52V_HS1_4287_GATE2_R")
	)
	(segment
		(start 337.3374 -37.827966)
		(end 337.3374 -38.96995)
		(width 0.508)
		(layer "B.Cu")
		(net "P52V_HS1_4287_GATE2_R")
	)
	(segment
		(start 299.925232 -75.67803)
		(end 299.925232 -73.74636)
		(width 0.508)
		(layer "B.Cu")
		(net "P52V_HS1_4287_GATE2_R")
	)
	(segment
		(start 298.85386 -72.674988)
		(end 298.532804 -72.353932)
		(width 0.2794)
		(layer "B.Cu")
		(net "P52V_HS1_4287_GATE2_R")
	)
	(segment
		(start 298.532804 -72.353932)
		(end 296.922444 -72.353932)
		(width 0.2794)
		(layer "B.Cu")
		(net "P52V_HS1_4287_GATE2_R")
	)
	(segment
		(start 324.591172 -81.160366)
		(end 325.834756 -79.916782)
		(width 0.762)
		(layer "In2.Cu")
		(net "P52V_HS1_4287_GATE2_R")
	)
	(segment
		(start 304.328322 -79.564992)
		(end 306.157884 -79.564992)
		(width 0.762)
		(layer "In2.Cu")
		(net "P52V_HS1_4287_GATE2_R")
	)
	(segment
		(start 304.070258 -79.823056)
		(end 304.328322 -79.564992)
		(width 0.762)
		(layer "In2.Cu")
		(net "P52V_HS1_4287_GATE2_R")
	)
	(segment
		(start 327.470008 -37.247068)
		(end 338.87156 -37.247068)
		(width 0.762)
		(layer "In2.Cu")
		(net "P52V_HS1_4287_GATE2_R")
	)
	(segment
		(start 325.834756 -38.88232)
		(end 327.470008 -37.247068)
		(width 0.762)
		(layer "In2.Cu")
		(net "P52V_HS1_4287_GATE2_R")
	)
	(segment
		(start 325.834756 -79.916782)
		(end 325.834756 -38.88232)
		(width 0.762)
		(layer "In2.Cu")
		(net "P52V_HS1_4287_GATE2_R")
	)
	(segment
		(start 306.157884 -79.564992)
		(end 307.753258 -81.160366)
		(width 0.762)
		(layer "In2.Cu")
		(net "P52V_HS1_4287_GATE2_R")
	)
	(segment
		(start 307.753258 -81.160366)
		(end 324.591172 -81.160366)
		(width 0.762)
		(layer "In2.Cu")
		(net "P52V_HS1_4287_GATE2_R")
	)
	(segment
		(start 334.631284 -17.2466)
		(end 335.367884 -17.2466)
		(width 0.4572)
		(layer "F.Cu")
		(net "P52V_HS1_GATE2_R")
	)
	(segment
		(start 334.631284 -39.8018)
		(end 335.367884 -39.8018)
		(width 0.4572)
		(layer "F.Cu")
		(net "P52V_HS1_GATE2_R")
	)
	(segment
		(start 334.631284 -28.5242)
		(end 335.367884 -28.5242)
		(width 0.4572)
		(layer "F.Cu")
		(net "P52V_HS1_GATE2_R")
	)
	(via
		(at 335.367884 -28.5242)
		(size 0.508)
		(drill 0.254)
		(layers "F.Cu" "B.Cu")
		(net "P52V_HS1_GATE2_R")
	)
	(via
		(at 335.367884 -39.8018)
		(size 0.508)
		(drill 0.254)
		(layers "F.Cu" "B.Cu")
		(net "P52V_HS1_GATE2_R")
	)
	(via
		(at 335.367884 -17.2466)
		(size 0.508)
		(drill 0.254)
		(layers "F.Cu" "B.Cu")
		(net "P52V_HS1_GATE2_R")
	)
	(segment
		(start 337.3374 -39.77005)
		(end 336.3214 -39.77005)
		(width 0.4572)
		(layer "B.Cu")
		(net "P52V_HS1_GATE2_R")
	)
	(segment
		(start 336.3214 -39.77005)
		(end 335.399634 -39.77005)
		(width 0.4572)
		(layer "B.Cu")
		(net "P52V_HS1_GATE2_R")
	)
	(segment
		(start 335.399634 -39.77005)
		(end 335.367884 -39.8018)
		(width 0.4572)
		(layer "B.Cu")
		(net "P52V_HS1_GATE2_R")
	)
	(segment
		(start 304.537364 -69.469)
		(end 304.029364 -69.977)
		(width 0.4572)
		(layer "F.Cu")
		(net "P52V_HS_1272_S_P")
	)
	(segment
		(start 304.029364 -69.977)
		(end 303.149 -69.977)
		(width 0.4572)
		(layer "F.Cu")
		(net "P52V_HS_1272_S_P")
	)
	(segment
		(start 304.5714 -69.469)
		(end 304.537364 -69.469)
		(width 0.4572)
		(layer "F.Cu")
		(net "P52V_HS_1272_S_P")
	)
	(segment
		(start 303.149 -34.3662)
		(end 304.1904 -34.3662)
		(width 0.4572)
		(layer "F.Cu")
		(net "P52V_HS_1272_S_P")
	)
	(segment
		(start 304.1904 -34.3662)
		(end 304.5714 -34.7472)
		(width 0.4572)
		(layer "F.Cu")
		(net "P52V_HS_1272_S_P")
	)
	(via
		(at 304.5714 -34.7472)
		(size 0.508)
		(drill 0.254)
		(layers "F.Cu" "B.Cu")
		(net "P52V_HS_1272_S_P")
	)
	(via
		(at 304.5714 -69.469)
		(size 0.762)
		(drill 0.254)
		(layers "F.Cu" "B.Cu")
		(net "P52V_HS_1272_S_P")
	)
	(via
		(at 268.0462 -73.8886)
		(size 0.508)
		(drill 0.254)
		(layers "F.Cu" "B.Cu")
		(net "P52V_HS_1272_S_P")
	)
	(segment
		(start 308.700932 -37.025072)
		(end 306.26812 -34.59226)
		(width 0.4572)
		(layer "B.Cu")
		(net "P52V_HS_1272_S_P")
	)
	(segment
		(start 304.72126 -69.61886)
		(end 307.066188 -69.61886)
		(width 0.4572)
		(layer "B.Cu")
		(net "P52V_HS_1272_S_P")
	)
	(segment
		(start 308.700932 -67.984116)
		(end 308.700932 -37.025072)
		(width 0.4572)
		(layer "B.Cu")
		(net "P52V_HS_1272_S_P")
	)
	(segment
		(start 304.5714 -69.469)
		(end 304.72126 -69.61886)
		(width 0.4572)
		(layer "B.Cu")
		(net "P52V_HS_1272_S_P")
	)
	(segment
		(start 267.90396 -73.74636)
		(end 268.0462 -73.8886)
		(width 0.254)
		(layer "B.Cu")
		(net "P52V_HS_1272_S_P")
	)
	(segment
		(start 304.72634 -34.59226)
		(end 304.5714 -34.7472)
		(width 0.4572)
		(layer "B.Cu")
		(net "P52V_HS_1272_S_P")
	)
	(segment
		(start 267.90396 -73.04532)
		(end 267.90396 -73.74636)
		(width 0.254)
		(layer "B.Cu")
		(net "P52V_HS_1272_S_P")
	)
	(segment
		(start 306.26812 -34.59226)
		(end 304.72634 -34.59226)
		(width 0.4572)
		(layer "B.Cu")
		(net "P52V_HS_1272_S_P")
	)
	(segment
		(start 307.066188 -69.61886)
		(end 308.700932 -67.984116)
		(width 0.4572)
		(layer "B.Cu")
		(net "P52V_HS_1272_S_P")
	)
	(segment
		(start 273.586194 -75.489816)
		(end 269.135352 -75.489816)
		(width 0.4572)
		(layer "In2.Cu")
		(net "P52V_HS_1272_S_P")
	)
	(segment
		(start 269.135352 -75.489816)
		(end 267.990066 -74.34453)
		(width 0.4572)
		(layer "In2.Cu")
		(net "P52V_HS_1272_S_P")
	)
	(segment
		(start 304.5714 -69.469)
		(end 304.39741 -69.64299)
		(width 0.4572)
		(layer "In2.Cu")
		(net "P52V_HS_1272_S_P")
	)
	(segment
		(start 298.978574 -84.16163)
		(end 282.258008 -84.16163)
		(width 0.4572)
		(layer "In2.Cu")
		(net "P52V_HS_1272_S_P")
	)
	(segment
		(start 302.268382 -70.510654)
		(end 302.268382 -80.871822)
		(width 0.4572)
		(layer "In2.Cu")
		(net "P52V_HS_1272_S_P")
	)
	(segment
		(start 267.990066 -73.944734)
		(end 268.0462 -73.8886)
		(width 0.4572)
		(layer "In2.Cu")
		(net "P52V_HS_1272_S_P")
	)
	(segment
		(start 303.136046 -69.64299)
		(end 302.268382 -70.510654)
		(width 0.4572)
		(layer "In2.Cu")
		(net "P52V_HS_1272_S_P")
	)
	(segment
		(start 304.39741 -69.64299)
		(end 303.136046 -69.64299)
		(width 0.4572)
		(layer "In2.Cu")
		(net "P52V_HS_1272_S_P")
	)
	(segment
		(start 282.258008 -84.16163)
		(end 273.586194 -75.489816)
		(width 0.4572)
		(layer "In2.Cu")
		(net "P52V_HS_1272_S_P")
	)
	(segment
		(start 302.268382 -80.871822)
		(end 298.978574 -84.16163)
		(width 0.4572)
		(layer "In2.Cu")
		(net "P52V_HS_1272_S_P")
	)
	(segment
		(start 267.990066 -74.34453)
		(end 267.990066 -73.944734)
		(width 0.4572)
		(layer "In2.Cu")
		(net "P52V_HS_1272_S_P")
	)
	(segment
		(start 303.149 -36.1442)
		(end 304.1904 -36.1442)
		(width 0.4572)
		(layer "F.Cu")
		(net "P52V_HS_4287_ADC_P")
	)
	(segment
		(start 304.528728 -67.691)
		(end 304.020728 -68.199)
		(width 0.4572)
		(layer "F.Cu")
		(net "P52V_HS_4287_ADC_P")
	)
	(segment
		(start 304.1904 -36.1442)
		(end 304.5714 -36.5252)
		(width 0.4572)
		(layer "F.Cu")
		(net "P52V_HS_4287_ADC_P")
	)
	(segment
		(start 304.020728 -68.199)
		(end 303.149 -68.199)
		(width 0.4572)
		(layer "F.Cu")
		(net "P52V_HS_4287_ADC_P")
	)
	(segment
		(start 304.5714 -67.691)
		(end 304.528728 -67.691)
		(width 0.4572)
		(layer "F.Cu")
		(net "P52V_HS_4287_ADC_P")
	)
	(via
		(at 304.5714 -36.5252)
		(size 0.508)
		(drill 0.254)
		(layers "F.Cu" "B.Cu")
		(net "P52V_HS_4287_ADC_P")
	)
	(via
		(at 297.684444 -68.35394)
		(size 0.762)
		(drill 0.254)
		(layers "F.Cu" "B.Cu")
		(net "P52V_HS_4287_ADC_P")
	)
	(via
		(at 304.5714 -67.691)
		(size 0.508)
		(drill 0.254)
		(layers "F.Cu" "B.Cu")
		(net "P52V_HS_4287_ADC_P")
	)
	(segment
		(start 305.29403 -67.766692)
		(end 304.647092 -67.766692)
		(width 0.4572)
		(layer "B.Cu")
		(net "P52V_HS_4287_ADC_P")
	)
	(segment
		(start 307.108098 -65.952624)
		(end 305.29403 -67.766692)
		(width 0.4572)
		(layer "B.Cu")
		(net "P52V_HS_4287_ADC_P")
	)
	(segment
		(start 307.108098 -37.806122)
		(end 307.108098 -65.952624)
		(width 0.4572)
		(layer "B.Cu")
		(net "P52V_HS_4287_ADC_P")
	)
	(segment
		(start 304.71618 -36.38042)
		(end 305.682396 -36.38042)
		(width 0.4572)
		(layer "B.Cu")
		(net "P52V_HS_4287_ADC_P")
	)
	(segment
		(start 296.922444 -68.35394)
		(end 297.684444 -68.35394)
		(width 0.254)
		(layer "B.Cu")
		(net "P52V_HS_4287_ADC_P")
	)
	(segment
		(start 304.647092 -67.766692)
		(end 304.5714 -67.691)
		(width 0.4572)
		(layer "B.Cu")
		(net "P52V_HS_4287_ADC_P")
	)
	(segment
		(start 304.5714 -36.5252)
		(end 304.71618 -36.38042)
		(width 0.4572)
		(layer "B.Cu")
		(net "P52V_HS_4287_ADC_P")
	)
	(segment
		(start 305.682396 -36.38042)
		(end 307.108098 -37.806122)
		(width 0.4572)
		(layer "B.Cu")
		(net "P52V_HS_4287_ADC_P")
	)
	(segment
		(start 302.830992 -67.83832)
		(end 304.42408 -67.83832)
		(width 0.4572)
		(layer "In2.Cu")
		(net "P52V_HS_4287_ADC_P")
	)
	(segment
		(start 297.684444 -68.35394)
		(end 298.158916 -68.828412)
		(width 0.4572)
		(layer "In2.Cu")
		(net "P52V_HS_4287_ADC_P")
	)
	(segment
		(start 298.158916 -68.828412)
		(end 301.8409 -68.828412)
		(width 0.4572)
		(layer "In2.Cu")
		(net "P52V_HS_4287_ADC_P")
	)
	(segment
		(start 301.8409 -68.828412)
		(end 302.830992 -67.83832)
		(width 0.4572)
		(layer "In2.Cu")
		(net "P52V_HS_4287_ADC_P")
	)
	(segment
		(start 304.42408 -67.83832)
		(end 304.5714 -67.691)
		(width 0.4572)
		(layer "In2.Cu")
		(net "P52V_HS_4287_ADC_P")
	)
	(segment
		(start 304.616104 -33.8582)
		(end 305.124104 -34.3662)
		(width 0.4572)
		(layer "F.Cu")
		(net "P52V_HS_1272_S_N")
	)
	(segment
		(start 304.5714 -70.358)
		(end 304.7746 -70.358)
		(width 0.4572)
		(layer "F.Cu")
		(net "P52V_HS_1272_S_N")
	)
	(segment
		(start 305.124104 -34.3662)
		(end 305.9938 -34.3662)
		(width 0.4572)
		(layer "F.Cu")
		(net "P52V_HS_1272_S_N")
	)
	(segment
		(start 305.1556 -69.977)
		(end 305.9938 -69.977)
		(width 0.4572)
		(layer "F.Cu")
		(net "P52V_HS_1272_S_N")
	)
	(segment
		(start 304.7746 -70.358)
		(end 305.1556 -69.977)
		(width 0.4572)
		(layer "F.Cu")
		(net "P52V_HS_1272_S_N")
	)
	(segment
		(start 304.5714 -33.8582)
		(end 304.616104 -33.8582)
		(width 0.4572)
		(layer "F.Cu")
		(net "P52V_HS_1272_S_N")
	)
	(via
		(at 267.2588 -73.8886)
		(size 0.508)
		(drill 0.254)
		(layers "F.Cu" "B.Cu")
		(net "P52V_HS_1272_S_N")
	)
	(via
		(at 304.5714 -70.358)
		(size 0.508)
		(drill 0.254)
		(layers "F.Cu" "B.Cu")
		(net "P52V_HS_1272_S_N")
	)
	(via
		(at 304.5714 -33.8582)
		(size 0.508)
		(drill 0.254)
		(layers "F.Cu" "B.Cu")
		(net "P52V_HS_1272_S_N")
	)
	(segment
		(start 306.510182 -34.00806)
		(end 309.285132 -36.78301)
		(width 0.4572)
		(layer "B.Cu")
		(net "P52V_HS_1272_S_N")
	)
	(segment
		(start 309.285132 -36.78301)
		(end 309.285132 -68.226178)
		(width 0.4572)
		(layer "B.Cu")
		(net "P52V_HS_1272_S_N")
	)
	(segment
		(start 304.72126 -34.00806)
		(end 306.510182 -34.00806)
		(width 0.4572)
		(layer "B.Cu")
		(net "P52V_HS_1272_S_N")
	)
	(segment
		(start 267.40358 -73.74382)
		(end 267.2588 -73.8886)
		(width 0.254)
		(layer "B.Cu")
		(net "P52V_HS_1272_S_N")
	)
	(segment
		(start 304.5714 -33.8582)
		(end 304.72126 -34.00806)
		(width 0.4572)
		(layer "B.Cu")
		(net "P52V_HS_1272_S_N")
	)
	(segment
		(start 307.30825 -70.20306)
		(end 304.72634 -70.20306)
		(width 0.4572)
		(layer "B.Cu")
		(net "P52V_HS_1272_S_N")
	)
	(segment
		(start 267.40358 -73.04532)
		(end 267.40358 -73.74382)
		(width 0.254)
		(layer "B.Cu")
		(net "P52V_HS_1272_S_N")
	)
	(segment
		(start 304.72634 -70.20306)
		(end 304.5714 -70.358)
		(width 0.4572)
		(layer "B.Cu")
		(net "P52V_HS_1272_S_N")
	)
	(segment
		(start 309.285132 -68.226178)
		(end 307.30825 -70.20306)
		(width 0.4572)
		(layer "B.Cu")
		(net "P52V_HS_1272_S_N")
	)
	(segment
		(start 268.893036 -76.074016)
		(end 267.34262 -74.5236)
		(width 0.4572)
		(layer "In2.Cu")
		(net "P52V_HS_1272_S_N")
	)
	(segment
		(start 304.44059 -70.22719)
		(end 303.378362 -70.22719)
		(width 0.4572)
		(layer "In2.Cu")
		(net "P52V_HS_1272_S_N")
	)
	(segment
		(start 282.015692 -84.74583)
		(end 273.343878 -76.074016)
		(width 0.4572)
		(layer "In2.Cu")
		(net "P52V_HS_1272_S_N")
	)
	(segment
		(start 299.22089 -84.74583)
		(end 282.015692 -84.74583)
		(width 0.4572)
		(layer "In2.Cu")
		(net "P52V_HS_1272_S_N")
	)
	(segment
		(start 267.34262 -73.97242)
		(end 267.2588 -73.8886)
		(width 0.4572)
		(layer "In2.Cu")
		(net "P52V_HS_1272_S_N")
	)
	(segment
		(start 303.378362 -70.22719)
		(end 302.852582 -70.75297)
		(width 0.4572)
		(layer "In2.Cu")
		(net "P52V_HS_1272_S_N")
	)
	(segment
		(start 302.852582 -81.114138)
		(end 299.22089 -84.74583)
		(width 0.4572)
		(layer "In2.Cu")
		(net "P52V_HS_1272_S_N")
	)
	(segment
		(start 304.5714 -70.358)
		(end 304.44059 -70.22719)
		(width 0.4572)
		(layer "In2.Cu")
		(net "P52V_HS_1272_S_N")
	)
	(segment
		(start 302.852582 -70.75297)
		(end 302.852582 -81.114138)
		(width 0.4572)
		(layer "In2.Cu")
		(net "P52V_HS_1272_S_N")
	)
	(segment
		(start 273.343878 -76.074016)
		(end 268.893036 -76.074016)
		(width 0.4572)
		(layer "In2.Cu")
		(net "P52V_HS_1272_S_N")
	)
	(segment
		(start 267.34262 -74.5236)
		(end 267.34262 -73.97242)
		(width 0.4572)
		(layer "In2.Cu")
		(net "P52V_HS_1272_S_N")
	)
	(segment
		(start 317.60795 -84.275676)
		(end 317.60795 -83.82)
		(width 0.254)
		(layer "F.Cu")
		(net "P52V_HS1_TEMPN_R")
	)
	(segment
		(start 320.8274 -83.693)
		(end 324.6628 -83.693)
		(width 0.254)
		(layer "F.Cu")
		(net "P52V_HS1_TEMPN_R")
	)
	(segment
		(start 317.86195 -84.529676)
		(end 317.60795 -84.275676)
		(width 0.254)
		(layer "F.Cu")
		(net "P52V_HS1_TEMPN_R")
	)
	(segment
		(start 320.8274 -83.693)
		(end 319.990724 -84.529676)
		(width 0.254)
		(layer "F.Cu")
		(net "P52V_HS1_TEMPN_R")
	)
	(segment
		(start 319.990724 -84.529676)
		(end 317.86195 -84.529676)
		(width 0.254)
		(layer "F.Cu")
		(net "P52V_HS1_TEMPN_R")
	)
	(via
		(at 324.6628 -83.693)
		(size 0.762)
		(drill 0.381)
		(layers "F.Cu" "B.Cu")
		(net "P52V_HS1_TEMPN_R")
	)
	(segment
		(start 305.9938 -36.1442)
		(end 305.112928 -36.1442)
		(width 0.4572)
		(layer "F.Cu")
		(net "P52V_HS_4287_ADC_N")
	)
	(segment
		(start 305.112928 -36.1442)
		(end 304.604928 -35.6362)
		(width 0.4572)
		(layer "F.Cu")
		(net "P52V_HS_4287_ADC_N")
	)
	(segment
		(start 304.604928 -35.6362)
		(end 304.5714 -35.6362)
		(width 0.4572)
		(layer "F.Cu")
		(net "P52V_HS_4287_ADC_N")
	)
	(segment
		(start 304.9524 -68.199)
		(end 305.9938 -68.199)
		(width 0.4572)
		(layer "F.Cu")
		(net "P52V_HS_4287_ADC_N")
	)
	(segment
		(start 304.5714 -68.58)
		(end 304.9524 -68.199)
		(width 0.4572)
		(layer "F.Cu")
		(net "P52V_HS_4287_ADC_N")
	)
	(via
		(at 304.5714 -35.6362)
		(size 0.508)
		(drill 0.254)
		(layers "F.Cu" "B.Cu")
		(net "P52V_HS_4287_ADC_N")
	)
	(via
		(at 297.684444 -69.854064)
		(size 0.762)
		(drill 0.254)
		(layers "F.Cu" "B.Cu")
		(net "P52V_HS_4287_ADC_N")
	)
	(via
		(at 304.5714 -68.58)
		(size 0.508)
		(drill 0.254)
		(layers "F.Cu" "B.Cu")
		(net "P52V_HS_4287_ADC_N")
	)
	(segment
		(start 307.692298 -37.56406)
		(end 305.924458 -35.79622)
		(width 0.4572)
		(layer "B.Cu")
		(net "P52V_HS_4287_ADC_N")
	)
	(segment
		(start 305.497992 -68.388992)
		(end 307.692298 -66.194686)
		(width 0.4572)
		(layer "B.Cu")
		(net "P52V_HS_4287_ADC_N")
	)
	(segment
		(start 304.73142 -35.79622)
		(end 304.5714 -35.6362)
		(width 0.4572)
		(layer "B.Cu")
		(net "P52V_HS_4287_ADC_N")
	)
	(segment
		(start 307.692298 -66.194686)
		(end 307.692298 -37.56406)
		(width 0.4572)
		(layer "B.Cu")
		(net "P52V_HS_4287_ADC_N")
	)
	(segment
		(start 304.762408 -68.388992)
		(end 305.497992 -68.388992)
		(width 0.4572)
		(layer "B.Cu")
		(net "P52V_HS_4287_ADC_N")
	)
	(segment
		(start 296.922444 -69.854064)
		(end 297.684444 -69.854064)
		(width 0.254)
		(layer "B.Cu")
		(net "P52V_HS_4287_ADC_N")
	)
	(segment
		(start 305.924458 -35.79622)
		(end 304.73142 -35.79622)
		(width 0.4572)
		(layer "B.Cu")
		(net "P52V_HS_4287_ADC_N")
	)
	(segment
		(start 304.5714 -68.58)
		(end 304.762408 -68.388992)
		(width 0.4572)
		(layer "B.Cu")
		(net "P52V_HS_4287_ADC_N")
	)
	(segment
		(start 302.083216 -69.412612)
		(end 298.125896 -69.412612)
		(width 0.4572)
		(layer "In2.Cu")
		(net "P52V_HS_4287_ADC_N")
	)
	(segment
		(start 304.5714 -68.58)
		(end 304.41392 -68.42252)
		(width 0.4572)
		(layer "In2.Cu")
		(net "P52V_HS_4287_ADC_N")
	)
	(segment
		(start 304.41392 -68.42252)
		(end 303.073308 -68.42252)
		(width 0.4572)
		(layer "In2.Cu")
		(net "P52V_HS_4287_ADC_N")
	)
	(segment
		(start 303.073308 -68.42252)
		(end 302.083216 -69.412612)
		(width 0.4572)
		(layer "In2.Cu")
		(net "P52V_HS_4287_ADC_N")
	)
	(segment
		(start 298.125896 -69.412612)
		(end 297.684444 -69.854064)
		(width 0.4572)
		(layer "In2.Cu")
		(net "P52V_HS_4287_ADC_N")
	)
	(segment
		(start 334.631284 -60.8838)
		(end 336.2198 -60.8838)
		(width 0.17272)
		(layer "F.Cu")
		(net "P52V_HS1_GATE2")
	)
	(via
		(at 336.2198 -60.8838)
		(size 0.762)
		(drill 0.381)
		(layers "F.Cu" "B.Cu")
		(net "P52V_HS1_GATE2")
	)
	(segment
		(start 334.631284 -27.051)
		(end 336.169 -27.051)
		(width 0.17272)
		(layer "F.Cu")
		(net "P52V_HS1_GATE4")
	)
	(via
		(at 336.169 -27.051)
		(size 0.762)
		(drill 0.381)
		(layers "F.Cu" "B.Cu")
		(net "P52V_HS1_GATE4")
	)
	(segment
		(start 319.01765 -83.82)
		(end 318.40805 -83.82)
		(width 0.254)
		(layer "F.Cu")
		(net "P52V_HS1_TEMPN")
	)
	(via
		(at 319.01765 -83.82)
		(size 0.508)
		(drill 0.254)
		(layers "F.Cu" "B.Cu")
		(net "P52V_HS1_TEMPN")
	)
	(via
		(at 271.02435 -77.21092)
		(size 0.508)
		(drill 0.254)
		(layers "F.Cu" "B.Cu")
		(net "P52V_HS1_TEMPN")
	)
	(segment
		(start 271.02435 -76.454)
		(end 271.02435 -76.073)
		(width 0.254)
		(layer "B.Cu")
		(net "P52V_HS1_TEMPN")
	)
	(segment
		(start 271.24279 -75.19416)
		(end 270.962628 -74.913998)
		(width 0.254)
		(layer "B.Cu")
		(net "P52V_HS1_TEMPN")
	)
	(segment
		(start 271.02435 -76.454)
		(end 271.02435 -77.21092)
		(width 0.254)
		(layer "B.Cu")
		(net "P52V_HS1_TEMPN")
	)
	(segment
		(start 270.962628 -74.913998)
		(end 270.962628 -73.536048)
		(width 0.254)
		(layer "B.Cu")
		(net "P52V_HS1_TEMPN")
	)
	(segment
		(start 271.02435 -76.073)
		(end 271.24279 -75.85456)
		(width 0.254)
		(layer "B.Cu")
		(net "P52V_HS1_TEMPN")
	)
	(segment
		(start 270.962628 -73.536048)
		(end 270.9037 -73.47712)
		(width 0.254)
		(layer "B.Cu")
		(net "P52V_HS1_TEMPN")
	)
	(segment
		(start 271.24279 -75.85456)
		(end 271.24279 -75.19416)
		(width 0.254)
		(layer "B.Cu")
		(net "P52V_HS1_TEMPN")
	)
	(segment
		(start 270.9037 -73.47712)
		(end 270.9037 -73.04532)
		(width 0.254)
		(layer "B.Cu")
		(net "P52V_HS1_TEMPN")
	)
	(segment
		(start 320.85407 -85.691726)
		(end 319.96634 -86.579456)
		(width 0.254)
		(layer "In2.Cu")
		(net "P52V_HS1_TEMPN")
	)
	(segment
		(start 271.174464 -77.361034)
		(end 271.02435 -77.21092)
		(width 0.254)
		(layer "In2.Cu")
		(net "P52V_HS1_TEMPN")
	)
	(segment
		(start 320.85407 -85.01634)
		(end 320.85407 -85.691726)
		(width 0.254)
		(layer "In2.Cu")
		(net "P52V_HS1_TEMPN")
	)
	(segment
		(start 279.058624 -85.847174)
		(end 271.174464 -77.963014)
		(width 0.254)
		(layer "In2.Cu")
		(net "P52V_HS1_TEMPN")
	)
	(segment
		(start 320.377058 -84.539328)
		(end 320.85407 -85.01634)
		(width 0.254)
		(layer "In2.Cu")
		(net "P52V_HS1_TEMPN")
	)
	(segment
		(start 319.01765 -83.82)
		(end 319.736978 -84.539328)
		(width 0.254)
		(layer "In2.Cu")
		(net "P52V_HS1_TEMPN")
	)
	(segment
		(start 271.174464 -77.963014)
		(end 271.174464 -77.361034)
		(width 0.254)
		(layer "In2.Cu")
		(net "P52V_HS1_TEMPN")
	)
	(segment
		(start 319.736978 -84.539328)
		(end 320.377058 -84.539328)
		(width 0.254)
		(layer "In2.Cu")
		(net "P52V_HS1_TEMPN")
	)
	(segment
		(start 315.759338 -85.847174)
		(end 279.058624 -85.847174)
		(width 0.254)
		(layer "In2.Cu")
		(net "P52V_HS1_TEMPN")
	)
	(segment
		(start 319.96634 -86.579456)
		(end 316.49162 -86.579456)
		(width 0.254)
		(layer "In2.Cu")
		(net "P52V_HS1_TEMPN")
	)
	(segment
		(start 316.49162 -86.579456)
		(end 315.759338 -85.847174)
		(width 0.254)
		(layer "In2.Cu")
		(net "P52V_HS1_TEMPN")
	)
	(via
		(at 313.4868 -28.7782)
		(size 0.508)
		(drill 0.254)
		(layers "F.Cu" "B.Cu")
		(net "P52V_HS1_DRAIN_2")
	)
	(via
		(at 312.7248 -18.2626)
		(size 0.508)
		(drill 0.254)
		(layers "F.Cu" "B.Cu")
		(net "P52V_HS1_DRAIN_2")
	)
	(via
		(at 315.0108 -41.5798)
		(size 0.508)
		(drill 0.254)
		(layers "F.Cu" "B.Cu")
		(net "P52V_HS1_DRAIN_2")
	)
	(via
		(at 313.4868 -19.7866)
		(size 0.508)
		(drill 0.254)
		(layers "F.Cu" "B.Cu")
		(net "P52V_HS1_DRAIN_2")
	)
	(via
		(at 315.0108 -19.7866)
		(size 0.508)
		(drill 0.254)
		(layers "F.Cu" "B.Cu")
		(net "P52V_HS1_DRAIN_2")
	)
	(via
		(at 315.0108 -30.3022)
		(size 0.508)
		(drill 0.254)
		(layers "F.Cu" "B.Cu")
		(net "P52V_HS1_DRAIN_2")
	)
	(via
		(at 315.0108 -39.2938)
		(size 0.508)
		(drill 0.254)
		(layers "F.Cu" "B.Cu")
		(net "P52V_HS1_DRAIN_2")
	)
	(via
		(at 314.2488 -28.7782)
		(size 0.508)
		(drill 0.254)
		(layers "F.Cu" "B.Cu")
		(net "P52V_HS1_DRAIN_2")
	)
	(via
		(at 314.2488 -18.2626)
		(size 0.508)
		(drill 0.254)
		(layers "F.Cu" "B.Cu")
		(net "P52V_HS1_DRAIN_2")
	)
	(via
		(at 313.4868 -16.7386)
		(size 0.508)
		(drill 0.254)
		(layers "F.Cu" "B.Cu")
		(net "P52V_HS1_DRAIN_2")
	)
	(via
		(at 314.2488 -41.5798)
		(size 0.508)
		(drill 0.254)
		(layers "F.Cu" "B.Cu")
		(net "P52V_HS1_DRAIN_2")
	)
	(via
		(at 314.2488 -19.7866)
		(size 0.508)
		(drill 0.254)
		(layers "F.Cu" "B.Cu")
		(net "P52V_HS1_DRAIN_2")
	)
	(via
		(at 314.2488 -30.3022)
		(size 0.508)
		(drill 0.254)
		(layers "F.Cu" "B.Cu")
		(net "P52V_HS1_DRAIN_2")
	)
	(via
		(at 313.4868 -29.5402)
		(size 0.508)
		(drill 0.254)
		(layers "F.Cu" "B.Cu")
		(net "P52V_HS1_DRAIN_2")
	)
	(via
		(at 310.642 -24.384)
		(size 0.762)
		(drill 0.381)
		(layers "F.Cu" "B.Cu")
		(net "P52V_HS1_DRAIN_2")
	)
	(via
		(at 315.0108 -19.0246)
		(size 0.508)
		(drill 0.254)
		(layers "F.Cu" "B.Cu")
		(net "P52V_HS1_DRAIN_2")
	)
	(via
		(at 314.2488 -17.5006)
		(size 0.508)
		(drill 0.254)
		(layers "F.Cu" "B.Cu")
		(net "P52V_HS1_DRAIN_2")
	)
	(via
		(at 312.7248 -17.5006)
		(size 0.508)
		(drill 0.254)
		(layers "F.Cu" "B.Cu")
		(net "P52V_HS1_DRAIN_2")
	)
	(via
		(at 313.4868 -18.2626)
		(size 0.508)
		(drill 0.254)
		(layers "F.Cu" "B.Cu")
		(net "P52V_HS1_DRAIN_2")
	)
	(via
		(at 313.4868 -31.0642)
		(size 0.508)
		(drill 0.254)
		(layers "F.Cu" "B.Cu")
		(net "P52V_HS1_DRAIN_2")
	)
	(via
		(at 314.2488 -40.8178)
		(size 0.508)
		(drill 0.254)
		(layers "F.Cu" "B.Cu")
		(net "P52V_HS1_DRAIN_2")
	)
	(via
		(at 313.4868 -19.0246)
		(size 0.508)
		(drill 0.254)
		(layers "F.Cu" "B.Cu")
		(net "P52V_HS1_DRAIN_2")
	)
	(via
		(at 315.0108 -28.0162)
		(size 0.508)
		(drill 0.254)
		(layers "F.Cu" "B.Cu")
		(net "P52V_HS1_DRAIN_2")
	)
	(via
		(at 314.2488 -42.3418)
		(size 0.508)
		(drill 0.254)
		(layers "F.Cu" "B.Cu")
		(net "P52V_HS1_DRAIN_2")
	)
	(via
		(at 314.2488 -16.7386)
		(size 0.508)
		(drill 0.254)
		(layers "F.Cu" "B.Cu")
		(net "P52V_HS1_DRAIN_2")
	)
	(via
		(at 314.2488 -29.5402)
		(size 0.508)
		(drill 0.254)
		(layers "F.Cu" "B.Cu")
		(net "P52V_HS1_DRAIN_2")
	)
	(via
		(at 312.7248 -19.7866)
		(size 0.508)
		(drill 0.254)
		(layers "F.Cu" "B.Cu")
		(net "P52V_HS1_DRAIN_2")
	)
	(via
		(at 315.0108 -31.0642)
		(size 0.508)
		(drill 0.254)
		(layers "F.Cu" "B.Cu")
		(net "P52V_HS1_DRAIN_2")
	)
	(via
		(at 308.356 -21.082)
		(size 0.762)
		(drill 0.381)
		(layers "F.Cu" "B.Cu")
		(net "P52V_HS1_DRAIN_2")
	)
	(via
		(at 315.0108 -17.5006)
		(size 0.508)
		(drill 0.254)
		(layers "F.Cu" "B.Cu")
		(net "P52V_HS1_DRAIN_2")
	)
	(via
		(at 314.2488 -31.0642)
		(size 0.508)
		(drill 0.254)
		(layers "F.Cu" "B.Cu")
		(net "P52V_HS1_DRAIN_2")
	)
	(via
		(at 315.0108 -40.0558)
		(size 0.508)
		(drill 0.254)
		(layers "F.Cu" "B.Cu")
		(net "P52V_HS1_DRAIN_2")
	)
	(via
		(at 314.2488 -19.0246)
		(size 0.508)
		(drill 0.254)
		(layers "F.Cu" "B.Cu")
		(net "P52V_HS1_DRAIN_2")
	)
	(via
		(at 308.356 -44.958)
		(size 0.762)
		(drill 0.381)
		(layers "F.Cu" "B.Cu")
		(net "P52V_HS1_DRAIN_2")
	)
	(via
		(at 314.2488 -40.0558)
		(size 0.508)
		(drill 0.254)
		(layers "F.Cu" "B.Cu")
		(net "P52V_HS1_DRAIN_2")
	)
	(via
		(at 314.2488 -39.2938)
		(size 0.508)
		(drill 0.254)
		(layers "F.Cu" "B.Cu")
		(net "P52V_HS1_DRAIN_2")
	)
	(via
		(at 311.15 -41.91)
		(size 0.762)
		(drill 0.381)
		(layers "F.Cu" "B.Cu")
		(net "P52V_HS1_DRAIN_2")
	)
	(via
		(at 312.7248 -19.0246)
		(size 0.508)
		(drill 0.254)
		(layers "F.Cu" "B.Cu")
		(net "P52V_HS1_DRAIN_2")
	)
	(via
		(at 312.7248 -16.7386)
		(size 0.508)
		(drill 0.254)
		(layers "F.Cu" "B.Cu")
		(net "P52V_HS1_DRAIN_2")
	)
	(via
		(at 313.4868 -30.3022)
		(size 0.508)
		(drill 0.254)
		(layers "F.Cu" "B.Cu")
		(net "P52V_HS1_DRAIN_2")
	)
	(via
		(at 315.0108 -42.3418)
		(size 0.508)
		(drill 0.254)
		(layers "F.Cu" "B.Cu")
		(net "P52V_HS1_DRAIN_2")
	)
	(via
		(at 315.0108 -16.7386)
		(size 0.508)
		(drill 0.254)
		(layers "F.Cu" "B.Cu")
		(net "P52V_HS1_DRAIN_2")
	)
	(via
		(at 315.0108 -28.7782)
		(size 0.508)
		(drill 0.254)
		(layers "F.Cu" "B.Cu")
		(net "P52V_HS1_DRAIN_2")
	)
	(via
		(at 315.0108 -40.8178)
		(size 0.508)
		(drill 0.254)
		(layers "F.Cu" "B.Cu")
		(net "P52V_HS1_DRAIN_2")
	)
	(via
		(at 314.2488 -28.0162)
		(size 0.508)
		(drill 0.254)
		(layers "F.Cu" "B.Cu")
		(net "P52V_HS1_DRAIN_2")
	)
	(via
		(at 315.0108 -29.5402)
		(size 0.508)
		(drill 0.254)
		(layers "F.Cu" "B.Cu")
		(net "P52V_HS1_DRAIN_2")
	)
	(via
		(at 313.4868 -17.5006)
		(size 0.508)
		(drill 0.254)
		(layers "F.Cu" "B.Cu")
		(net "P52V_HS1_DRAIN_2")
	)
	(via
		(at 315.0108 -18.2626)
		(size 0.508)
		(drill 0.254)
		(layers "F.Cu" "B.Cu")
		(net "P52V_HS1_DRAIN_2")
	)
	(via
		(at 313.4868 -28.0162)
		(size 0.508)
		(drill 0.254)
		(layers "F.Cu" "B.Cu")
		(net "P52V_HS1_DRAIN_2")
	)
	(segment
		(start 319.01765 -85.598)
		(end 318.40805 -85.598)
		(width 0.254)
		(layer "F.Cu")
		(net "P52V_HS1_TEMPP")
	)
	(via
		(at 271.82445 -77.21092)
		(size 0.508)
		(drill 0.254)
		(layers "F.Cu" "B.Cu")
		(net "P52V_HS1_TEMPP")
	)
	(via
		(at 319.01765 -85.598)
		(size 0.508)
		(drill 0.254)
		(layers "F.Cu" "B.Cu")
		(net "P52V_HS1_TEMPP")
	)
	(segment
		(start 271.343628 -73.539604)
		(end 271.40408 -73.479152)
		(width 0.254)
		(layer "B.Cu")
		(net "P52V_HS1_TEMPP")
	)
	(segment
		(start 271.343628 -74.75601)
		(end 271.343628 -73.539604)
		(width 0.254)
		(layer "B.Cu")
		(net "P52V_HS1_TEMPP")
	)
	(segment
		(start 271.40408 -73.479152)
		(end 271.40408 -73.04532)
		(width 0.254)
		(layer "B.Cu")
		(net "P52V_HS1_TEMPP")
	)
	(segment
		(start 271.82445 -76.073)
		(end 271.62379 -75.87234)
		(width 0.254)
		(layer "B.Cu")
		(net "P52V_HS1_TEMPP")
	)
	(segment
		(start 271.82445 -76.454)
		(end 271.82445 -76.073)
		(width 0.254)
		(layer "B.Cu")
		(net "P52V_HS1_TEMPP")
	)
	(segment
		(start 271.82445 -76.454)
		(end 271.82445 -77.21092)
		(width 0.254)
		(layer "B.Cu")
		(net "P52V_HS1_TEMPP")
	)
	(segment
		(start 271.62379 -75.87234)
		(end 271.62379 -75.036172)
		(width 0.254)
		(layer "B.Cu")
		(net "P52V_HS1_TEMPP")
	)
	(segment
		(start 271.62379 -75.036172)
		(end 271.343628 -74.75601)
		(width 0.254)
		(layer "B.Cu")
		(net "P52V_HS1_TEMPP")
	)
	(segment
		(start 271.614138 -77.421232)
		(end 271.82445 -77.21092)
		(width 0.254)
		(layer "In2.Cu")
		(net "P52V_HS1_TEMPP")
	)
	(segment
		(start 320.21907 -84.920328)
		(end 320.47307 -85.174328)
		(width 0.254)
		(layer "In2.Cu")
		(net "P52V_HS1_TEMPP")
	)
	(segment
		(start 271.614138 -77.780642)
		(end 271.614138 -77.421232)
		(width 0.254)
		(layer "In2.Cu")
		(net "P52V_HS1_TEMPP")
	)
	(segment
		(start 316.649608 -86.198456)
		(end 315.917326 -85.466174)
		(width 0.254)
		(layer "In2.Cu")
		(net "P52V_HS1_TEMPP")
	)
	(segment
		(start 319.808352 -86.198456)
		(end 316.649608 -86.198456)
		(width 0.254)
		(layer "In2.Cu")
		(net "P52V_HS1_TEMPP")
	)
	(segment
		(start 320.47307 -85.533738)
		(end 319.808352 -86.198456)
		(width 0.254)
		(layer "In2.Cu")
		(net "P52V_HS1_TEMPP")
	)
	(segment
		(start 320.47307 -85.174328)
		(end 320.47307 -85.533738)
		(width 0.254)
		(layer "In2.Cu")
		(net "P52V_HS1_TEMPP")
	)
	(segment
		(start 279.29967 -85.466174)
		(end 271.614138 -77.780642)
		(width 0.254)
		(layer "In2.Cu")
		(net "P52V_HS1_TEMPP")
	)
	(segment
		(start 319.695322 -84.920328)
		(end 320.21907 -84.920328)
		(width 0.254)
		(layer "In2.Cu")
		(net "P52V_HS1_TEMPP")
	)
	(segment
		(start 315.917326 -85.466174)
		(end 279.29967 -85.466174)
		(width 0.254)
		(layer "In2.Cu")
		(net "P52V_HS1_TEMPP")
	)
	(segment
		(start 319.01765 -85.598)
		(end 319.695322 -84.920328)
		(width 0.254)
		(layer "In2.Cu")
		(net "P52V_HS1_TEMPP")
	)
	(segment
		(start 334.631284 -62.357)
		(end 335.367884 -62.357)
		(width 0.4572)
		(layer "F.Cu")
		(net "P52V_HS1_GATE1_R")
	)
	(segment
		(start 334.631284 -73.6346)
		(end 335.367884 -73.6346)
		(width 0.4572)
		(layer "F.Cu")
		(net "P52V_HS1_GATE1_R")
	)
	(segment
		(start 334.631284 -51.0794)
		(end 335.367884 -51.0794)
		(width 0.4572)
		(layer "F.Cu")
		(net "P52V_HS1_GATE1_R")
	)
	(via
		(at 335.367884 -62.357)
		(size 0.508)
		(drill 0.254)
		(layers "F.Cu" "B.Cu")
		(net "P52V_HS1_GATE1_R")
	)
	(via
		(at 335.367884 -51.0794)
		(size 0.508)
		(drill 0.254)
		(layers "F.Cu" "B.Cu")
		(net "P52V_HS1_GATE1_R")
	)
	(via
		(at 335.367884 -73.6346)
		(size 0.508)
		(drill 0.254)
		(layers "F.Cu" "B.Cu")
		(net "P52V_HS1_GATE1_R")
	)
	(segment
		(start 335.367884 -51.0794)
		(end 335.399634 -51.04765)
		(width 0.4572)
		(layer "B.Cu")
		(net "P52V_HS1_GATE1_R")
	)
	(segment
		(start 336.3214 -51.04765)
		(end 337.3374 -51.04765)
		(width 0.4572)
		(layer "B.Cu")
		(net "P52V_HS1_GATE1_R")
	)
	(segment
		(start 335.399634 -51.04765)
		(end 336.3214 -51.04765)
		(width 0.4572)
		(layer "B.Cu")
		(net "P52V_HS1_GATE1_R")
	)
	(segment
		(start 305.39309 -29.5402)
		(end 305.0794 -29.5402)
		(width 0.254)
		(layer "F.Cu")
		(net "P52V_HS1_SENSE_N_R2")
	)
	(segment
		(start 304.616358 -29.077158)
		(end 304.616358 -28.987242)
		(width 0.254)
		(layer "F.Cu")
		(net "P52V_HS1_SENSE_N_R2")
	)
	(segment
		(start 305.0794 -29.5402)
		(end 304.616358 -29.077158)
		(width 0.254)
		(layer "F.Cu")
		(net "P52V_HS1_SENSE_N_R2")
	)
	(segment
		(start 307.467 -34.3662)
		(end 307.467 -33.6296)
		(width 0.4572)
		(layer "F.Cu")
		(net "P52V_HS1_SENSE_N_R2")
	)
	(segment
		(start 307.467 -37.9222)
		(end 307.467 -36.1442)
		(width 0.4572)
		(layer "F.Cu")
		(net "P52V_HS1_SENSE_N_R2")
	)
	(segment
		(start 307.467 -36.1442)
		(end 307.467 -34.3662)
		(width 0.4572)
		(layer "F.Cu")
		(net "P52V_HS1_SENSE_N_R2")
	)
	(via
		(at 304.616358 -28.987242)
		(size 0.508)
		(drill 0.254)
		(layers "F.Cu" "B.Cu")
		(net "P52V_HS1_SENSE_N_R2")
	)
	(via
		(at 307.467 -33.6296)
		(size 0.508)
		(drill 0.254)
		(layers "F.Cu" "B.Cu")
		(net "P52V_HS1_SENSE_N_R2")
	)
	(segment
		(start 307.467 -33.6296)
		(end 305.75377 -33.6296)
		(width 0.4572)
		(layer "In2.Cu")
		(net "P52V_HS1_SENSE_N_R2")
	)
	(segment
		(start 305.251358 -33.127188)
		(end 305.251358 -29.622242)
		(width 0.4572)
		(layer "In2.Cu")
		(net "P52V_HS1_SENSE_N_R2")
	)
	(segment
		(start 305.75377 -33.6296)
		(end 305.251358 -33.127188)
		(width 0.4572)
		(layer "In2.Cu")
		(net "P52V_HS1_SENSE_N_R2")
	)
	(segment
		(start 305.251358 -29.622242)
		(end 304.616358 -28.987242)
		(width 0.4572)
		(layer "In2.Cu")
		(net "P52V_HS1_SENSE_N_R2")
	)
	(segment
		(start 334.631284 -15.7734)
		(end 336.2706 -15.7734)
		(width 0.17272)
		(layer "F.Cu")
		(net "P52V_HS1_GATE5")
	)
	(via
		(at 336.2706 -15.7734)
		(size 0.762)
		(drill 0.381)
		(layers "F.Cu" "B.Cu")
		(net "P52V_HS1_GATE5")
	)
	(via
		(at 305.063398 -81.003648)
		(size 0.508)
		(drill 0.254)
		(layers "F.Cu" "B.Cu")
		(net "P52V_HS1_4287_GATE_R")
	)
	(via
		(at 300.331886 -72.70623)
		(size 0.6604)
		(drill 0.3302)
		(layers "F.Cu" "B.Cu")
		(net "P52V_HS1_4287_GATE_R")
	)
	(via
		(at 338.498434 -48.423576)
		(size 0.508)
		(drill 0.254)
		(layers "F.Cu" "B.Cu")
		(net "P52V_HS1_4287_GATE_R")
	)
	(segment
		(start 338.8614 -49.4284)
		(end 338.04225 -50.24755)
		(width 0.508)
		(layer "B.Cu")
		(net "P52V_HS1_4287_GATE_R")
	)
	(segment
		(start 305.063398 -79.314802)
		(end 300.949868 -75.201272)
		(width 0.508)
		(layer "B.Cu")
		(net "P52V_HS1_4287_GATE_R")
	)
	(segment
		(start 300.949868 -73.324212)
		(end 300.331886 -72.70623)
		(width 0.508)
		(layer "B.Cu")
		(net "P52V_HS1_4287_GATE_R")
	)
	(segment
		(start 341.503 -47.9806)
		(end 341.503 -48.5648)
		(width 0.508)
		(layer "B.Cu")
		(net "P52V_HS1_4287_GATE_R")
	)
	(segment
		(start 299.714158 -72.088502)
		(end 299.479716 -71.85406)
		(width 0.2794)
		(layer "B.Cu")
		(net "P52V_HS1_4287_GATE_R")
	)
	(segment
		(start 341.4522 -49.35855)
		(end 340.5124 -49.35855)
		(width 0.4572)
		(layer "B.Cu")
		(net "P52V_HS1_4287_GATE_R")
	)
	(segment
		(start 341.5792 -48.641)
		(end 341.5792 -49.1998)
		(width 0.508)
		(layer "B.Cu")
		(net "P52V_HS1_4287_GATE_R")
	)
	(segment
		(start 341.5792 -49.23155)
		(end 341.4522 -49.35855)
		(width 0.4572)
		(layer "B.Cu")
		(net "P52V_HS1_4287_GATE_R")
	)
	(segment
		(start 338.93125 -49.35855)
		(end 340.5124 -49.35855)
		(width 0.4572)
		(layer "B.Cu")
		(net "P52V_HS1_4287_GATE_R")
	)
	(segment
		(start 338.078318 -48.423576)
		(end 337.3374 -49.164494)
		(width 0.508)
		(layer "B.Cu")
		(net "P52V_HS1_4287_GATE_R")
	)
	(segment
		(start 338.8614 -49.4284)
		(end 338.93125 -49.35855)
		(width 0.4572)
		(layer "B.Cu")
		(net "P52V_HS1_4287_GATE_R")
	)
	(segment
		(start 341.5792 -49.1998)
		(end 341.5792 -49.23155)
		(width 0.4572)
		(layer "B.Cu")
		(net "P52V_HS1_4287_GATE_R")
	)
	(segment
		(start 341.503 -48.5648)
		(end 341.5792 -48.641)
		(width 0.508)
		(layer "B.Cu")
		(net "P52V_HS1_4287_GATE_R")
	)
	(segment
		(start 338.04225 -50.24755)
		(end 337.3374 -50.24755)
		(width 0.508)
		(layer "B.Cu")
		(net "P52V_HS1_4287_GATE_R")
	)
	(segment
		(start 299.479716 -71.85406)
		(end 296.922444 -71.85406)
		(width 0.2794)
		(layer "B.Cu")
		(net "P52V_HS1_4287_GATE_R")
	)
	(segment
		(start 305.063398 -81.003648)
		(end 305.063398 -79.314802)
		(width 0.508)
		(layer "B.Cu")
		(net "P52V_HS1_4287_GATE_R")
	)
	(segment
		(start 338.498434 -48.423576)
		(end 338.078318 -48.423576)
		(width 0.508)
		(layer "B.Cu")
		(net "P52V_HS1_4287_GATE_R")
	)
	(segment
		(start 300.331886 -72.70623)
		(end 299.714158 -72.088502)
		(width 0.508)
		(layer "B.Cu")
		(net "P52V_HS1_4287_GATE_R")
	)
	(segment
		(start 300.949868 -75.201272)
		(end 300.949868 -73.324212)
		(width 0.508)
		(layer "B.Cu")
		(net "P52V_HS1_4287_GATE_R")
	)
	(segment
		(start 337.3374 -49.164494)
		(end 337.3374 -50.24755)
		(width 0.508)
		(layer "B.Cu")
		(net "P52V_HS1_4287_GATE_R")
	)
	(segment
		(start 306.549552 -82.489802)
		(end 325.732902 -82.489802)
		(width 0.762)
		(layer "In2.Cu")
		(net "P52V_HS1_4287_GATE_R")
	)
	(segment
		(start 327.398126 -49.440846)
		(end 328.415396 -48.423576)
		(width 0.762)
		(layer "In2.Cu")
		(net "P52V_HS1_4287_GATE_R")
	)
	(segment
		(start 327.398126 -80.824578)
		(end 327.398126 -49.440846)
		(width 0.762)
		(layer "In2.Cu")
		(net "P52V_HS1_4287_GATE_R")
	)
	(segment
		(start 325.732902 -82.489802)
		(end 327.398126 -80.824578)
		(width 0.762)
		(layer "In2.Cu")
		(net "P52V_HS1_4287_GATE_R")
	)
	(segment
		(start 305.063398 -81.003648)
		(end 306.549552 -82.489802)
		(width 0.762)
		(layer "In2.Cu")
		(net "P52V_HS1_4287_GATE_R")
	)
	(segment
		(start 328.415396 -48.423576)
		(end 338.498434 -48.423576)
		(width 0.762)
		(layer "In2.Cu")
		(net "P52V_HS1_4287_GATE_R")
	)
	(segment
		(start 334.631284 -38.3286)
		(end 335.0006 -38.3286)
		(width 0.17272)
		(layer "F.Cu")
		(net "P52V_HS1_GATE6")
	)
	(segment
		(start 335.0006 -38.3286)
		(end 336.296 -39.624)
		(width 0.17272)
		(layer "F.Cu")
		(net "P52V_HS1_GATE6")
	)
	(via
		(at 336.296 -39.624)
		(size 0.762)
		(drill 0.381)
		(layers "F.Cu" "B.Cu")
		(net "P52V_HS1_GATE6")
	)
	(segment
		(start 334.631284 -72.1614)
		(end 336.042 -72.1614)
		(width 0.17272)
		(layer "F.Cu")
		(net "P52V_HS1_GATE1")
	)
	(via
		(at 336.042 -72.1614)
		(size 0.762)
		(drill 0.381)
		(layers "F.Cu" "B.Cu")
		(net "P52V_HS1_GATE1")
	)
	(via
		(at 336.3214 -38.227)
		(size 0.508)
		(drill 0.254)
		(layers "F.Cu" "B.Cu")
		(net "P52V_HS1_1272_GATE")
	)
	(via
		(at 336.3214 -49.5046)
		(size 0.508)
		(drill 0.254)
		(layers "F.Cu" "B.Cu")
		(net "P52V_HS1_1272_GATE")
	)
	(via
		(at 265.4046 -70.7644)
		(size 0.762)
		(drill 0.254)
		(layers "F.Cu" "B.Cu")
		(net "P52V_HS1_1272_GATE")
	)
	(segment
		(start 336.3214 -38.96995)
		(end 336.3214 -38.227)
		(width 0.508)
		(layer "B.Cu")
		(net "P52V_HS1_1272_GATE")
	)
	(segment
		(start 336.3214 -50.24755)
		(end 336.3214 -49.5046)
		(width 0.508)
		(layer "B.Cu")
		(net "P52V_HS1_1272_GATE")
	)
	(segment
		(start 265.4046 -70.7644)
		(end 265.8237 -70.3453)
		(width 0.17272)
		(layer "B.Cu")
		(net "P52V_HS1_1272_GATE")
	)
	(segment
		(start 265.8237 -70.3453)
		(end 266.2047 -70.3453)
		(width 0.17272)
		(layer "B.Cu")
		(net "P52V_HS1_1272_GATE")
	)
	(segment
		(start 304.845466 -38.1762)
		(end 305.099466 -37.9222)
		(width 0.4572)
		(layer "F.Cu")
		(net "P52V_HS_4287_S2N")
	)
	(segment
		(start 304.845466 -39.345616)
		(end 304.845466 -38.1762)
		(width 0.4572)
		(layer "F.Cu")
		(net "P52V_HS_4287_S2N")
	)
	(segment
		(start 305.099466 -37.9222)
		(end 305.9938 -37.9222)
		(width 0.4572)
		(layer "F.Cu")
		(net "P52V_HS_4287_S2N")
	)
	(segment
		(start 304.94605 -40.712136)
		(end 304.94605 -39.4462)
		(width 0.4572)
		(layer "F.Cu")
		(net "P52V_HS_4287_S2N")
	)
	(segment
		(start 304.94605 -39.4462)
		(end 304.845466 -39.345616)
		(width 0.4572)
		(layer "F.Cu")
		(net "P52V_HS_4287_S2N")
	)
	(via
		(at 304.94605 -40.712136)
		(size 0.762)
		(drill 0.254)
		(layers "F.Cu" "B.Cu")
		(net "P52V_HS_4287_S2N")
	)
	(segment
		(start 298.31792 -67.79133)
		(end 297.395646 -67.79133)
		(width 0.254)
		(layer "B.Cu")
		(net "P52V_HS_4287_S2N")
	)
	(segment
		(start 306.109116 -42.33799)
		(end 306.109116 -64.931036)
		(width 0.4572)
		(layer "B.Cu")
		(net "P52V_HS_4287_S2N")
	)
	(segment
		(start 300.341538 -68.957698)
		(end 299.290486 -67.906646)
		(width 0.4572)
		(layer "B.Cu")
		(net "P52V_HS_4287_S2N")
	)
	(segment
		(start 298.433236 -67.906646)
		(end 298.31792 -67.79133)
		(width 0.254)
		(layer "B.Cu")
		(net "P52V_HS_4287_S2N")
	)
	(segment
		(start 299.290486 -67.906646)
		(end 298.433236 -67.906646)
		(width 0.4572)
		(layer "B.Cu")
		(net "P52V_HS_4287_S2N")
	)
	(segment
		(start 306.109116 -64.931036)
		(end 302.082454 -68.957698)
		(width 0.4572)
		(layer "B.Cu")
		(net "P52V_HS_4287_S2N")
	)
	(segment
		(start 297.395646 -67.79133)
		(end 297.332908 -67.854068)
		(width 0.254)
		(layer "B.Cu")
		(net "P52V_HS_4287_S2N")
	)
	(segment
		(start 302.082454 -68.957698)
		(end 300.341538 -68.957698)
		(width 0.4572)
		(layer "B.Cu")
		(net "P52V_HS_4287_S2N")
	)
	(segment
		(start 304.94605 -41.174924)
		(end 306.109116 -42.33799)
		(width 0.4572)
		(layer "B.Cu")
		(net "P52V_HS_4287_S2N")
	)
	(segment
		(start 304.94605 -40.712136)
		(end 304.94605 -41.174924)
		(width 0.4572)
		(layer "B.Cu")
		(net "P52V_HS_4287_S2N")
	)
	(segment
		(start 297.332908 -67.854068)
		(end 296.922444 -67.854068)
		(width 0.254)
		(layer "B.Cu")
		(net "P52V_HS_4287_S2N")
	)
	(segment
		(start 304.840386 -73.173336)
		(end 304.94605 -73.279)
		(width 0.4572)
		(layer "F.Cu")
		(net "P52V_HS_4287_S1N")
	)
	(segment
		(start 305.181 -74.494136)
		(end 304.94605 -74.259186)
		(width 0.4572)
		(layer "F.Cu")
		(net "P52V_HS_4287_S1N")
	)
	(segment
		(start 304.94605 -74.259186)
		(end 304.94605 -73.279)
		(width 0.4572)
		(layer "F.Cu")
		(net "P52V_HS_4287_S1N")
	)
	(segment
		(start 304.840386 -72.009)
		(end 304.840386 -73.173336)
		(width 0.4572)
		(layer "F.Cu")
		(net "P52V_HS_4287_S1N")
	)
	(segment
		(start 305.094386 -71.755)
		(end 304.840386 -72.009)
		(width 0.4572)
		(layer "F.Cu")
		(net "P52V_HS_4287_S1N")
	)
	(segment
		(start 305.9938 -71.755)
		(end 305.094386 -71.755)
		(width 0.4572)
		(layer "F.Cu")
		(net "P52V_HS_4287_S1N")
	)
	(via
		(at 305.181 -74.494136)
		(size 0.762)
		(drill 0.254)
		(layers "F.Cu" "B.Cu")
		(net "P52V_HS_4287_S1N")
	)
	(segment
		(start 299.389038 -70.173596)
		(end 299.389038 -70.012306)
		(width 0.254)
		(layer "B.Cu")
		(net "P52V_HS_4287_S1N")
	)
	(segment
		(start 302.933862 -75.932792)
		(end 301.905924 -74.904854)
		(width 0.4572)
		(layer "B.Cu")
		(net "P52V_HS_4287_S1N")
	)
	(segment
		(start 304.836322 -75.108054)
		(end 304.011584 -75.932792)
		(width 0.4572)
		(layer "B.Cu")
		(net "P52V_HS_4287_S1N")
	)
	(segment
		(start 299.389038 -70.012306)
		(end 298.667932 -69.2912)
		(width 0.254)
		(layer "B.Cu")
		(net "P52V_HS_4287_S1N")
	)
	(segment
		(start 301.905924 -74.904854)
		(end 301.905924 -72.690482)
		(width 0.4572)
		(layer "B.Cu")
		(net "P52V_HS_4287_S1N")
	)
	(segment
		(start 297.332908 -69.353938)
		(end 296.922444 -69.353938)
		(width 0.254)
		(layer "B.Cu")
		(net "P52V_HS_4287_S1N")
	)
	(segment
		(start 298.667932 -69.2912)
		(end 297.395646 -69.2912)
		(width 0.254)
		(layer "B.Cu")
		(net "P52V_HS_4287_S1N")
	)
	(segment
		(start 304.836322 -74.838814)
		(end 304.836322 -75.108054)
		(width 0.4572)
		(layer "B.Cu")
		(net "P52V_HS_4287_S1N")
	)
	(segment
		(start 301.905924 -72.690482)
		(end 299.389038 -70.173596)
		(width 0.4572)
		(layer "B.Cu")
		(net "P52V_HS_4287_S1N")
	)
	(segment
		(start 297.395646 -69.2912)
		(end 297.332908 -69.353938)
		(width 0.254)
		(layer "B.Cu")
		(net "P52V_HS_4287_S1N")
	)
	(segment
		(start 304.011584 -75.932792)
		(end 302.933862 -75.932792)
		(width 0.4572)
		(layer "B.Cu")
		(net "P52V_HS_4287_S1N")
	)
	(segment
		(start 305.181 -74.494136)
		(end 304.836322 -74.838814)
		(width 0.4572)
		(layer "B.Cu")
		(net "P52V_HS_4287_S1N")
	)
	(segment
		(start 303.149 -71.755)
		(end 303.99228 -71.755)
		(width 0.4572)
		(layer "F.Cu")
		(net "P52V_HS_4287_S1P")
	)
	(segment
		(start 304.24628 -73.17867)
		(end 304.14595 -73.279)
		(width 0.4572)
		(layer "F.Cu")
		(net "P52V_HS_4287_S1P")
	)
	(segment
		(start 304.14595 -74.259186)
		(end 304.14595 -73.279)
		(width 0.4572)
		(layer "F.Cu")
		(net "P52V_HS_4287_S1P")
	)
	(segment
		(start 303.911 -74.494136)
		(end 304.14595 -74.259186)
		(width 0.4572)
		(layer "F.Cu")
		(net "P52V_HS_4287_S1P")
	)
	(segment
		(start 304.24628 -72.009)
		(end 304.24628 -73.17867)
		(width 0.4572)
		(layer "F.Cu")
		(net "P52V_HS_4287_S1P")
	)
	(segment
		(start 303.99228 -71.755)
		(end 304.24628 -72.009)
		(width 0.4572)
		(layer "F.Cu")
		(net "P52V_HS_4287_S1P")
	)
	(via
		(at 303.911 -74.494136)
		(size 0.762)
		(drill 0.254)
		(layers "F.Cu" "B.Cu")
		(net "P52V_HS_4287_S1P")
	)
	(segment
		(start 304.165 -74.942192)
		(end 303.7586 -75.348592)
		(width 0.4572)
		(layer "B.Cu")
		(net "P52V_HS_4287_S1P")
	)
	(segment
		(start 304.165 -74.748136)
		(end 304.165 -74.942192)
		(width 0.4572)
		(layer "B.Cu")
		(net "P52V_HS_4287_S1P")
	)
	(segment
		(start 299.676058 -69.760338)
		(end 298.82592 -68.9102)
		(width 0.254)
		(layer "B.Cu")
		(net "P52V_HS_4287_S1P")
	)
	(segment
		(start 297.352212 -68.854066)
		(end 296.922444 -68.854066)
		(width 0.254)
		(layer "B.Cu")
		(net "P52V_HS_4287_S1P")
	)
	(segment
		(start 302.490124 -72.44842)
		(end 299.802042 -69.760338)
		(width 0.4572)
		(layer "B.Cu")
		(net "P52V_HS_4287_S1P")
	)
	(segment
		(start 297.408346 -68.9102)
		(end 297.352212 -68.854066)
		(width 0.254)
		(layer "B.Cu")
		(net "P52V_HS_4287_S1P")
	)
	(segment
		(start 298.82592 -68.9102)
		(end 297.408346 -68.9102)
		(width 0.254)
		(layer "B.Cu")
		(net "P52V_HS_4287_S1P")
	)
	(segment
		(start 303.175924 -75.348592)
		(end 302.490124 -74.662792)
		(width 0.4572)
		(layer "B.Cu")
		(net "P52V_HS_4287_S1P")
	)
	(segment
		(start 303.911 -74.494136)
		(end 304.165 -74.748136)
		(width 0.4572)
		(layer "B.Cu")
		(net "P52V_HS_4287_S1P")
	)
	(segment
		(start 303.7586 -75.348592)
		(end 303.175924 -75.348592)
		(width 0.4572)
		(layer "B.Cu")
		(net "P52V_HS_4287_S1P")
	)
	(segment
		(start 299.802042 -69.760338)
		(end 299.676058 -69.760338)
		(width 0.254)
		(layer "B.Cu")
		(net "P52V_HS_4287_S1P")
	)
	(segment
		(start 302.490124 -74.662792)
		(end 302.490124 -72.44842)
		(width 0.4572)
		(layer "B.Cu")
		(net "P52V_HS_4287_S1P")
	)
	(segment
		(start 301.6758 -37.9222)
		(end 301.6758 -36.1442)
		(width 0.4572)
		(layer "F.Cu")
		(net "P52V_HS1_SENSE_P_R2")
	)
	(segment
		(start 304.1904 -29.5402)
		(end 304.616358 -29.966158)
		(width 0.254)
		(layer "F.Cu")
		(net "P52V_HS1_SENSE_P_R2")
	)
	(segment
		(start 303.839626 -29.5402)
		(end 304.1904 -29.5402)
		(width 0.254)
		(layer "F.Cu")
		(net "P52V_HS1_SENSE_P_R2")
	)
	(segment
		(start 301.6758 -34.3662)
		(end 301.6758 -33.6296)
		(width 0.4572)
		(layer "F.Cu")
		(net "P52V_HS1_SENSE_P_R2")
	)
	(segment
		(start 301.6758 -36.1442)
		(end 301.6758 -34.3662)
		(width 0.4572)
		(layer "F.Cu")
		(net "P52V_HS1_SENSE_P_R2")
	)
	(segment
		(start 304.616358 -29.966158)
		(end 304.616358 -30.093158)
		(width 0.254)
		(layer "F.Cu")
		(net "P52V_HS1_SENSE_P_R2")
	)
	(via
		(at 304.616358 -30.093158)
		(size 0.508)
		(drill 0.254)
		(layers "F.Cu" "B.Cu")
		(net "P52V_HS1_SENSE_P_R2")
	)
	(via
		(at 301.6758 -33.6296)
		(size 0.508)
		(drill 0.254)
		(layers "F.Cu" "B.Cu")
		(net "P52V_HS1_SENSE_P_R2")
	)
	(segment
		(start 303.797716 -33.6296)
		(end 304.616358 -32.810958)
		(width 0.4572)
		(layer "In2.Cu")
		(net "P52V_HS1_SENSE_P_R2")
	)
	(segment
		(start 301.6758 -33.6296)
		(end 303.797716 -33.6296)
		(width 0.4572)
		(layer "In2.Cu")
		(net "P52V_HS1_SENSE_P_R2")
	)
	(segment
		(start 304.616358 -32.810958)
		(end 304.616358 -30.093158)
		(width 0.4572)
		(layer "In2.Cu")
		(net "P52V_HS1_SENSE_P_R2")
	)
	(via
		(at 287.4264 -71.882)
		(size 0.6604)
		(drill 0.3302)
		(layers "F.Cu" "B.Cu")
		(net "SMB_P52V_PDB_SCL_R3")
	)
	(segment
		(start 288.1884 -71.882)
		(end 287.4264 -71.882)
		(width 0.17272)
		(layer "B.Cu")
		(net "SMB_P52V_PDB_SCL_R3")
	)
	(segment
		(start 290.122356 -71.353934)
		(end 288.716466 -71.353934)
		(width 0.17272)
		(layer "B.Cu")
		(net "SMB_P52V_PDB_SCL_R3")
	)
	(segment
		(start 286.30245 -71.882)
		(end 287.4264 -71.882)
		(width 0.17272)
		(layer "B.Cu")
		(net "SMB_P52V_PDB_SCL_R3")
	)
	(segment
		(start 288.716466 -71.353934)
		(end 288.1884 -71.882)
		(width 0.17272)
		(layer "B.Cu")
		(net "SMB_P52V_PDB_SCL_R3")
	)
	(via
		(at 342.9 -39.3192)
		(size 0.6604)
		(drill 0.3302)
		(layers "F.Cu" "B.Cu")
		(net "P52V_HS1_4287_GATE2_RC")
	)
	(segment
		(start 342.6968 -39.5224)
		(end 341.5792 -39.5224)
		(width 0.508)
		(layer "B.Cu")
		(net "P52V_HS1_4287_GATE2_RC")
	)
	(segment
		(start 342.7984 -37.973)
		(end 342.7984 -39.2176)
		(width 0.508)
		(layer "B.Cu")
		(net "P52V_HS1_4287_GATE2_RC")
	)
	(segment
		(start 342.9 -39.3192)
		(end 342.6968 -39.5224)
		(width 0.508)
		(layer "B.Cu")
		(net "P52V_HS1_4287_GATE2_RC")
	)
	(segment
		(start 342.7984 -39.2176)
		(end 342.9 -39.3192)
		(width 0.508)
		(layer "B.Cu")
		(net "P52V_HS1_4287_GATE2_RC")
	)
	(via
		(at 341.757 -42.037)
		(size 0.6604)
		(drill 0.3302)
		(layers "F.Cu" "B.Cu")
		(net "P52V_HS1_GATE2_R1")
	)
	(segment
		(start 340.3854 -38.93185)
		(end 340.3854 -39.37381)
		(width 0.4572)
		(layer "B.Cu")
		(net "P52V_HS1_GATE2_R1")
	)
	(segment
		(start 340.6648 -40.9448)
		(end 340.6648 -40.7162)
		(width 0.508)
		(layer "B.Cu")
		(net "P52V_HS1_GATE2_R1")
	)
	(segment
		(start 340.6648 -40.7162)
		(end 339.9536 -40.7162)
		(width 0.508)
		(layer "B.Cu")
		(net "P52V_HS1_GATE2_R1")
	)
	(segment
		(start 341.757 -42.037)
		(end 340.6648 -40.9448)
		(width 0.508)
		(layer "B.Cu")
		(net "P52V_HS1_GATE2_R1")
	)
	(segment
		(start 339.5726 -40.3352)
		(end 338.8614 -40.3352)
		(width 0.508)
		(layer "B.Cu")
		(net "P52V_HS1_GATE2_R1")
	)
	(segment
		(start 340.3854 -39.37381)
		(end 340.6648 -39.65321)
		(width 0.508)
		(layer "B.Cu")
		(net "P52V_HS1_GATE2_R1")
	)
	(segment
		(start 339.9536 -40.7162)
		(end 339.5726 -40.3352)
		(width 0.508)
		(layer "B.Cu")
		(net "P52V_HS1_GATE2_R1")
	)
	(segment
		(start 340.6648 -39.65321)
		(end 340.6648 -40.7162)
		(width 0.508)
		(layer "B.Cu")
		(net "P52V_HS1_GATE2_R1")
	)
	(segment
		(start 287.556702 -70.285102)
		(end 287.8074 -70.5358)
		(width 0.17272)
		(layer "F.Cu")
		(net "P52V_HS1_SCK")
	)
	(segment
		(start 287.8074 -70.5358)
		(end 287.8074 -77.50302)
		(width 0.17272)
		(layer "F.Cu")
		(net "P52V_HS1_SCK")
	)
	(segment
		(start 287.8074 -77.50302)
		(end 287.14954 -78.16088)
		(width 0.17272)
		(layer "F.Cu")
		(net "P52V_HS1_SCK")
	)
	(segment
		(start 287.556702 -69.723)
		(end 287.556702 -70.285102)
		(width 0.17272)
		(layer "F.Cu")
		(net "P52V_HS1_SCK")
	)
	(via
		(at 287.14954 -78.16088)
		(size 0.508)
		(drill 0.254)
		(layers "F.Cu" "B.Cu")
		(net "P52V_HS1_SCK")
	)
	(via
		(at 287.8074 -70.5358)
		(size 0.762)
		(drill 0.381)
		(layers "F.Cu" "B.Cu")
		(net "P52V_HS1_SCK")
	)
	(via
		(at 287.556702 -69.723)
		(size 0.508)
		(drill 0.254)
		(layers "F.Cu" "B.Cu")
		(net "P52V_HS1_SCK")
	)
	(segment
		(start 290.122356 -70.353936)
		(end 289.115754 -70.353936)
		(width 0.17272)
		(layer "B.Cu")
		(net "P52V_HS1_SCK")
	)
	(segment
		(start 286.30245 -69.723)
		(end 286.2834 -69.74205)
		(width 0.17272)
		(layer "B.Cu")
		(net "P52V_HS1_SCK")
	)
	(segment
		(start 286.2834 -69.74205)
		(end 285.3055 -69.74205)
		(width 0.17272)
		(layer "B.Cu")
		(net "P52V_HS1_SCK")
	)
	(segment
		(start 287.556702 -69.723)
		(end 286.30245 -69.723)
		(width 0.17272)
		(layer "B.Cu")
		(net "P52V_HS1_SCK")
	)
	(segment
		(start 289.115754 -70.353936)
		(end 288.484818 -69.723)
		(width 0.17272)
		(layer "B.Cu")
		(net "P52V_HS1_SCK")
	)
	(segment
		(start 288.484818 -69.723)
		(end 287.556702 -69.723)
		(width 0.17272)
		(layer "B.Cu")
		(net "P52V_HS1_SCK")
	)
	(segment
		(start 285.3055 -69.74205)
		(end 285.28645 -69.723)
		(width 0.17272)
		(layer "B.Cu")
		(net "P52V_HS1_SCK")
	)
	(segment
		(start 284.881828 -78.16088)
		(end 287.14954 -78.16088)
		(width 0.17272)
		(layer "B.Cu")
		(net "P52V_HS1_SCK")
	)
	(segment
		(start 288.339276 -71.058786)
		(end 288.339276 -77.833982)
		(width 0.17272)
		(layer "F.Cu")
		(net "P52V_HS1_CS")
	)
	(segment
		(start 288.339276 -77.833982)
		(end 289.9664 -79.461106)
		(width 0.17272)
		(layer "F.Cu")
		(net "P52V_HS1_CS")
	)
	(segment
		(start 288.544 -70.854062)
		(end 288.339276 -71.058786)
		(width 0.17272)
		(layer "F.Cu")
		(net "P52V_HS1_CS")
	)
	(via
		(at 288.544 -70.854062)
		(size 0.508)
		(drill 0.254)
		(layers "F.Cu" "B.Cu")
		(net "P52V_HS1_CS")
	)
	(via
		(at 287.898586 -70.427088)
		(size 0.6604)
		(drill 0.3302)
		(layers "F.Cu" "B.Cu")
		(net "P52V_HS1_CS")
	)
	(via
		(at 289.9664 -79.461106)
		(size 0.508)
		(drill 0.254)
		(layers "F.Cu" "B.Cu")
		(net "P52V_HS1_CS")
	)
	(segment
		(start 290.122356 -70.854062)
		(end 288.544 -70.854062)
		(width 0.17272)
		(layer "B.Cu")
		(net "P52V_HS1_CS")
	)
	(segment
		(start 290.986972 -79.461106)
		(end 289.9664 -79.461106)
		(width 0.17272)
		(layer "B.Cu")
		(net "P52V_HS1_CS")
	)
	(segment
		(start 286.30245 -70.739)
		(end 287.586674 -70.739)
		(width 0.17272)
		(layer "B.Cu")
		(net "P52V_HS1_CS")
	)
	(segment
		(start 288.117026 -70.427088)
		(end 288.544 -70.854062)
		(width 0.17272)
		(layer "B.Cu")
		(net "P52V_HS1_CS")
	)
	(segment
		(start 287.586674 -70.739)
		(end 287.898586 -70.427088)
		(width 0.17272)
		(layer "B.Cu")
		(net "P52V_HS1_CS")
	)
	(segment
		(start 287.898586 -70.427088)
		(end 288.117026 -70.427088)
		(width 0.17272)
		(layer "B.Cu")
		(net "P52V_HS1_CS")
	)
	(segment
		(start 287.521904 -67.945)
		(end 287.0454 -68.421504)
		(width 0.17272)
		(layer "F.Cu")
		(net "P52V_HS1_SIO")
	)
	(segment
		(start 287.0454 -68.421504)
		(end 287.0454 -77.514196)
		(width 0.17272)
		(layer "F.Cu")
		(net "P52V_HS1_SIO")
	)
	(via
		(at 287.0454 -77.514196)
		(size 0.508)
		(drill 0.254)
		(layers "F.Cu" "B.Cu")
		(net "P52V_HS1_SIO")
	)
	(via
		(at 287.521904 -67.945)
		(size 0.762)
		(drill 0.254)
		(layers "F.Cu" "B.Cu")
		(net "P52V_HS1_SIO")
	)
	(segment
		(start 287.521904 -67.945)
		(end 286.30245 -67.945)
		(width 0.17272)
		(layer "B.Cu")
		(net "P52V_HS1_SIO")
	)
	(segment
		(start 287.042098 -77.510894)
		(end 287.0454 -77.514196)
		(width 0.17272)
		(layer "B.Cu")
		(net "P52V_HS1_SIO")
	)
	(segment
		(start 288.08045 -68.503546)
		(end 287.521904 -67.945)
		(width 0.17272)
		(layer "B.Cu")
		(net "P52V_HS1_SIO")
	)
	(segment
		(start 288.08045 -68.58)
		(end 288.08045 -68.503546)
		(width 0.17272)
		(layer "B.Cu")
		(net "P52V_HS1_SIO")
	)
	(segment
		(start 291.850826 -77.298296)
		(end 291.850826 -78.373478)
		(width 0.17272)
		(layer "B.Cu")
		(net "P52V_HS1_SIO")
	)
	(segment
		(start 290.122356 -69.854064)
		(end 289.354514 -69.854064)
		(width 0.17272)
		(layer "B.Cu")
		(net "P52V_HS1_SIO")
	)
	(segment
		(start 287.048702 -77.510894)
		(end 287.786826 -77.510894)
		(width 0.17272)
		(layer "B.Cu")
		(net "P52V_HS1_SIO")
	)
	(segment
		(start 284.881828 -77.510894)
		(end 287.042098 -77.510894)
		(width 0.17272)
		(layer "B.Cu")
		(net "P52V_HS1_SIO")
	)
	(segment
		(start 291.413184 -78.81112)
		(end 290.986972 -78.81112)
		(width 0.17272)
		(layer "B.Cu")
		(net "P52V_HS1_SIO")
	)
	(segment
		(start 287.786826 -77.510894)
		(end 288.440622 -76.857098)
		(width 0.17272)
		(layer "B.Cu")
		(net "P52V_HS1_SIO")
	)
	(segment
		(start 287.0454 -77.514196)
		(end 287.048702 -77.510894)
		(width 0.17272)
		(layer "B.Cu")
		(net "P52V_HS1_SIO")
	)
	(segment
		(start 291.850826 -78.373478)
		(end 291.413184 -78.81112)
		(width 0.17272)
		(layer "B.Cu")
		(net "P52V_HS1_SIO")
	)
	(segment
		(start 289.354514 -69.854064)
		(end 288.08045 -68.58)
		(width 0.17272)
		(layer "B.Cu")
		(net "P52V_HS1_SIO")
	)
	(segment
		(start 291.409628 -76.857098)
		(end 291.850826 -77.298296)
		(width 0.17272)
		(layer "B.Cu")
		(net "P52V_HS1_SIO")
	)
	(segment
		(start 288.440622 -76.857098)
		(end 291.409628 -76.857098)
		(width 0.17272)
		(layer "B.Cu")
		(net "P52V_HS1_SIO")
	)
	(via
		(at 288.1884 -65.67805)
		(size 0.6604)
		(drill 0.3302)
		(layers "F.Cu" "B.Cu")
		(net "P52V_HS1_TMR")
	)
	(segment
		(start 286.2834 -65.67805)
		(end 285.1785 -65.67805)
		(width 0.17272)
		(layer "B.Cu")
		(net "P52V_HS1_TMR")
	)
	(segment
		(start 289.0774 -67.131438)
		(end 289.0774 -66.548)
		(width 0.17272)
		(layer "B.Cu")
		(net "P52V_HS1_TMR")
	)
	(segment
		(start 290.122356 -67.854068)
		(end 289.80003 -67.854068)
		(width 0.17272)
		(layer "B.Cu")
		(net "P52V_HS1_TMR")
	)
	(segment
		(start 289.0774 -66.548)
		(end 288.20745 -65.67805)
		(width 0.17272)
		(layer "B.Cu")
		(net "P52V_HS1_TMR")
	)
	(segment
		(start 289.80003 -67.854068)
		(end 289.0774 -67.131438)
		(width 0.17272)
		(layer "B.Cu")
		(net "P52V_HS1_TMR")
	)
	(segment
		(start 288.20745 -65.67805)
		(end 288.1884 -65.67805)
		(width 0.17272)
		(layer "B.Cu")
		(net "P52V_HS1_TMR")
	)
	(segment
		(start 285.1785 -65.67805)
		(end 285.15945 -65.659)
		(width 0.17272)
		(layer "B.Cu")
		(net "P52V_HS1_TMR")
	)
	(segment
		(start 286.2834 -65.67805)
		(end 288.1884 -65.67805)
		(width 0.17272)
		(layer "B.Cu")
		(net "P52V_HS1_TMR")
	)
	(segment
		(start 293.913052 -76.962)
		(end 293.5224 -77.352652)
		(width 0.254)
		(layer "F.Cu")
		(net "P52V_HS1_TEMP")
	)
	(segment
		(start 315.69025 -85.09)
		(end 316.19825 -85.598)
		(width 0.254)
		(layer "F.Cu")
		(net "P52V_HS1_TEMP")
	)
	(segment
		(start 293.5224 -77.352652)
		(end 293.5224 -80.325722)
		(width 0.254)
		(layer "F.Cu")
		(net "P52V_HS1_TEMP")
	)
	(segment
		(start 316.19825 -85.598)
		(end 316.80785 -85.598)
		(width 0.254)
		(layer "F.Cu")
		(net "P52V_HS1_TEMP")
	)
	(segment
		(start 293.5224 -80.325722)
		(end 298.286678 -85.09)
		(width 0.254)
		(layer "F.Cu")
		(net "P52V_HS1_TEMP")
	)
	(segment
		(start 298.286678 -85.09)
		(end 315.69025 -85.09)
		(width 0.254)
		(layer "F.Cu")
		(net "P52V_HS1_TEMP")
	)
	(via
		(at 292.772338 -74.84237)
		(size 0.6604)
		(drill 0.3302)
		(layers "F.Cu" "B.Cu")
		(net "P52V_HS1_TEMP")
	)
	(via
		(at 293.913052 -76.962)
		(size 0.508)
		(drill 0.254)
		(layers "F.Cu" "B.Cu")
		(net "P52V_HS1_TEMP")
	)
	(segment
		(start 292.772338 -74.9554)
		(end 292.772338 -74.84237)
		(width 0.17272)
		(layer "B.Cu")
		(net "P52V_HS1_TEMP")
	)
	(segment
		(start 293.2684 -75.451462)
		(end 292.772338 -74.9554)
		(width 0.17272)
		(layer "B.Cu")
		(net "P52V_HS1_TEMP")
	)
	(segment
		(start 293.913052 -76.30795)
		(end 293.659052 -76.05395)
		(width 0.254)
		(layer "B.Cu")
		(net "P52V_HS1_TEMP")
	)
	(segment
		(start 293.659052 -76.05395)
		(end 293.2684 -76.05395)
		(width 0.254)
		(layer "B.Cu")
		(net "P52V_HS1_TEMP")
	)
	(segment
		(start 292.772338 -74.84237)
		(end 292.772338 -73.504044)
		(width 0.17272)
		(layer "B.Cu")
		(net "P52V_HS1_TEMP")
	)
	(segment
		(start 293.913052 -76.962)
		(end 293.913052 -76.30795)
		(width 0.254)
		(layer "B.Cu")
		(net "P52V_HS1_TEMP")
	)
	(segment
		(start 293.2684 -76.05395)
		(end 293.2684 -75.451462)
		(width 0.17272)
		(layer "B.Cu")
		(net "P52V_HS1_TEMP")
	)
	(via
		(at 284.48 -80.645)
		(size 0.6604)
		(drill 0.3302)
		(layers "F.Cu" "B.Cu")
		(net "P52V_HS1_DVCC")
	)
	(via
		(at 285.2674 -81.153)
		(size 0.508)
		(drill 0.254)
		(layers "F.Cu" "B.Cu")
		(net "P52V_HS1_DVCC")
	)
	(via
		(at 284.48 -82.042)
		(size 0.6604)
		(drill 0.3302)
		(layers "F.Cu" "B.Cu")
		(net "P52V_HS1_DVCC")
	)
	(via
		(at 285.2674 -81.915)
		(size 0.762)
		(drill 0.254)
		(layers "F.Cu" "B.Cu")
		(net "P52V_HS1_DVCC")
	)
	(via
		(at 293.12235 -62.738)
		(size 0.508)
		(drill 0.254)
		(layers "F.Cu" "B.Cu")
		(net "P52V_HS1_DVCC")
	)
	(segment
		(start 288.407602 -78.16088)
		(end 290.986972 -78.16088)
		(width 0.381)
		(layer "B.Cu")
		(net "P52V_HS1_DVCC")
	)
	(segment
		(start 292.272466 -66.703956)
		(end 292.272466 -65.384934)
		(width 0.2794)
		(layer "B.Cu")
		(net "P52V_HS1_DVCC")
	)
	(segment
		(start 293.12235 -63.373)
		(end 293.12235 -62.738)
		(width 0.2794)
		(layer "B.Cu")
		(net "P52V_HS1_DVCC")
	)
	(segment
		(start 292.272466 -65.384934)
		(end 293.12235 -64.53505)
		(width 0.2794)
		(layer "B.Cu")
		(net "P52V_HS1_DVCC")
	)
	(segment
		(start 293.12235 -64.53505)
		(end 293.12235 -63.373)
		(width 0.2794)
		(layer "B.Cu")
		(net "P52V_HS1_DVCC")
	)
	(segment
		(start 284.881828 -78.81112)
		(end 287.757362 -78.81112)
		(width 0.381)
		(layer "B.Cu")
		(net "P52V_HS1_DVCC")
	)
	(segment
		(start 287.757362 -78.81112)
		(end 288.407602 -78.16088)
		(width 0.381)
		(layer "B.Cu")
		(net "P52V_HS1_DVCC")
	)
	(segment
		(start 294.6654 -65.853056)
		(end 294.6654 -70.866)
		(width 0.4572)
		(layer "In2.Cu")
		(net "P52V_HS1_DVCC")
	)
	(segment
		(start 295.6306 -79.1972)
		(end 294.3352 -80.4926)
		(width 0.4572)
		(layer "In2.Cu")
		(net "P52V_HS1_DVCC")
	)
	(segment
		(start 288.9504 -80.4926)
		(end 288.29 -81.153)
		(width 0.4572)
		(layer "In2.Cu")
		(net "P52V_HS1_DVCC")
	)
	(segment
		(start 293.12235 -62.738)
		(end 293.2684 -62.88405)
		(width 0.4572)
		(layer "In2.Cu")
		(net "P52V_HS1_DVCC")
	)
	(segment
		(start 294.3352 -80.4926)
		(end 288.9504 -80.4926)
		(width 0.4572)
		(layer "In2.Cu")
		(net "P52V_HS1_DVCC")
	)
	(segment
		(start 288.29 -81.153)
		(end 285.2674 -81.153)
		(width 0.4572)
		(layer "In2.Cu")
		(net "P52V_HS1_DVCC")
	)
	(segment
		(start 293.2684 -64.456056)
		(end 294.6654 -65.853056)
		(width 0.4572)
		(layer "In2.Cu")
		(net "P52V_HS1_DVCC")
	)
	(segment
		(start 293.2684 -62.88405)
		(end 293.2684 -64.456056)
		(width 0.4572)
		(layer "In2.Cu")
		(net "P52V_HS1_DVCC")
	)
	(segment
		(start 294.6654 -70.866)
		(end 295.6306 -71.8312)
		(width 0.4572)
		(layer "In2.Cu")
		(net "P52V_HS1_DVCC")
	)
	(segment
		(start 295.6306 -71.8312)
		(end 295.6306 -79.1972)
		(width 0.4572)
		(layer "In2.Cu")
		(net "P52V_HS1_DVCC")
	)
	(via
		(at 341.0966 -53.2384)
		(size 0.6604)
		(drill 0.3302)
		(layers "F.Cu" "B.Cu")
		(net "P52V_HS1_GATE_R1")
	)
	(segment
		(start 340.5124 -50.15865)
		(end 340.5124 -50.647854)
		(width 0.4572)
		(layer "B.Cu")
		(net "P52V_HS1_GATE_R1")
	)
	(segment
		(start 340.6648 -51.9176)
		(end 340.6648 -52.8066)
		(width 0.508)
		(layer "B.Cu")
		(net "P52V_HS1_GATE_R1")
	)
	(segment
		(start 340.6648 -52.8066)
		(end 341.0966 -53.2384)
		(width 0.508)
		(layer "B.Cu")
		(net "P52V_HS1_GATE_R1")
	)
	(segment
		(start 339.5726 -51.6128)
		(end 339.8774 -51.9176)
		(width 0.508)
		(layer "B.Cu")
		(net "P52V_HS1_GATE_R1")
	)
	(segment
		(start 339.8774 -51.9176)
		(end 340.6648 -51.9176)
		(width 0.508)
		(layer "B.Cu")
		(net "P52V_HS1_GATE_R1")
	)
	(segment
		(start 338.8614 -51.6128)
		(end 339.5726 -51.6128)
		(width 0.508)
		(layer "B.Cu")
		(net "P52V_HS1_GATE_R1")
	)
	(segment
		(start 340.6648 -50.800254)
		(end 340.6648 -51.9176)
		(width 0.508)
		(layer "B.Cu")
		(net "P52V_HS1_GATE_R1")
	)
	(segment
		(start 340.5124 -50.647854)
		(end 340.6648 -50.800254)
		(width 0.508)
		(layer "B.Cu")
		(net "P52V_HS1_GATE_R1")
	)
	(via
		(at 296.512234 -75.24496)
		(size 0.6604)
		(drill 0.3302)
		(layers "F.Cu" "B.Cu")
		(net "P52V_HS1_VDSFB")
	)
	(via
		(at 287.6804 -64.008)
		(size 0.6604)
		(drill 0.3302)
		(layers "F.Cu" "B.Cu")
		(net "HS1_TMR1")
	)
	(segment
		(start 287.6804 -64.389)
		(end 287.19145 -64.87795)
		(width 0.17272)
		(layer "B.Cu")
		(net "HS1_TMR1")
	)
	(segment
		(start 285.92145 -64.516)
		(end 286.2834 -64.87795)
		(width 0.17272)
		(layer "B.Cu")
		(net "HS1_TMR1")
	)
	(segment
		(start 287.31845 -63.64605)
		(end 287.6804 -64.008)
		(width 0.17272)
		(layer "B.Cu")
		(net "HS1_TMR1")
	)
	(segment
		(start 285.15945 -64.516)
		(end 285.92145 -64.516)
		(width 0.17272)
		(layer "B.Cu")
		(net "HS1_TMR1")
	)
	(segment
		(start 287.19145 -64.87795)
		(end 286.2834 -64.87795)
		(width 0.17272)
		(layer "B.Cu")
		(net "HS1_TMR1")
	)
	(segment
		(start 287.6804 -64.008)
		(end 287.6804 -64.389)
		(width 0.17272)
		(layer "B.Cu")
		(net "HS1_TMR1")
	)
	(segment
		(start 286.2834 -63.64605)
		(end 287.31845 -63.64605)
		(width 0.17272)
		(layer "B.Cu")
		(net "HS1_TMR1")
	)
	(segment
		(start 260.18744 -48.387)
		(end 260.18744 -47.05096)
		(width 0.17272)
		(layer "F.Cu")
		(net "P52V_1_FUSE_1")
	)
	(segment
		(start 260.18744 -47.05096)
		(end 260.2484 -46.99)
		(width 0.17272)
		(layer "F.Cu")
		(net "P52V_1_FUSE_1")
	)
	(via
		(at 249.809 -46.99)
		(size 0.508)
		(drill 0.254)
		(layers "F.Cu" "B.Cu")
		(net "P52V_1_FUSE_1")
	)
	(via
		(at 248.285 -47.752)
		(size 0.508)
		(drill 0.254)
		(layers "F.Cu" "B.Cu")
		(net "P52V_1_FUSE_1")
	)
	(via
		(at 260.2484 -46.99)
		(size 0.508)
		(drill 0.254)
		(layers "F.Cu" "B.Cu")
		(net "P52V_1_FUSE_1")
	)
	(via
		(at 254.254 -46.99)
		(size 0.508)
		(drill 0.254)
		(layers "F.Cu" "B.Cu")
		(net "P52V_1_FUSE_1")
	)
	(via
		(at 255.778 -47.752)
		(size 0.508)
		(drill 0.254)
		(layers "F.Cu" "B.Cu")
		(net "P52V_1_FUSE_1")
	)
	(via
		(at 257.302 -47.752)
		(size 0.508)
		(drill 0.254)
		(layers "F.Cu" "B.Cu")
		(net "P52V_1_FUSE_1")
	)
	(via
		(at 249.047 -46.99)
		(size 0.762)
		(drill 0.254)
		(layers "F.Cu" "B.Cu")
		(net "P52V_1_FUSE_1")
	)
	(via
		(at 247.523 -46.99)
		(size 0.508)
		(drill 0.254)
		(layers "F.Cu" "B.Cu")
		(net "P52V_1_FUSE_1")
	)
	(via
		(at 256.54 -47.752)
		(size 0.508)
		(drill 0.254)
		(layers "F.Cu" "B.Cu")
		(net "P52V_1_FUSE_1")
	)
	(via
		(at 257.302 -46.99)
		(size 0.508)
		(drill 0.254)
		(layers "F.Cu" "B.Cu")
		(net "P52V_1_FUSE_1")
	)
	(via
		(at 254.254 -47.752)
		(size 0.508)
		(drill 0.254)
		(layers "F.Cu" "B.Cu")
		(net "P52V_1_FUSE_1")
	)
	(via
		(at 250.571 -46.99)
		(size 0.508)
		(drill 0.254)
		(layers "F.Cu" "B.Cu")
		(net "P52V_1_FUSE_1")
	)
	(via
		(at 248.285 -46.99)
		(size 0.508)
		(drill 0.254)
		(layers "F.Cu" "B.Cu")
		(net "P52V_1_FUSE_1")
	)
	(via
		(at 250.571 -47.752)
		(size 0.508)
		(drill 0.254)
		(layers "F.Cu" "B.Cu")
		(net "P52V_1_FUSE_1")
	)
	(via
		(at 255.016 -47.752)
		(size 0.508)
		(drill 0.254)
		(layers "F.Cu" "B.Cu")
		(net "P52V_1_FUSE_1")
	)
	(via
		(at 256.54 -46.99)
		(size 0.508)
		(drill 0.254)
		(layers "F.Cu" "B.Cu")
		(net "P52V_1_FUSE_1")
	)
	(via
		(at 247.523 -47.752)
		(size 0.508)
		(drill 0.254)
		(layers "F.Cu" "B.Cu")
		(net "P52V_1_FUSE_1")
	)
	(via
		(at 249.047 -47.752)
		(size 0.508)
		(drill 0.254)
		(layers "F.Cu" "B.Cu")
		(net "P52V_1_FUSE_1")
	)
	(via
		(at 255.778 -46.99)
		(size 0.508)
		(drill 0.254)
		(layers "F.Cu" "B.Cu")
		(net "P52V_1_FUSE_1")
	)
	(via
		(at 249.809 -47.752)
		(size 0.508)
		(drill 0.254)
		(layers "F.Cu" "B.Cu")
		(net "P52V_1_FUSE_1")
	)
	(via
		(at 255.016 -46.99)
		(size 0.508)
		(drill 0.254)
		(layers "F.Cu" "B.Cu")
		(net "P52V_1_FUSE_1")
	)
	(segment
		(start 257.302 -47.752)
		(end 258.3434 -47.752)
		(width 0.17272)
		(layer "B.Cu")
		(net "P52V_1_FUSE_1")
	)
	(segment
		(start 258.3434 -47.752)
		(end 258.79044 -48.19904)
		(width 0.17272)
		(layer "B.Cu")
		(net "P52V_1_FUSE_1")
	)
	(segment
		(start 260.2484 -48.19904)
		(end 260.2484 -46.99)
		(width 0.17272)
		(layer "B.Cu")
		(net "P52V_1_FUSE_1")
	)
	(segment
		(start 258.79044 -48.19904)
		(end 260.2484 -48.19904)
		(width 0.17272)
		(layer "B.Cu")
		(net "P52V_1_FUSE_1")
	)
	(segment
		(start 290.9824 -61.98235)
		(end 289.59175 -61.98235)
		(width 0.4572)
		(layer "F.Cu")
		(net "P52V_HS1_INTVCC")
	)
	(segment
		(start 293.6748 -64.97955)
		(end 292.57625 -63.881)
		(width 0.4572)
		(layer "F.Cu")
		(net "P52V_HS1_INTVCC")
	)
	(segment
		(start 289.59175 -61.98235)
		(end 289.5854 -61.976)
		(width 0.4572)
		(layer "F.Cu")
		(net "P52V_HS1_INTVCC")
	)
	(segment
		(start 290.9824 -61.98235)
		(end 291.99205 -62.992)
		(width 0.4572)
		(layer "F.Cu")
		(net "P52V_HS1_INTVCC")
	)
	(segment
		(start 292.57625 -63.881)
		(end 291.99205 -63.881)
		(width 0.4572)
		(layer "F.Cu")
		(net "P52V_HS1_INTVCC")
	)
	(segment
		(start 291.99205 -62.992)
		(end 291.99205 -63.881)
		(width 0.4572)
		(layer "F.Cu")
		(net "P52V_HS1_INTVCC")
	)
	(segment
		(start 293.6748 -65.7606)
		(end 293.6748 -64.97955)
		(width 0.4572)
		(layer "F.Cu")
		(net "P52V_HS1_INTVCC")
	)
	(via
		(at 290.9824 -61.98235)
		(size 0.762)
		(drill 0.254)
		(layers "F.Cu" "B.Cu")
		(net "P52V_HS1_INTVCC")
	)
	(via
		(at 293.6748 -65.7606)
		(size 0.762)
		(drill 0.254)
		(layers "F.Cu" "B.Cu")
		(net "P52V_HS1_INTVCC")
	)
	(via
		(at 289.5854 -61.976)
		(size 0.762)
		(drill 0.254)
		(layers "F.Cu" "B.Cu")
		(net "P52V_HS1_INTVCC")
	)
	(via
		(at 285.6484 -68.94195)
		(size 0.508)
		(drill 0.254)
		(layers "F.Cu" "B.Cu")
		(net "P52V_HS1_INTVCC")
	)
	(segment
		(start 286.2834 -68.94195)
		(end 285.6484 -68.94195)
		(width 0.4572)
		(layer "B.Cu")
		(net "P52V_HS1_INTVCC")
	)
	(segment
		(start 293.6748 -65.7606)
		(end 293.272464 -66.162936)
		(width 0.2794)
		(layer "B.Cu")
		(net "P52V_HS1_INTVCC")
	)
	(segment
		(start 291.9984 -62.59195)
		(end 290.9824 -62.59195)
		(width 0.4572)
		(layer "B.Cu")
		(net "P52V_HS1_INTVCC")
	)
	(segment
		(start 293.272464 -66.162936)
		(end 293.272464 -66.703956)
		(width 0.2794)
		(layer "B.Cu")
		(net "P52V_HS1_INTVCC")
	)
	(segment
		(start 290.9824 -62.59195)
		(end 290.9824 -61.98235)
		(width 0.4572)
		(layer "B.Cu")
		(net "P52V_HS1_INTVCC")
	)
	(segment
		(start 289.5854 -62.59195)
		(end 289.5854 -61.976)
		(width 0.4572)
		(layer "B.Cu")
		(net "P52V_HS1_INTVCC")
	)
	(segment
		(start 286.2834 -68.94195)
		(end 286.9184 -68.94195)
		(width 0.4572)
		(layer "B.Cu")
		(net "P52V_HS1_INTVCC")
	)
	(segment
		(start 286.9184 -68.94195)
		(end 287.28035 -68.58)
		(width 0.4572)
		(layer "B.Cu")
		(net "P52V_HS1_INTVCC")
	)
	(segment
		(start 285.6484 -65.913)
		(end 285.6484 -68.94195)
		(width 0.4572)
		(layer "In2.Cu")
		(net "P52V_HS1_INTVCC")
	)
	(segment
		(start 289.5854 -61.976)
		(end 285.6484 -65.913)
		(width 0.4572)
		(layer "In2.Cu")
		(net "P52V_HS1_INTVCC")
	)
	(via
		(at 286.2834 -61.595)
		(size 0.6604)
		(drill 0.3302)
		(layers "F.Cu" "B.Cu")
		(net "HS1_TMR2")
	)
	(segment
		(start 286.2834 -61.595)
		(end 284.90545 -61.595)
		(width 0.17272)
		(layer "B.Cu")
		(net "HS1_TMR2")
	)
	(segment
		(start 284.65145 -62.78245)
		(end 284.988 -63.119)
		(width 0.17272)
		(layer "B.Cu")
		(net "HS1_TMR2")
	)
	(segment
		(start 284.65145 -61.849)
		(end 284.65145 -62.78245)
		(width 0.17272)
		(layer "B.Cu")
		(net "HS1_TMR2")
	)
	(segment
		(start 284.90545 -61.595)
		(end 284.65145 -61.849)
		(width 0.17272)
		(layer "B.Cu")
		(net "HS1_TMR2")
	)
	(segment
		(start 286.2834 -62.84595)
		(end 286.2834 -61.595)
		(width 0.17272)
		(layer "B.Cu")
		(net "HS1_TMR2")
	)
	(segment
		(start 284.5816 -76.4794)
		(end 283.972 -77.089)
		(width 0.4572)
		(layer "F.Cu")
		(net "GND_FIELD_SIGNAL")
	)
	(segment
		(start 281.47645 -76.327)
		(end 282.2194 -76.327)
		(width 0.4572)
		(layer "F.Cu")
		(net "GND_FIELD_SIGNAL")
	)
	(segment
		(start 284.5816 -76.327)
		(end 284.5816 -76.4794)
		(width 0.4572)
		(layer "F.Cu")
		(net "GND_FIELD_SIGNAL")
	)
	(segment
		(start 281.47645 -72.39)
		(end 282.2194 -72.39)
		(width 0.4572)
		(layer "F.Cu")
		(net "GND_FIELD_SIGNAL")
	)
	(segment
		(start 294.0812 -79.2607)
		(end 294.0812 -79.8068)
		(width 0.4572)
		(layer "F.Cu")
		(net "GND_FIELD_SIGNAL")
	)
	(segment
		(start 316.80785 -83.82)
		(end 316.197996 -83.82)
		(width 0.4572)
		(layer "F.Cu")
		(net "GND_FIELD_SIGNAL")
	)
	(segment
		(start 294.0812 -79.8068)
		(end 298.6024 -84.328)
		(width 0.4572)
		(layer "F.Cu")
		(net "GND_FIELD_SIGNAL")
	)
	(segment
		(start 280.67635 -75.184)
		(end 280.0604 -75.184)
		(width 0.4572)
		(layer "F.Cu")
		(net "GND_FIELD_SIGNAL")
	)
	(segment
		(start 270.5354 -78.105)
		(end 269.9004 -77.47)
		(width 0.4572)
		(layer "F.Cu")
		(net "GND_FIELD_SIGNAL")
	)
	(segment
		(start 270.89735 -78.105)
		(end 270.5354 -78.105)
		(width 0.4572)
		(layer "F.Cu")
		(net "GND_FIELD_SIGNAL")
	)
	(segment
		(start 270.89735 -79.121)
		(end 270.89735 -78.105)
		(width 0.4572)
		(layer "F.Cu")
		(net "GND_FIELD_SIGNAL")
	)
	(segment
		(start 284.01645 -75.184)
		(end 284.7594 -75.184)
		(width 0.4572)
		(layer "F.Cu")
		(net "GND_FIELD_SIGNAL")
	)
	(segment
		(start 281.47645 -74.041)
		(end 282.2194 -74.041)
		(width 0.4572)
		(layer "F.Cu")
		(net "GND_FIELD_SIGNAL")
	)
	(segment
		(start 298.6024 -84.328)
		(end 315.689996 -84.328)
		(width 0.4572)
		(layer "F.Cu")
		(net "GND_FIELD_SIGNAL")
	)
	(segment
		(start 315.689996 -84.328)
		(end 316.197996 -83.82)
		(width 0.4572)
		(layer "F.Cu")
		(net "GND_FIELD_SIGNAL")
	)
	(via
		(at 282.2194 -76.327)
		(size 0.508)
		(drill 0.254)
		(layers "F.Cu" "B.Cu")
		(net "GND_FIELD_SIGNAL")
	)
	(via
		(at 282.2194 -72.39)
		(size 0.508)
		(drill 0.254)
		(layers "F.Cu" "B.Cu")
		(net "GND_FIELD_SIGNAL")
	)
	(via
		(at 282.2194 -74.041)
		(size 0.508)
		(drill 0.254)
		(layers "F.Cu" "B.Cu")
		(net "GND_FIELD_SIGNAL")
	)
	(via
		(at 291.1094 -72.39)
		(size 0.508)
		(drill 0.254)
		(layers "F.Cu" "B.Cu")
		(net "GND_FIELD_SIGNAL")
	)
	(via
		(at 273.177 -72.1106)
		(size 0.508)
		(drill 0.254)
		(layers "F.Cu" "B.Cu")
		(net "GND_FIELD_SIGNAL")
	)
	(via
		(at 284.7594 -75.184)
		(size 0.508)
		(drill 0.254)
		(layers "F.Cu" "B.Cu")
		(net "GND_FIELD_SIGNAL")
	)
	(via
		(at 294.0304 -72.39)
		(size 0.508)
		(drill 0.254)
		(layers "F.Cu" "B.Cu")
		(net "GND_FIELD_SIGNAL")
	)
	(via
		(at 269.9004 -77.47)
		(size 0.508)
		(drill 0.254)
		(layers "F.Cu" "B.Cu")
		(net "GND_FIELD_SIGNAL")
	)
	(via
		(at 294.0304 -70.104)
		(size 0.508)
		(drill 0.254)
		(layers "F.Cu" "B.Cu")
		(net "GND_FIELD_SIGNAL")
	)
	(via
		(at 270.9418 -69.596)
		(size 0.508)
		(drill 0.254)
		(layers "F.Cu" "B.Cu")
		(net "GND_FIELD_SIGNAL")
	)
	(via
		(at 291.1094 -67.818)
		(size 0.508)
		(drill 0.254)
		(layers "F.Cu" "B.Cu")
		(net "GND_FIELD_SIGNAL")
	)
	(via
		(at 291.1094 -70.104)
		(size 0.508)
		(drill 0.254)
		(layers "F.Cu" "B.Cu")
		(net "GND_FIELD_SIGNAL")
	)
	(via
		(at 316.197996 -83.82)
		(size 0.508)
		(drill 0.254)
		(layers "F.Cu" "B.Cu")
		(net "GND_FIELD_SIGNAL")
	)
	(via
		(at 270.9164 -67.0814)
		(size 0.508)
		(drill 0.254)
		(layers "F.Cu" "B.Cu")
		(net "GND_FIELD_SIGNAL")
	)
	(via
		(at 273.177 -67.0814)
		(size 0.508)
		(drill 0.254)
		(layers "F.Cu" "B.Cu")
		(net "GND_FIELD_SIGNAL")
	)
	(via
		(at 294.0812 -79.2607)
		(size 0.508)
		(drill 0.254)
		(layers "F.Cu" "B.Cu")
		(net "GND_FIELD_SIGNAL")
	)
	(via
		(at 294.0304 -67.818)
		(size 0.508)
		(drill 0.254)
		(layers "F.Cu" "B.Cu")
		(net "GND_FIELD_SIGNAL")
	)
	(via
		(at 273.177 -69.596)
		(size 0.508)
		(drill 0.254)
		(layers "F.Cu" "B.Cu")
		(net "GND_FIELD_SIGNAL")
	)
	(via
		(at 270.9418 -72.1106)
		(size 0.508)
		(drill 0.254)
		(layers "F.Cu" "B.Cu")
		(net "GND_FIELD_SIGNAL")
	)
	(via
		(at 283.972 -77.089)
		(size 0.508)
		(drill 0.254)
		(layers "F.Cu" "B.Cu")
		(net "GND_FIELD_SIGNAL")
	)
	(via
		(at 280.0604 -75.184)
		(size 0.508)
		(drill 0.254)
		(layers "F.Cu" "B.Cu")
		(net "GND_FIELD_SIGNAL")
	)
	(segment
		(start 293.2684 -79.2607)
		(end 294.0812 -79.2607)
		(width 0.4572)
		(layer "B.Cu")
		(net "GND_FIELD_SIGNAL")
	)
	(segment
		(start 269.9004 -76.85405)
		(end 269.9004 -77.47)
		(width 0.4572)
		(layer "B.Cu")
		(net "GND_FIELD_SIGNAL")
	)
	(segment
		(start 321.8434 -84.709)
		(end 320.8274 -85.725)
		(width 0.254)
		(layer "F.Cu")
		(net "P52V_HS1_TEMP_R")
	)
	(segment
		(start 317.88227 -84.910676)
		(end 317.60795 -85.184996)
		(width 0.254)
		(layer "F.Cu")
		(net "P52V_HS1_TEMP_R")
	)
	(segment
		(start 320.8274 -85.725)
		(end 320.8274 -87.1728)
		(width 0.254)
		(layer "F.Cu")
		(net "P52V_HS1_TEMP_R")
	)
	(segment
		(start 320.013076 -84.910676)
		(end 317.88227 -84.910676)
		(width 0.254)
		(layer "F.Cu")
		(net "P52V_HS1_TEMP_R")
	)
	(segment
		(start 317.60795 -85.184996)
		(end 317.60795 -85.598)
		(width 0.254)
		(layer "F.Cu")
		(net "P52V_HS1_TEMP_R")
	)
	(segment
		(start 323.0626 -84.709)
		(end 321.8434 -84.709)
		(width 0.254)
		(layer "F.Cu")
		(net "P52V_HS1_TEMP_R")
	)
	(segment
		(start 320.8274 -85.725)
		(end 320.013076 -84.910676)
		(width 0.254)
		(layer "F.Cu")
		(net "P52V_HS1_TEMP_R")
	)
	(via
		(at 320.8274 -87.1728)
		(size 0.762)
		(drill 0.381)
		(layers "F.Cu" "B.Cu")
		(net "P52V_HS1_TEMP_R")
	)
	(via
		(at 152.9588 -64.3128)
		(size 0.6604)
		(drill 0.3302)
		(layers "F.Cu" "B.Cu")
		(net "P52V_HS2_FB")
	)
	(via
		(at 294.6908 -76.1492)
		(size 0.6604)
		(drill 0.3302)
		(layers "F.Cu" "B.Cu")
		(net "P52V_HS1_FB")
	)
	(via
		(at 289.5854 -64.643)
		(size 0.6604)
		(drill 0.3302)
		(layers "F.Cu" "B.Cu")
		(net "P52V_HS1_MODE")
	)
	(segment
		(start 290.096956 -67.353942)
		(end 289.97529 -67.353942)
		(width 0.17272)
		(layer "B.Cu")
		(net "P52V_HS1_MODE")
	)
	(segment
		(start 289.5854 -66.964052)
		(end 289.5854 -64.643)
		(width 0.17272)
		(layer "B.Cu")
		(net "P52V_HS1_MODE")
	)
	(segment
		(start 289.97529 -67.353942)
		(end 289.5854 -66.964052)
		(width 0.17272)
		(layer "B.Cu")
		(net "P52V_HS1_MODE")
	)
	(segment
		(start 289.5854 -63.39205)
		(end 289.5854 -64.643)
		(width 0.17272)
		(layer "B.Cu")
		(net "P52V_HS1_MODE")
	)
	(via
		(at 104.648 -55.7022)
		(size 0.6604)
		(drill 0.3302)
		(layers "F.Cu" "B.Cu")
		(net "P52V_HS2_GATE_RC")
	)
	(segment
		(start 104.7496 -55.6006)
		(end 104.648 -55.7022)
		(width 0.508)
		(layer "B.Cu")
		(net "P52V_HS2_GATE_RC")
	)
	(segment
		(start 106.0196 -55.7022)
		(end 106.045 -55.7276)
		(width 0.508)
		(layer "B.Cu")
		(net "P52V_HS2_GATE_RC")
	)
	(segment
		(start 104.7496 -54.356)
		(end 104.7496 -55.6006)
		(width 0.508)
		(layer "B.Cu")
		(net "P52V_HS2_GATE_RC")
	)
	(segment
		(start 104.648 -55.7022)
		(end 106.0196 -55.7022)
		(width 0.508)
		(layer "B.Cu")
		(net "P52V_HS2_GATE_RC")
	)
	(via
		(at 287.4518 -66.802)
		(size 0.6604)
		(drill 0.3302)
		(layers "F.Cu" "B.Cu")
		(net "P52V_HS1_CLKIN")
	)
	(segment
		(start 286.30245 -66.929)
		(end 286.42945 -66.802)
		(width 0.17272)
		(layer "B.Cu")
		(net "P52V_HS1_CLKIN")
	)
	(segment
		(start 287.4518 -66.802)
		(end 287.9344 -66.802)
		(width 0.17272)
		(layer "B.Cu")
		(net "P52V_HS1_CLKIN")
	)
	(segment
		(start 287.9344 -66.802)
		(end 289.48634 -68.35394)
		(width 0.17272)
		(layer "B.Cu")
		(net "P52V_HS1_CLKIN")
	)
	(segment
		(start 289.48634 -68.35394)
		(end 290.122356 -68.35394)
		(width 0.17272)
		(layer "B.Cu")
		(net "P52V_HS1_CLKIN")
	)
	(segment
		(start 286.42945 -66.802)
		(end 287.4518 -66.802)
		(width 0.17272)
		(layer "B.Cu")
		(net "P52V_HS1_CLKIN")
	)
	(segment
		(start 160.713674 -71.647558)
		(end 160.713674 -64.02451)
		(width 0.17272)
		(layer "F.Cu")
		(net "P52V_HS2_SIO")
	)
	(segment
		(start 160.713674 -64.02451)
		(end 162.041078 -62.697106)
		(width 0.17272)
		(layer "F.Cu")
		(net "P52V_HS2_SIO")
	)
	(segment
		(start 160.098232 -72.263)
		(end 160.713674 -71.647558)
		(width 0.17272)
		(layer "F.Cu")
		(net "P52V_HS2_SIO")
	)
	(segment
		(start 162.041078 -62.697106)
		(end 163.703508 -62.697106)
		(width 0.17272)
		(layer "F.Cu")
		(net "P52V_HS2_SIO")
	)
	(via
		(at 163.703508 -62.697106)
		(size 0.508)
		(drill 0.254)
		(layers "F.Cu" "B.Cu")
		(net "P52V_HS2_SIO")
	)
	(via
		(at 160.098232 -72.263)
		(size 0.762)
		(drill 0.254)
		(layers "F.Cu" "B.Cu")
		(net "P52V_HS2_SIO")
	)
	(segment
		(start 159.539686 -71.628)
		(end 159.539686 -71.704454)
		(width 0.17272)
		(layer "B.Cu")
		(net "P52V_HS2_SIO")
	)
	(segment
		(start 155.644088 -62.97168)
		(end 156.033978 -63.36157)
		(width 0.17272)
		(layer "B.Cu")
		(net "P52V_HS2_SIO")
	)
	(segment
		(start 158.265622 -70.353936)
		(end 159.539686 -71.628)
		(width 0.17272)
		(layer "B.Cu")
		(net "P52V_HS2_SIO")
	)
	(segment
		(start 159.19958 -63.36157)
		(end 159.864044 -62.697106)
		(width 0.17272)
		(layer "B.Cu")
		(net "P52V_HS2_SIO")
	)
	(segment
		(start 159.864044 -62.697106)
		(end 162.738308 -62.697106)
		(width 0.17272)
		(layer "B.Cu")
		(net "P52V_HS2_SIO")
	)
	(segment
		(start 156.633164 -61.39688)
		(end 155.949142 -61.39688)
		(width 0.17272)
		(layer "B.Cu")
		(net "P52V_HS2_SIO")
	)
	(segment
		(start 155.644088 -61.701934)
		(end 155.644088 -62.97168)
		(width 0.17272)
		(layer "B.Cu")
		(net "P52V_HS2_SIO")
	)
	(segment
		(start 160.098232 -72.263)
		(end 161.317686 -72.263)
		(width 0.17272)
		(layer "B.Cu")
		(net "P52V_HS2_SIO")
	)
	(segment
		(start 155.949142 -61.39688)
		(end 155.644088 -61.701934)
		(width 0.17272)
		(layer "B.Cu")
		(net "P52V_HS2_SIO")
	)
	(segment
		(start 159.539686 -71.704454)
		(end 160.098232 -72.263)
		(width 0.17272)
		(layer "B.Cu")
		(net "P52V_HS2_SIO")
	)
	(segment
		(start 156.033978 -63.36157)
		(end 159.19958 -63.36157)
		(width 0.17272)
		(layer "B.Cu")
		(net "P52V_HS2_SIO")
	)
	(segment
		(start 162.738308 -62.697106)
		(end 163.703508 -62.697106)
		(width 0.17272)
		(layer "B.Cu")
		(net "P52V_HS2_SIO")
	)
	(segment
		(start 157.49778 -70.353936)
		(end 158.265622 -70.353936)
		(width 0.17272)
		(layer "B.Cu")
		(net "P52V_HS2_SIO")
	)
	(via
		(at 342.9254 -50.6095)
		(size 0.6604)
		(drill 0.3302)
		(layers "F.Cu" "B.Cu")
		(net "P52V_HS1_GATE_RC")
	)
	(segment
		(start 342.7984 -50.0126)
		(end 342.9254 -50.1396)
		(width 0.508)
		(layer "B.Cu")
		(net "P52V_HS1_GATE_RC")
	)
	(segment
		(start 342.7984 -49.276)
		(end 342.7984 -50.0126)
		(width 0.508)
		(layer "B.Cu")
		(net "P52V_HS1_GATE_RC")
	)
	(segment
		(start 342.9254 -50.6095)
		(end 342.8619 -50.673)
		(width 0.508)
		(layer "B.Cu")
		(net "P52V_HS1_GATE_RC")
	)
	(segment
		(start 342.8619 -50.673)
		(end 341.5792 -50.673)
		(width 0.508)
		(layer "B.Cu")
		(net "P52V_HS1_GATE_RC")
	)
	(segment
		(start 342.9254 -50.1396)
		(end 342.9254 -50.6095)
		(width 0.508)
		(layer "B.Cu")
		(net "P52V_HS1_GATE_RC")
	)
	(via
		(at 287.6804 -74.168)
		(size 0.6604)
		(drill 0.3302)
		(layers "F.Cu" "B.Cu")
		(net "SMB_P52V_HS1_SDAO")
	)
	(segment
		(start 290.122356 -72.353932)
		(end 289.621468 -72.353932)
		(width 0.17272)
		(layer "B.Cu")
		(net "SMB_P52V_HS1_SDAO")
	)
	(segment
		(start 289.621468 -72.353932)
		(end 287.8074 -74.168)
		(width 0.17272)
		(layer "B.Cu")
		(net "SMB_P52V_HS1_SDAO")
	)
	(segment
		(start 287.8074 -74.168)
		(end 287.6804 -74.168)
		(width 0.17272)
		(layer "B.Cu")
		(net "SMB_P52V_HS1_SDAO")
	)
	(segment
		(start 287.6804 -74.168)
		(end 286.30245 -74.168)
		(width 0.17272)
		(layer "B.Cu")
		(net "SMB_P52V_HS1_SDAO")
	)
	(via
		(at 288.609532 -72.477122)
		(size 0.6604)
		(drill 0.3302)
		(layers "F.Cu" "B.Cu")
		(net "SMB_P52V_HS1_SDAI")
	)
	(segment
		(start 288.061654 -73.025)
		(end 288.609532 -72.477122)
		(width 0.17272)
		(layer "B.Cu")
		(net "SMB_P52V_HS1_SDAI")
	)
	(segment
		(start 289.232594 -71.85406)
		(end 288.609532 -72.477122)
		(width 0.17272)
		(layer "B.Cu")
		(net "SMB_P52V_HS1_SDAI")
	)
	(segment
		(start 290.122356 -71.85406)
		(end 289.232594 -71.85406)
		(width 0.17272)
		(layer "B.Cu")
		(net "SMB_P52V_HS1_SDAI")
	)
	(segment
		(start 286.30245 -73.025)
		(end 288.061654 -73.025)
		(width 0.17272)
		(layer "B.Cu")
		(net "SMB_P52V_HS1_SDAI")
	)
	(via
		(at 159.939736 -66.04)
		(size 0.6604)
		(drill 0.3302)
		(layers "F.Cu" "B.Cu")
		(net "SMB_P52V_HS2_SDAO")
	)
	(segment
		(start 157.49778 -67.854068)
		(end 157.998668 -67.854068)
		(width 0.17272)
		(layer "B.Cu")
		(net "SMB_P52V_HS2_SDAO")
	)
	(segment
		(start 157.998668 -67.854068)
		(end 159.812736 -66.04)
		(width 0.17272)
		(layer "B.Cu")
		(net "SMB_P52V_HS2_SDAO")
	)
	(segment
		(start 159.939736 -66.04)
		(end 161.317686 -66.04)
		(width 0.17272)
		(layer "B.Cu")
		(net "SMB_P52V_HS2_SDAO")
	)
	(segment
		(start 159.812736 -66.04)
		(end 159.939736 -66.04)
		(width 0.17272)
		(layer "B.Cu")
		(net "SMB_P52V_HS2_SDAO")
	)
	(via
		(at 159.010604 -67.730878)
		(size 0.6604)
		(drill 0.3302)
		(layers "F.Cu" "B.Cu")
		(net "SMB_P52V_HS2_SDAI")
	)
	(segment
		(start 158.387542 -68.35394)
		(end 157.49778 -68.35394)
		(width 0.17272)
		(layer "B.Cu")
		(net "SMB_P52V_HS2_SDAI")
	)
	(segment
		(start 159.558482 -67.183)
		(end 159.010604 -67.730878)
		(width 0.17272)
		(layer "B.Cu")
		(net "SMB_P52V_HS2_SDAI")
	)
	(segment
		(start 159.010604 -67.730878)
		(end 158.387542 -68.35394)
		(width 0.17272)
		(layer "B.Cu")
		(net "SMB_P52V_HS2_SDAI")
	)
	(segment
		(start 161.317686 -67.183)
		(end 159.558482 -67.183)
		(width 0.17272)
		(layer "B.Cu")
		(net "SMB_P52V_HS2_SDAI")
	)
	(segment
		(start 127.60706 -82.475324)
		(end 126.792736 -81.661)
		(width 0.254)
		(layer "F.Cu")
		(net "P52V_HS2_TEMP_R")
	)
	(segment
		(start 130.012186 -82.201004)
		(end 129.737866 -82.475324)
		(width 0.254)
		(layer "F.Cu")
		(net "P52V_HS2_TEMP_R")
	)
	(segment
		(start 125.776736 -82.677)
		(end 126.792736 -81.661)
		(width 0.254)
		(layer "F.Cu")
		(net "P52V_HS2_TEMP_R")
	)
	(segment
		(start 130.012186 -81.788)
		(end 130.012186 -82.201004)
		(width 0.254)
		(layer "F.Cu")
		(net "P52V_HS2_TEMP_R")
	)
	(segment
		(start 124.557536 -82.677)
		(end 122.9614 -82.677)
		(width 0.254)
		(layer "F.Cu")
		(net "P52V_HS2_TEMP_R")
	)
	(segment
		(start 124.557536 -82.677)
		(end 125.776736 -82.677)
		(width 0.254)
		(layer "F.Cu")
		(net "P52V_HS2_TEMP_R")
	)
	(segment
		(start 129.737866 -82.475324)
		(end 127.60706 -82.475324)
		(width 0.254)
		(layer "F.Cu")
		(net "P52V_HS2_TEMP_R")
	)
	(via
		(at 122.9614 -82.677)
		(size 0.762)
		(drill 0.381)
		(layers "F.Cu" "B.Cu")
		(net "P52V_HS2_TEMP_R")
	)
	(via
		(at 161.4424 -78.591664)
		(size 0.6604)
		(drill 0.3302)
		(layers "F.Cu" "B.Cu")
		(net "HS2_TMR2")
	)
	(segment
		(start 161.336736 -77.36205)
		(end 161.336736 -78.486)
		(width 0.17272)
		(layer "B.Cu")
		(net "HS2_TMR2")
	)
	(segment
		(start 161.336736 -78.486)
		(end 161.4424 -78.591664)
		(width 0.17272)
		(layer "B.Cu")
		(net "HS2_TMR2")
	)
	(segment
		(start 161.4424 -78.591664)
		(end 161.675064 -78.359)
		(width 0.17272)
		(layer "B.Cu")
		(net "HS2_TMR2")
	)
	(segment
		(start 162.94735 -77.404214)
		(end 162.632136 -77.089)
		(width 0.17272)
		(layer "B.Cu")
		(net "HS2_TMR2")
	)
	(segment
		(start 161.675064 -78.359)
		(end 162.94735 -78.359)
		(width 0.17272)
		(layer "B.Cu")
		(net "HS2_TMR2")
	)
	(segment
		(start 162.94735 -78.359)
		(end 162.94735 -77.404214)
		(width 0.17272)
		(layer "B.Cu")
		(net "HS2_TMR2")
	)
	(via
		(at 159.431736 -74.52995)
		(size 0.6604)
		(drill 0.3302)
		(layers "F.Cu" "B.Cu")
		(net "P52V_HS2_TMR")
	)
	(segment
		(start 161.336736 -74.52995)
		(end 162.441636 -74.52995)
		(width 0.17272)
		(layer "B.Cu")
		(net "P52V_HS2_TMR")
	)
	(segment
		(start 159.431736 -74.52995)
		(end 159.412686 -74.52995)
		(width 0.17272)
		(layer "B.Cu")
		(net "P52V_HS2_TMR")
	)
	(segment
		(start 158.542736 -73.66)
		(end 158.542736 -73.076562)
		(width 0.17272)
		(layer "B.Cu")
		(net "P52V_HS2_TMR")
	)
	(segment
		(start 162.441636 -74.52995)
		(end 162.460686 -74.549)
		(width 0.17272)
		(layer "B.Cu")
		(net "P52V_HS2_TMR")
	)
	(segment
		(start 159.412686 -74.52995)
		(end 158.542736 -73.66)
		(width 0.17272)
		(layer "B.Cu")
		(net "P52V_HS2_TMR")
	)
	(segment
		(start 157.820106 -72.353932)
		(end 157.49778 -72.353932)
		(width 0.17272)
		(layer "B.Cu")
		(net "P52V_HS2_TMR")
	)
	(segment
		(start 158.542736 -73.076562)
		(end 157.820106 -72.353932)
		(width 0.17272)
		(layer "B.Cu")
		(net "P52V_HS2_TMR")
	)
	(segment
		(start 161.336736 -74.52995)
		(end 159.431736 -74.52995)
		(width 0.17272)
		(layer "B.Cu")
		(net "P52V_HS2_TMR")
	)
	(via
		(at 106.299 -58.3184)
		(size 0.6604)
		(drill 0.3302)
		(layers "F.Cu" "B.Cu")
		(net "P52V_HS2_GATE_R1")
	)
	(segment
		(start 108.7374 -56.7182)
		(end 107.7722 -56.7182)
		(width 0.508)
		(layer "B.Cu")
		(net "P52V_HS2_GATE_R1")
	)
	(segment
		(start 107.188 -55.26405)
		(end 107.188 -55.640986)
		(width 0.4572)
		(layer "B.Cu")
		(net "P52V_HS2_GATE_R1")
	)
	(segment
		(start 107.080812 -55.748174)
		(end 107.080812 -56.876188)
		(width 0.508)
		(layer "B.Cu")
		(net "P52V_HS2_GATE_R1")
	)
	(segment
		(start 106.934 -57.6834)
		(end 106.299 -58.3184)
		(width 0.508)
		(layer "B.Cu")
		(net "P52V_HS2_GATE_R1")
	)
	(segment
		(start 107.4674 -57.023)
		(end 106.934 -57.023)
		(width 0.508)
		(layer "B.Cu")
		(net "P52V_HS2_GATE_R1")
	)
	(segment
		(start 107.188 -55.640986)
		(end 107.080812 -55.748174)
		(width 0.508)
		(layer "B.Cu")
		(net "P52V_HS2_GATE_R1")
	)
	(segment
		(start 106.934 -57.023)
		(end 106.934 -57.6834)
		(width 0.508)
		(layer "B.Cu")
		(net "P52V_HS2_GATE_R1")
	)
	(segment
		(start 107.7722 -56.7182)
		(end 107.4674 -57.023)
		(width 0.508)
		(layer "B.Cu")
		(net "P52V_HS2_GATE_R1")
	)
	(segment
		(start 107.080812 -56.876188)
		(end 106.934 -57.023)
		(width 0.508)
		(layer "B.Cu")
		(net "P52V_HS2_GATE_R1")
	)
	(segment
		(start 145.365724 -82.269076)
		(end 131.902962 -82.269076)
		(width 0.254)
		(layer "F.Cu")
		(net "P52V_HS2_TEMP")
	)
	(segment
		(start 130.812286 -81.788)
		(end 131.421886 -81.788)
		(width 0.254)
		(layer "F.Cu")
		(net "P52V_HS2_TEMP")
	)
	(segment
		(start 152.959562 -69.065902)
		(end 151.880316 -70.145148)
		(width 0.254)
		(layer "F.Cu")
		(net "P52V_HS2_TEMP")
	)
	(segment
		(start 151.880316 -72.205088)
		(end 146.411188 -77.674216)
		(width 0.254)
		(layer "F.Cu")
		(net "P52V_HS2_TEMP")
	)
	(segment
		(start 153.570178 -64.6176)
		(end 152.959562 -65.228216)
		(width 0.254)
		(layer "F.Cu")
		(net "P52V_HS2_TEMP")
	)
	(segment
		(start 154.816556 -64.6176)
		(end 153.570178 -64.6176)
		(width 0.254)
		(layer "F.Cu")
		(net "P52V_HS2_TEMP")
	)
	(segment
		(start 146.411188 -81.223612)
		(end 145.365724 -82.269076)
		(width 0.254)
		(layer "F.Cu")
		(net "P52V_HS2_TEMP")
	)
	(segment
		(start 131.902962 -82.269076)
		(end 131.421886 -81.788)
		(width 0.254)
		(layer "F.Cu")
		(net "P52V_HS2_TEMP")
	)
	(segment
		(start 154.847798 -64.648842)
		(end 154.816556 -64.6176)
		(width 0.254)
		(layer "F.Cu")
		(net "P52V_HS2_TEMP")
	)
	(segment
		(start 152.959562 -65.228216)
		(end 152.959562 -69.065902)
		(width 0.254)
		(layer "F.Cu")
		(net "P52V_HS2_TEMP")
	)
	(segment
		(start 151.880316 -70.145148)
		(end 151.880316 -72.205088)
		(width 0.254)
		(layer "F.Cu")
		(net "P52V_HS2_TEMP")
	)
	(segment
		(start 146.411188 -77.674216)
		(end 146.411188 -81.223612)
		(width 0.254)
		(layer "F.Cu")
		(net "P52V_HS2_TEMP")
	)
	(via
		(at 154.847798 -64.648842)
		(size 0.508)
		(drill 0.254)
		(layers "F.Cu" "B.Cu")
		(net "P52V_HS2_TEMP")
	)
	(via
		(at 131.421886 -81.788)
		(size 0.508)
		(drill 0.254)
		(layers "F.Cu" "B.Cu")
		(net "P52V_HS2_TEMP")
	)
	(segment
		(start 154.847798 -66.703956)
		(end 154.847798 -64.648842)
		(width 0.17272)
		(layer "B.Cu")
		(net "P52V_HS2_TEMP")
	)
	(segment
		(start 154.846528 -64.648842)
		(end 154.351736 -64.15405)
		(width 0.17272)
		(layer "B.Cu")
		(net "P52V_HS2_TEMP")
	)
	(segment
		(start 154.847798 -64.648842)
		(end 154.846528 -64.648842)
		(width 0.17272)
		(layer "B.Cu")
		(net "P52V_HS2_TEMP")
	)
	(via
		(at 159.939736 -76.2)
		(size 0.6604)
		(drill 0.3302)
		(layers "F.Cu" "B.Cu")
		(net "HS2_TMR1")
	)
	(segment
		(start 160.301686 -76.56195)
		(end 159.939736 -76.2)
		(width 0.17272)
		(layer "B.Cu")
		(net "HS2_TMR1")
	)
	(segment
		(start 160.428686 -75.33005)
		(end 161.336736 -75.33005)
		(width 0.17272)
		(layer "B.Cu")
		(net "HS2_TMR1")
	)
	(segment
		(start 159.939736 -76.2)
		(end 159.939736 -75.819)
		(width 0.17272)
		(layer "B.Cu")
		(net "HS2_TMR1")
	)
	(segment
		(start 161.698686 -75.692)
		(end 161.336736 -75.33005)
		(width 0.17272)
		(layer "B.Cu")
		(net "HS2_TMR1")
	)
	(segment
		(start 162.460686 -75.692)
		(end 161.698686 -75.692)
		(width 0.17272)
		(layer "B.Cu")
		(net "HS2_TMR1")
	)
	(segment
		(start 161.336736 -76.56195)
		(end 160.301686 -76.56195)
		(width 0.17272)
		(layer "B.Cu")
		(net "HS2_TMR1")
	)
	(segment
		(start 159.939736 -75.819)
		(end 160.428686 -75.33005)
		(width 0.17272)
		(layer "B.Cu")
		(net "HS2_TMR1")
	)
	(via
		(at 159.304736 -73.025)
		(size 0.6604)
		(drill 0.3302)
		(layers "F.Cu" "B.Cu")
		(net "P52V_HS2_CLKIN")
	)
	(segment
		(start 161.317686 -73.279)
		(end 159.558736 -73.279)
		(width 0.17272)
		(layer "B.Cu")
		(net "P52V_HS2_CLKIN")
	)
	(segment
		(start 159.304736 -73.025)
		(end 158.133796 -71.85406)
		(width 0.17272)
		(layer "B.Cu")
		(net "P52V_HS2_CLKIN")
	)
	(segment
		(start 158.133796 -71.85406)
		(end 157.49778 -71.85406)
		(width 0.17272)
		(layer "B.Cu")
		(net "P52V_HS2_CLKIN")
	)
	(segment
		(start 159.558736 -73.279)
		(end 159.304736 -73.025)
		(width 0.17272)
		(layer "B.Cu")
		(net "P52V_HS2_CLKIN")
	)
	(via
		(at 150.876 -65.278)
		(size 0.6604)
		(drill 0.3302)
		(layers "F.Cu" "B.Cu")
		(net "P52V_HS2_VDSFB")
	)
	(via
		(at 154.497786 -77.47)
		(size 0.762)
		(drill 0.254)
		(layers "F.Cu" "B.Cu")
		(net "P52V_HS2_DVCC")
	)
	(via
		(at 162.941 -58.928)
		(size 0.6604)
		(drill 0.3302)
		(layers "F.Cu" "B.Cu")
		(net "P52V_HS2_DVCC")
	)
	(via
		(at 162.30854 -60.039758)
		(size 0.762)
		(drill 0.254)
		(layers "F.Cu" "B.Cu")
		(net "P52V_HS2_DVCC")
	)
	(segment
		(start 154.497786 -76.835)
		(end 154.497786 -77.47)
		(width 0.17272)
		(layer "B.Cu")
		(net "P52V_HS2_DVCC")
	)
	(segment
		(start 155.34767 -74.80173)
		(end 155.34767 -73.504044)
		(width 0.17272)
		(layer "B.Cu")
		(net "P52V_HS2_DVCC")
	)
	(segment
		(start 162.738308 -61.39688)
		(end 159.862774 -61.39688)
		(width 0.381)
		(layer "B.Cu")
		(net "P52V_HS2_DVCC")
	)
	(segment
		(start 154.497786 -75.651614)
		(end 155.34767 -74.80173)
		(width 0.17272)
		(layer "B.Cu")
		(net "P52V_HS2_DVCC")
	)
	(segment
		(start 159.862774 -61.39688)
		(end 159.212534 -62.04712)
		(width 0.381)
		(layer "B.Cu")
		(net "P52V_HS2_DVCC")
	)
	(segment
		(start 154.497786 -76.835)
		(end 154.497786 -75.651614)
		(width 0.17272)
		(layer "B.Cu")
		(net "P52V_HS2_DVCC")
	)
	(segment
		(start 159.212534 -62.04712)
		(end 156.633164 -62.04712)
		(width 0.381)
		(layer "B.Cu")
		(net "P52V_HS2_DVCC")
	)
	(segment
		(start 154.497786 -75.60691)
		(end 154.497786 -77.47)
		(width 0.4572)
		(layer "In2.Cu")
		(net "P52V_HS2_DVCC")
	)
	(segment
		(start 162.30854 -60.039758)
		(end 161.544508 -60.80379)
		(width 0.4572)
		(layer "In2.Cu")
		(net "P52V_HS2_DVCC")
	)
	(segment
		(start 161.544508 -60.80379)
		(end 161.544508 -69.668644)
		(width 0.4572)
		(layer "In2.Cu")
		(net "P52V_HS2_DVCC")
	)
	(segment
		(start 157.376622 -73.83653)
		(end 156.268166 -73.83653)
		(width 0.4572)
		(layer "In2.Cu")
		(net "P52V_HS2_DVCC")
	)
	(segment
		(start 156.268166 -73.83653)
		(end 154.497786 -75.60691)
		(width 0.4572)
		(layer "In2.Cu")
		(net "P52V_HS2_DVCC")
	)
	(segment
		(start 161.544508 -69.668644)
		(end 157.376622 -73.83653)
		(width 0.4572)
		(layer "In2.Cu")
		(net "P52V_HS2_DVCC")
	)
	(via
		(at 157.988762 -75.565)
		(size 0.6604)
		(drill 0.3302)
		(layers "F.Cu" "B.Cu")
		(net "P52V_HS2_MODE")
	)
	(segment
		(start 157.52318 -72.854058)
		(end 157.644846 -72.854058)
		(width 0.17272)
		(layer "B.Cu")
		(net "P52V_HS2_MODE")
	)
	(segment
		(start 157.988762 -76.328016)
		(end 158.034736 -76.37399)
		(width 0.17272)
		(layer "B.Cu")
		(net "P52V_HS2_MODE")
	)
	(segment
		(start 157.988762 -75.565)
		(end 157.988762 -76.328016)
		(width 0.17272)
		(layer "B.Cu")
		(net "P52V_HS2_MODE")
	)
	(segment
		(start 158.034736 -76.37399)
		(end 158.034736 -76.81595)
		(width 0.17272)
		(layer "B.Cu")
		(net "P52V_HS2_MODE")
	)
	(segment
		(start 157.644846 -72.854058)
		(end 157.988762 -73.197974)
		(width 0.17272)
		(layer "B.Cu")
		(net "P52V_HS2_MODE")
	)
	(segment
		(start 157.988762 -73.197974)
		(end 157.988762 -75.565)
		(width 0.17272)
		(layer "B.Cu")
		(net "P52V_HS2_MODE")
	)
	(segment
		(start 158.923736 -62.03823)
		(end 157.6324 -60.746894)
		(width 0.17272)
		(layer "F.Cu")
		(net "P52V_HS2_CS")
	)
	(segment
		(start 158.923736 -69.468746)
		(end 158.923736 -62.03823)
		(width 0.17272)
		(layer "F.Cu")
		(net "P52V_HS2_CS")
	)
	(via
		(at 157.6324 -60.746894)
		(size 0.508)
		(drill 0.254)
		(layers "F.Cu" "B.Cu")
		(net "P52V_HS2_CS")
	)
	(via
		(at 158.923736 -69.468746)
		(size 0.762)
		(drill 0.254)
		(layers "F.Cu" "B.Cu")
		(net "P52V_HS2_CS")
	)
	(segment
		(start 161.317686 -69.469)
		(end 159.28086 -69.469)
		(width 0.17272)
		(layer "B.Cu")
		(net "P52V_HS2_CS")
	)
	(segment
		(start 158.923736 -69.468746)
		(end 158.808928 -69.353938)
		(width 0.17272)
		(layer "B.Cu")
		(net "P52V_HS2_CS")
	)
	(segment
		(start 156.633164 -60.746894)
		(end 157.6324 -60.746894)
		(width 0.17272)
		(layer "B.Cu")
		(net "P52V_HS2_CS")
	)
	(segment
		(start 159.280606 -69.468746)
		(end 158.923736 -69.468746)
		(width 0.17272)
		(layer "B.Cu")
		(net "P52V_HS2_CS")
	)
	(segment
		(start 159.28086 -69.469)
		(end 159.280606 -69.468746)
		(width 0.17272)
		(layer "B.Cu")
		(net "P52V_HS2_CS")
	)
	(segment
		(start 158.808928 -69.353938)
		(end 157.49778 -69.353938)
		(width 0.17272)
		(layer "B.Cu")
		(net "P52V_HS2_CS")
	)
	(segment
		(start 159.770572 -63.8429)
		(end 159.770572 -70.485)
		(width 0.17272)
		(layer "F.Cu")
		(net "P52V_HS2_SCK")
	)
	(segment
		(start 164.0586 -61.5188)
		(end 162.094672 -61.5188)
		(width 0.17272)
		(layer "F.Cu")
		(net "P52V_HS2_SCK")
	)
	(segment
		(start 162.094672 -61.5188)
		(end 159.770572 -63.8429)
		(width 0.17272)
		(layer "F.Cu")
		(net "P52V_HS2_SCK")
	)
	(via
		(at 159.770572 -70.485)
		(size 0.508)
		(drill 0.254)
		(layers "F.Cu" "B.Cu")
		(net "P52V_HS2_SCK")
	)
	(via
		(at 164.0586 -61.5188)
		(size 0.762)
		(drill 0.254)
		(layers "F.Cu" "B.Cu")
		(net "P52V_HS2_SCK")
	)
	(segment
		(start 162.738308 -62.04712)
		(end 163.53028 -62.04712)
		(width 0.17272)
		(layer "B.Cu")
		(net "P52V_HS2_SCK")
	)
	(segment
		(start 162.314636 -70.46595)
		(end 162.333686 -70.485)
		(width 0.17272)
		(layer "B.Cu")
		(net "P52V_HS2_SCK")
	)
	(segment
		(start 161.317686 -70.485)
		(end 159.770572 -70.485)
		(width 0.17272)
		(layer "B.Cu")
		(net "P52V_HS2_SCK")
	)
	(segment
		(start 159.135318 -70.485)
		(end 158.504382 -69.854064)
		(width 0.17272)
		(layer "B.Cu")
		(net "P52V_HS2_SCK")
	)
	(segment
		(start 161.336736 -70.46595)
		(end 161.317686 -70.485)
		(width 0.17272)
		(layer "B.Cu")
		(net "P52V_HS2_SCK")
	)
	(segment
		(start 159.770572 -70.485)
		(end 159.135318 -70.485)
		(width 0.17272)
		(layer "B.Cu")
		(net "P52V_HS2_SCK")
	)
	(segment
		(start 161.336736 -70.46595)
		(end 162.314636 -70.46595)
		(width 0.17272)
		(layer "B.Cu")
		(net "P52V_HS2_SCK")
	)
	(segment
		(start 163.53028 -62.04712)
		(end 164.0586 -61.5188)
		(width 0.17272)
		(layer "B.Cu")
		(net "P52V_HS2_SCK")
	)
	(segment
		(start 158.504382 -69.854064)
		(end 157.49778 -69.854064)
		(width 0.17272)
		(layer "B.Cu")
		(net "P52V_HS2_SCK")
	)
	(segment
		(start 153.945336 -74.4474)
		(end 153.945336 -75.22591)
		(width 0.381)
		(layer "F.Cu")
		(net "P52V_HS2_INTVCC")
	)
	(segment
		(start 153.538682 -76.176632)
		(end 153.56205 -76.2)
		(width 0.381)
		(layer "F.Cu")
		(net "P52V_HS2_INTVCC")
	)
	(segment
		(start 161.971736 -74.295)
		(end 158.034736 -78.232)
		(width 0.4572)
		(layer "F.Cu")
		(net "P52V_HS2_INTVCC")
	)
	(segment
		(start 158.028386 -78.22565)
		(end 158.034736 -78.232)
		(width 0.4572)
		(layer "F.Cu")
		(net "P52V_HS2_INTVCC")
	)
	(segment
		(start 156.637736 -78.22565)
		(end 156.637736 -77.673962)
		(width 0.4572)
		(layer "F.Cu")
		(net "P52V_HS2_INTVCC")
	)
	(segment
		(start 156.637736 -78.22565)
		(end 158.028386 -78.22565)
		(width 0.4572)
		(layer "F.Cu")
		(net "P52V_HS2_INTVCC")
	)
	(segment
		(start 153.538682 -75.632564)
		(end 153.538682 -76.176632)
		(width 0.381)
		(layer "F.Cu")
		(net "P52V_HS2_INTVCC")
	)
	(segment
		(start 161.971736 -71.26605)
		(end 161.971736 -74.295)
		(width 0.4572)
		(layer "F.Cu")
		(net "P52V_HS2_INTVCC")
	)
	(segment
		(start 156.637736 -77.673962)
		(end 155.650438 -76.686664)
		(width 0.4572)
		(layer "F.Cu")
		(net "P52V_HS2_INTVCC")
	)
	(segment
		(start 154.475688 -76.2)
		(end 153.56205 -76.2)
		(width 0.4572)
		(layer "F.Cu")
		(net "P52V_HS2_INTVCC")
	)
	(segment
		(start 153.945336 -75.22591)
		(end 153.538682 -75.632564)
		(width 0.381)
		(layer "F.Cu")
		(net "P52V_HS2_INTVCC")
	)
	(segment
		(start 155.650438 -76.686664)
		(end 154.475688 -76.2)
		(width 0.4572)
		(layer "F.Cu")
		(net "P52V_HS2_INTVCC")
	)
	(via
		(at 158.034736 -78.232)
		(size 0.762)
		(drill 0.254)
		(layers "F.Cu" "B.Cu")
		(net "P52V_HS2_INTVCC")
	)
	(via
		(at 156.637736 -78.22565)
		(size 0.762)
		(drill 0.254)
		(layers "F.Cu" "B.Cu")
		(net "P52V_HS2_INTVCC")
	)
	(via
		(at 153.945336 -74.4474)
		(size 0.762)
		(drill 0.254)
		(layers "F.Cu" "B.Cu")
		(net "P52V_HS2_INTVCC")
	)
	(via
		(at 161.971736 -71.26605)
		(size 0.762)
		(drill 0.254)
		(layers "F.Cu" "B.Cu")
		(net "P52V_HS2_INTVCC")
	)
	(segment
		(start 153.945336 -74.4474)
		(end 154.347672 -74.045064)
		(width 0.2794)
		(layer "B.Cu")
		(net "P52V_HS2_INTVCC")
	)
	(segment
		(start 161.336736 -71.26605)
		(end 160.701736 -71.26605)
		(width 0.4572)
		(layer "B.Cu")
		(net "P52V_HS2_INTVCC")
	)
	(segment
		(start 154.347672 -74.045064)
		(end 154.347672 -73.504044)
		(width 0.2794)
		(layer "B.Cu")
		(net "P52V_HS2_INTVCC")
	)
	(segment
		(start 156.637736 -77.61605)
		(end 156.637736 -78.22565)
		(width 0.4572)
		(layer "B.Cu")
		(net "P52V_HS2_INTVCC")
	)
	(segment
		(start 158.034736 -77.61605)
		(end 158.034736 -78.232)
		(width 0.4572)
		(layer "B.Cu")
		(net "P52V_HS2_INTVCC")
	)
	(segment
		(start 160.701736 -71.26605)
		(end 160.339786 -71.628)
		(width 0.4572)
		(layer "B.Cu")
		(net "P52V_HS2_INTVCC")
	)
	(segment
		(start 155.621736 -77.61605)
		(end 156.637736 -77.61605)
		(width 0.4572)
		(layer "B.Cu")
		(net "P52V_HS2_INTVCC")
	)
	(segment
		(start 161.336736 -71.26605)
		(end 161.971736 -71.26605)
		(width 0.4572)
		(layer "B.Cu")
		(net "P52V_HS2_INTVCC")
	)
	(segment
		(start 412.0134 -37.82695)
		(end 410.9974 -37.82695)
		(width 0.17272)
		(layer "F.Cu")
		(net "PWRGD_P52V_HS2_4287_PG_R_N")
	)
	(segment
		(start 99.568 -11.90625)
		(end 98.31324 -13.16101)
		(width 0.17272)
		(layer "F.Cu")
		(net "PWRGD_P52V_HS2_4287_PG_R_N")
	)
	(segment
		(start 412.984442 -38.354)
		(end 413.47644 -37.862002)
		(width 0.17272)
		(layer "F.Cu")
		(net "PWRGD_P52V_HS2_4287_PG_R_N")
	)
	(segment
		(start 98.31324 -13.16101)
		(end 98.31324 -14.097)
		(width 0.17272)
		(layer "F.Cu")
		(net "PWRGD_P52V_HS2_4287_PG_R_N")
	)
	(segment
		(start 99.568 -11.90625)
		(end 100.638864 -11.90625)
		(width 0.17272)
		(layer "F.Cu")
		(net "PWRGD_P52V_HS2_4287_PG_R_N")
	)
	(segment
		(start 412.54045 -38.354)
		(end 412.984442 -38.354)
		(width 0.17272)
		(layer "F.Cu")
		(net "PWRGD_P52V_HS2_4287_PG_R_N")
	)
	(segment
		(start 412.0134 -37.82695)
		(end 412.54045 -38.354)
		(width 0.17272)
		(layer "F.Cu")
		(net "PWRGD_P52V_HS2_4287_PG_R_N")
	)
	(via
		(at 100.638864 -11.90625)
		(size 0.508)
		(drill 0.254)
		(layers "F.Cu" "B.Cu")
		(net "PWRGD_P52V_HS2_4287_PG_R_N")
	)
	(via
		(at 410.9974 -37.82695)
		(size 0.508)
		(drill 0.254)
		(layers "F.Cu" "B.Cu")
		(net "PWRGD_P52V_HS2_4287_PG_R_N")
	)
	(segment
		(start 349.179642 -6.98246)
		(end 361.00766 -18.810478)
		(width 0.12954)
		(layer "In2.Cu")
		(net "PWRGD_P52V_HS2_4287_PG_R_N")
	)
	(segment
		(start 365.625126 -25.71369)
		(end 382.825752 -25.71369)
		(width 0.12954)
		(layer "In2.Cu")
		(net "PWRGD_P52V_HS2_4287_PG_R_N")
	)
	(segment
		(start 386.397246 -29.285184)
		(end 400.963384 -29.285184)
		(width 0.12954)
		(layer "In2.Cu")
		(net "PWRGD_P52V_HS2_4287_PG_R_N")
	)
	(segment
		(start 100.638864 -11.90625)
		(end 106.70286 -5.842254)
		(width 0.12954)
		(layer "In2.Cu")
		(net "PWRGD_P52V_HS2_4287_PG_R_N")
	)
	(segment
		(start 361.00766 -18.810478)
		(end 361.00766 -21.096224)
		(width 0.12954)
		(layer "In2.Cu")
		(net "PWRGD_P52V_HS2_4287_PG_R_N")
	)
	(segment
		(start 106.70286 -5.842254)
		(end 216.596214 -5.842254)
		(width 0.12954)
		(layer "In2.Cu")
		(net "PWRGD_P52V_HS2_4287_PG_R_N")
	)
	(segment
		(start 361.00766 -21.096224)
		(end 365.625126 -25.71369)
		(width 0.12954)
		(layer "In2.Cu")
		(net "PWRGD_P52V_HS2_4287_PG_R_N")
	)
	(segment
		(start 407.071576 -37.404294)
		(end 407.494232 -37.82695)
		(width 0.12954)
		(layer "In2.Cu")
		(net "PWRGD_P52V_HS2_4287_PG_R_N")
	)
	(segment
		(start 222.981266 -6.98246)
		(end 349.179642 -6.98246)
		(width 0.12954)
		(layer "In2.Cu")
		(net "PWRGD_P52V_HS2_4287_PG_R_N")
	)
	(segment
		(start 219.286328 -8.532368)
		(end 221.431358 -8.532368)
		(width 0.12954)
		(layer "In2.Cu")
		(net "PWRGD_P52V_HS2_4287_PG_R_N")
	)
	(segment
		(start 407.071576 -35.393376)
		(end 407.071576 -37.404294)
		(width 0.12954)
		(layer "In2.Cu")
		(net "PWRGD_P52V_HS2_4287_PG_R_N")
	)
	(segment
		(start 400.963384 -29.285184)
		(end 407.071576 -35.393376)
		(width 0.12954)
		(layer "In2.Cu")
		(net "PWRGD_P52V_HS2_4287_PG_R_N")
	)
	(segment
		(start 221.431358 -8.532368)
		(end 222.981266 -6.98246)
		(width 0.12954)
		(layer "In2.Cu")
		(net "PWRGD_P52V_HS2_4287_PG_R_N")
	)
	(segment
		(start 407.494232 -37.82695)
		(end 410.9974 -37.82695)
		(width 0.12954)
		(layer "In2.Cu")
		(net "PWRGD_P52V_HS2_4287_PG_R_N")
	)
	(segment
		(start 216.596214 -5.842254)
		(end 219.286328 -8.532368)
		(width 0.12954)
		(layer "In2.Cu")
		(net "PWRGD_P52V_HS2_4287_PG_R_N")
	)
	(segment
		(start 382.825752 -25.71369)
		(end 386.397246 -29.285184)
		(width 0.12954)
		(layer "In2.Cu")
		(net "PWRGD_P52V_HS2_4287_PG_R_N")
	)
	(segment
		(start 415.331402 -50.927)
		(end 415.648648 -50.927)
		(width 0.17272)
		(layer "F.Cu")
		(net "PWRGD_P52V_HS1_4287_PG_R_N")
	)
	(segment
		(start 413.72536 -49.86909)
		(end 413.9184 -49.67605)
		(width 0.17272)
		(layer "F.Cu")
		(net "PWRGD_P52V_HS1_4287_PG_R_N")
	)
	(segment
		(start 415.331402 -49.46396)
		(end 414.13049 -49.46396)
		(width 0.17272)
		(layer "F.Cu")
		(net "PWRGD_P52V_HS1_4287_PG_R_N")
	)
	(segment
		(start 413.72536 -51.435)
		(end 413.72536 -49.86909)
		(width 0.17272)
		(layer "F.Cu")
		(net "PWRGD_P52V_HS1_4287_PG_R_N")
	)
	(segment
		(start 415.883598 -51.16195)
		(end 416.814 -51.16195)
		(width 0.17272)
		(layer "F.Cu")
		(net "PWRGD_P52V_HS1_4287_PG_R_N")
	)
	(segment
		(start 415.331402 -49.46396)
		(end 415.331402 -50.927)
		(width 0.17272)
		(layer "F.Cu")
		(net "PWRGD_P52V_HS1_4287_PG_R_N")
	)
	(segment
		(start 415.648648 -50.927)
		(end 415.883598 -51.16195)
		(width 0.17272)
		(layer "F.Cu")
		(net "PWRGD_P52V_HS1_4287_PG_R_N")
	)
	(segment
		(start 414.13049 -49.46396)
		(end 413.9184 -49.67605)
		(width 0.17272)
		(layer "F.Cu")
		(net "PWRGD_P52V_HS1_4287_PG_R_N")
	)
	(via
		(at 415.331402 -50.927)
		(size 0.762)
		(drill 0.381)
		(layers "F.Cu" "B.Cu")
		(net "PWRGD_P52V_HS1_4287_PG_R_N")
	)
	(segment
		(start 294.15867 -88.29167)
		(end 295.402 -89.535)
		(width 0.17272)
		(layer "F.Cu")
		(net "P52V_HS1_FLT")
	)
	(segment
		(start 293.753286 -75.030584)
		(end 292.1762 -76.60767)
		(width 0.17272)
		(layer "F.Cu")
		(net "P52V_HS1_FLT")
	)
	(segment
		(start 292.1762 -76.60767)
		(end 292.1762 -85.079586)
		(width 0.17272)
		(layer "F.Cu")
		(net "P52V_HS1_FLT")
	)
	(segment
		(start 277.3934 -64.897)
		(end 275.76145 -64.897)
		(width 0.17272)
		(layer "F.Cu")
		(net "P52V_HS1_FLT")
	)
	(segment
		(start 279.4254 -62.865)
		(end 277.3934 -64.897)
		(width 0.17272)
		(layer "F.Cu")
		(net "P52V_HS1_FLT")
	)
	(segment
		(start 292.1762 -85.079586)
		(end 294.15867 -87.062056)
		(width 0.17272)
		(layer "F.Cu")
		(net "P52V_HS1_FLT")
	)
	(segment
		(start 294.15867 -87.062056)
		(end 294.15867 -88.29167)
		(width 0.17272)
		(layer "F.Cu")
		(net "P52V_HS1_FLT")
	)
	(segment
		(start 415.6964 -44.069)
		(end 415.722308 -44.043092)
		(width 0.17272)
		(layer "F.Cu")
		(net "P52V_HS1_FLT")
	)
	(segment
		(start 415.722308 -44.043092)
		(end 417.449 -44.043092)
		(width 0.17272)
		(layer "F.Cu")
		(net "P52V_HS1_FLT")
	)
	(via
		(at 295.402 -89.535)
		(size 0.508)
		(drill 0.254)
		(layers "F.Cu" "B.Cu")
		(net "P52V_HS1_FLT")
	)
	(via
		(at 415.6964 -44.069)
		(size 0.762)
		(drill 0.254)
		(layers "F.Cu" "B.Cu")
		(net "P52V_HS1_FLT")
	)
	(via
		(at 293.753286 -75.030584)
		(size 0.508)
		(drill 0.254)
		(layers "F.Cu" "B.Cu")
		(net "P52V_HS1_FLT")
	)
	(via
		(at 279.4254 -62.865)
		(size 0.508)
		(drill 0.254)
		(layers "F.Cu" "B.Cu")
		(net "P52V_HS1_FLT")
	)
	(segment
		(start 293.272464 -73.504044)
		(end 293.272464 -74.549762)
		(width 0.17272)
		(layer "B.Cu")
		(net "P52V_HS1_FLT")
	)
	(segment
		(start 293.272464 -74.549762)
		(end 293.753286 -75.030584)
		(width 0.17272)
		(layer "B.Cu")
		(net "P52V_HS1_FLT")
	)
	(segment
		(start 278.80945 -62.865)
		(end 279.4254 -62.865)
		(width 0.17272)
		(layer "B.Cu")
		(net "P52V_HS1_FLT")
	)
	(segment
		(start 413.766 -51.435254)
		(end 413.766 -45.9994)
		(width 0.12954)
		(layer "In2.Cu")
		(net "P52V_HS1_FLT")
	)
	(segment
		(start 337.866228 -82.348578)
		(end 359.111804 -82.348578)
		(width 0.12954)
		(layer "In2.Cu")
		(net "P52V_HS1_FLT")
	)
	(segment
		(start 377.237498 -64.222884)
		(end 400.97837 -64.222884)
		(width 0.12954)
		(layer "In2.Cu")
		(net "P52V_HS1_FLT")
	)
	(segment
		(start 295.402 -90.17)
		(end 295.98874 -90.75674)
		(width 0.12954)
		(layer "In2.Cu")
		(net "P52V_HS1_FLT")
	)
	(segment
		(start 294.88003 -72.27443)
		(end 294.88003 -74.4728)
		(width 0.12954)
		(layer "In2.Cu")
		(net "P52V_HS1_FLT")
	)
	(segment
		(start 295.402 -89.535)
		(end 295.402 -90.17)
		(width 0.12954)
		(layer "In2.Cu")
		(net "P52V_HS1_FLT")
	)
	(segment
		(start 294.322246 -75.030584)
		(end 293.753286 -75.030584)
		(width 0.12954)
		(layer "In2.Cu")
		(net "P52V_HS1_FLT")
	)
	(segment
		(start 294.88003 -74.4728)
		(end 294.322246 -75.030584)
		(width 0.12954)
		(layer "In2.Cu")
		(net "P52V_HS1_FLT")
	)
	(segment
		(start 281.2542 -61.0362)
		(end 291.3634 -61.0362)
		(width 0.12954)
		(layer "In2.Cu")
		(net "P52V_HS1_FLT")
	)
	(segment
		(start 400.97837 -64.222884)
		(end 413.766 -51.435254)
		(width 0.12954)
		(layer "In2.Cu")
		(net "P52V_HS1_FLT")
	)
	(segment
		(start 305.7398 -93.3958)
		(end 326.819006 -93.3958)
		(width 0.12954)
		(layer "In2.Cu")
		(net "P52V_HS1_FLT")
	)
	(segment
		(start 295.98874 -90.75674)
		(end 303.10074 -90.75674)
		(width 0.12954)
		(layer "In2.Cu")
		(net "P52V_HS1_FLT")
	)
	(segment
		(start 326.819006 -93.3958)
		(end 337.866228 -82.348578)
		(width 0.12954)
		(layer "In2.Cu")
		(net "P52V_HS1_FLT")
	)
	(segment
		(start 279.4254 -62.865)
		(end 281.2542 -61.0362)
		(width 0.12954)
		(layer "In2.Cu")
		(net "P52V_HS1_FLT")
	)
	(segment
		(start 292.46957 -69.86397)
		(end 294.88003 -72.27443)
		(width 0.12954)
		(layer "In2.Cu")
		(net "P52V_HS1_FLT")
	)
	(segment
		(start 413.766 -45.9994)
		(end 415.6964 -44.069)
		(width 0.12954)
		(layer "In2.Cu")
		(net "P52V_HS1_FLT")
	)
	(segment
		(start 359.111804 -82.348578)
		(end 377.237498 -64.222884)
		(width 0.12954)
		(layer "In2.Cu")
		(net "P52V_HS1_FLT")
	)
	(segment
		(start 291.3634 -61.0362)
		(end 292.46957 -62.14237)
		(width 0.12954)
		(layer "In2.Cu")
		(net "P52V_HS1_FLT")
	)
	(segment
		(start 303.10074 -90.75674)
		(end 305.7398 -93.3958)
		(width 0.12954)
		(layer "In2.Cu")
		(net "P52V_HS1_FLT")
	)
	(segment
		(start 292.46957 -62.14237)
		(end 292.46957 -69.86397)
		(width 0.12954)
		(layer "In2.Cu")
		(net "P52V_HS1_FLT")
	)
	(segment
		(start 170.56735 -77.343)
		(end 172.09135 -75.819)
		(width 0.17272)
		(layer "F.Cu")
		(net "P52V_HS2_FLT")
	)
	(segment
		(start 153.519378 -79.351378)
		(end 158.011622 -79.351378)
		(width 0.17272)
		(layer "F.Cu")
		(net "P52V_HS2_FLT")
	)
	(segment
		(start 152.019 -74.080624)
		(end 152.019 -77.851)
		(width 0.17272)
		(layer "F.Cu")
		(net "P52V_HS2_FLT")
	)
	(segment
		(start 418.465 -43.688)
		(end 418.465 -48.005746)
		(width 0.17272)
		(layer "F.Cu")
		(net "P52V_HS2_FLT")
	)
	(segment
		(start 152.019 -77.851)
		(end 153.519378 -79.351378)
		(width 0.17272)
		(layer "F.Cu")
		(net "P52V_HS2_FLT")
	)
	(segment
		(start 154.559 -68.199254)
		(end 152.713944 -70.04431)
		(width 0.17272)
		(layer "F.Cu")
		(net "P52V_HS2_FLT")
	)
	(segment
		(start 418.170106 -43.393106)
		(end 418.465 -43.688)
		(width 0.17272)
		(layer "F.Cu")
		(net "P52V_HS2_FLT")
	)
	(segment
		(start 160.02 -77.343)
		(end 168.1734 -77.343)
		(width 0.17272)
		(layer "F.Cu")
		(net "P52V_HS2_FLT")
	)
	(segment
		(start 422.656 -50.292)
		(end 422.656 -51.435)
		(width 0.17272)
		(layer "F.Cu")
		(net "P52V_HS2_FLT")
	)
	(segment
		(start 158.011622 -79.351378)
		(end 160.02 -77.343)
		(width 0.17272)
		(layer "F.Cu")
		(net "P52V_HS2_FLT")
	)
	(segment
		(start 153.8732 -65.151)
		(end 153.8732 -65.1764)
		(width 0.17272)
		(layer "F.Cu")
		(net "P52V_HS2_FLT")
	)
	(segment
		(start 168.1734 -77.343)
		(end 170.56735 -77.343)
		(width 0.17272)
		(layer "F.Cu")
		(net "P52V_HS2_FLT")
	)
	(segment
		(start 154.559 -65.8622)
		(end 154.559 -68.199254)
		(width 0.17272)
		(layer "F.Cu")
		(net "P52V_HS2_FLT")
	)
	(segment
		(start 153.8732 -65.1764)
		(end 154.559 -65.8622)
		(width 0.17272)
		(layer "F.Cu")
		(net "P52V_HS2_FLT")
	)
	(segment
		(start 422.402 -50.038)
		(end 422.656 -50.292)
		(width 0.17272)
		(layer "F.Cu")
		(net "P52V_HS2_FLT")
	)
	(segment
		(start 420.497254 -50.038)
		(end 422.402 -50.038)
		(width 0.17272)
		(layer "F.Cu")
		(net "P52V_HS2_FLT")
	)
	(segment
		(start 418.465 -48.005746)
		(end 420.497254 -50.038)
		(width 0.17272)
		(layer "F.Cu")
		(net "P52V_HS2_FLT")
	)
	(segment
		(start 152.713944 -70.04431)
		(end 152.713944 -73.38568)
		(width 0.17272)
		(layer "F.Cu")
		(net "P52V_HS2_FLT")
	)
	(segment
		(start 152.713944 -73.38568)
		(end 152.019 -74.080624)
		(width 0.17272)
		(layer "F.Cu")
		(net "P52V_HS2_FLT")
	)
	(segment
		(start 417.449 -43.393106)
		(end 418.170106 -43.393106)
		(width 0.17272)
		(layer "F.Cu")
		(net "P52V_HS2_FLT")
	)
	(via
		(at 168.1734 -77.343)
		(size 0.508)
		(drill 0.254)
		(layers "F.Cu" "B.Cu")
		(net "P52V_HS2_FLT")
	)
	(via
		(at 422.656 -51.435)
		(size 0.508)
		(drill 0.254)
		(layers "F.Cu" "B.Cu")
		(net "P52V_HS2_FLT")
	)
	(via
		(at 153.8732 -65.151)
		(size 0.508)
		(drill 0.254)
		(layers "F.Cu" "B.Cu")
		(net "P52V_HS2_FLT")
	)
	(segment
		(start 154.347672 -65.797938)
		(end 154.347672 -66.703956)
		(width 0.17272)
		(layer "B.Cu")
		(net "P52V_HS2_FLT")
	)
	(segment
		(start 153.8732 -65.151)
		(end 153.8732 -65.1764)
		(width 0.17272)
		(layer "B.Cu")
		(net "P52V_HS2_FLT")
	)
	(segment
		(start 153.8732 -65.1764)
		(end 154.243786 -65.546986)
		(width 0.17272)
		(layer "B.Cu")
		(net "P52V_HS2_FLT")
	)
	(segment
		(start 154.243786 -65.546986)
		(end 154.347672 -65.797938)
		(width 0.17272)
		(layer "B.Cu")
		(net "P52V_HS2_FLT")
	)
	(segment
		(start 168.78935 -77.343)
		(end 168.1734 -77.343)
		(width 0.17272)
		(layer "B.Cu")
		(net "P52V_HS2_FLT")
	)
	(segment
		(start 347.264228 -101.665532)
		(end 375.65076 -73.279)
		(width 0.12954)
		(layer "In2.Cu")
		(net "P52V_HS2_FLT")
	)
	(segment
		(start 127.508 -96.0628)
		(end 133.110732 -101.665532)
		(width 0.12954)
		(layer "In2.Cu")
		(net "P52V_HS2_FLT")
	)
	(segment
		(start 127.508 -93.282262)
		(end 127.508 -96.0628)
		(width 0.12954)
		(layer "In2.Cu")
		(net "P52V_HS2_FLT")
	)
	(segment
		(start 402.843746 -73.279)
		(end 422.656 -53.466746)
		(width 0.12954)
		(layer "In2.Cu")
		(net "P52V_HS2_FLT")
	)
	(segment
		(start 128.778 -92.012262)
		(end 127.508 -93.282262)
		(width 0.12954)
		(layer "In2.Cu")
		(net "P52V_HS2_FLT")
	)
	(segment
		(start 137.905998 -99.23526)
		(end 130.683 -92.012262)
		(width 0.12954)
		(layer "In2.Cu")
		(net "P52V_HS2_FLT")
	)
	(segment
		(start 133.110732 -101.665532)
		(end 347.264228 -101.665532)
		(width 0.12954)
		(layer "In2.Cu")
		(net "P52V_HS2_FLT")
	)
	(segment
		(start 375.65076 -73.279)
		(end 402.843746 -73.279)
		(width 0.12954)
		(layer "In2.Cu")
		(net "P52V_HS2_FLT")
	)
	(segment
		(start 166.243 -92.50426)
		(end 159.512 -99.23526)
		(width 0.12954)
		(layer "In2.Cu")
		(net "P52V_HS2_FLT")
	)
	(segment
		(start 159.512 -99.23526)
		(end 137.905998 -99.23526)
		(width 0.12954)
		(layer "In2.Cu")
		(net "P52V_HS2_FLT")
	)
	(segment
		(start 166.243 -79.2734)
		(end 166.243 -92.50426)
		(width 0.12954)
		(layer "In2.Cu")
		(net "P52V_HS2_FLT")
	)
	(segment
		(start 422.656 -53.466746)
		(end 422.656 -51.435)
		(width 0.12954)
		(layer "In2.Cu")
		(net "P52V_HS2_FLT")
	)
	(segment
		(start 168.1734 -77.343)
		(end 166.243 -79.2734)
		(width 0.12954)
		(layer "In2.Cu")
		(net "P52V_HS2_FLT")
	)
	(segment
		(start 130.683 -92.012262)
		(end 128.778 -92.012262)
		(width 0.12954)
		(layer "In2.Cu")
		(net "P52V_HS2_FLT")
	)
	(segment
		(start 294.271192 -74.790808)
		(end 294.271192 -75.324208)
		(width 0.17272)
		(layer "F.Cu")
		(net "PWRGD_P52V_HS1_4287_PG_N")
	)
	(segment
		(start 292.65372 -84.88172)
		(end 294.63619 -86.86419)
		(width 0.17272)
		(layer "F.Cu")
		(net "PWRGD_P52V_HS1_4287_PG_N")
	)
	(segment
		(start 294.63619 -88.00719)
		(end 296.164 -89.535)
		(width 0.17272)
		(layer "F.Cu")
		(net "PWRGD_P52V_HS1_4287_PG_N")
	)
	(segment
		(start 293.772336 -74.291952)
		(end 294.271192 -74.790808)
		(width 0.17272)
		(layer "F.Cu")
		(net "PWRGD_P52V_HS1_4287_PG_N")
	)
	(segment
		(start 294.271192 -75.324208)
		(end 292.65372 -76.94168)
		(width 0.17272)
		(layer "F.Cu")
		(net "PWRGD_P52V_HS1_4287_PG_N")
	)
	(segment
		(start 412.496 -48.006)
		(end 413.04845 -48.006)
		(width 0.17272)
		(layer "F.Cu")
		(net "PWRGD_P52V_HS1_4287_PG_N")
	)
	(segment
		(start 413.04845 -48.006)
		(end 413.9184 -48.87595)
		(width 0.17272)
		(layer "F.Cu")
		(net "PWRGD_P52V_HS1_4287_PG_N")
	)
	(segment
		(start 294.63619 -86.86419)
		(end 294.63619 -88.00719)
		(width 0.17272)
		(layer "F.Cu")
		(net "PWRGD_P52V_HS1_4287_PG_N")
	)
	(segment
		(start 292.65372 -76.94168)
		(end 292.65372 -84.88172)
		(width 0.17272)
		(layer "F.Cu")
		(net "PWRGD_P52V_HS1_4287_PG_N")
	)
	(via
		(at 412.496 -48.006)
		(size 0.508)
		(drill 0.254)
		(layers "F.Cu" "B.Cu")
		(net "PWRGD_P52V_HS1_4287_PG_N")
	)
	(via
		(at 293.772336 -74.291952)
		(size 0.508)
		(drill 0.254)
		(layers "F.Cu" "B.Cu")
		(net "PWRGD_P52V_HS1_4287_PG_N")
	)
	(via
		(at 296.164 -89.535)
		(size 0.508)
		(drill 0.254)
		(layers "F.Cu" "B.Cu")
		(net "PWRGD_P52V_HS1_4287_PG_N")
	)
	(segment
		(start 293.772336 -73.504044)
		(end 293.772336 -74.291952)
		(width 0.17272)
		(layer "B.Cu")
		(net "PWRGD_P52V_HS1_4287_PG_N")
	)
	(segment
		(start 412.496 -50.927254)
		(end 400.37385 -63.049404)
		(width 0.12954)
		(layer "In2.Cu")
		(net "PWRGD_P52V_HS1_4287_PG_N")
	)
	(segment
		(start 376.751088 -63.049404)
		(end 358.625394 -81.175098)
		(width 0.12954)
		(layer "In2.Cu")
		(net "PWRGD_P52V_HS1_4287_PG_N")
	)
	(segment
		(start 400.37385 -63.049404)
		(end 376.751088 -63.049404)
		(width 0.12954)
		(layer "In2.Cu")
		(net "PWRGD_P52V_HS1_4287_PG_N")
	)
	(segment
		(start 412.496 -48.006)
		(end 412.496 -50.927254)
		(width 0.12954)
		(layer "In2.Cu")
		(net "PWRGD_P52V_HS1_4287_PG_N")
	)
	(segment
		(start 337.380072 -81.175098)
		(end 329.02017 -89.535)
		(width 0.12954)
		(layer "In2.Cu")
		(net "PWRGD_P52V_HS1_4287_PG_N")
	)
	(segment
		(start 358.625394 -81.175098)
		(end 337.380072 -81.175098)
		(width 0.12954)
		(layer "In2.Cu")
		(net "PWRGD_P52V_HS1_4287_PG_N")
	)
	(segment
		(start 329.02017 -89.535)
		(end 296.164 -89.535)
		(width 0.12954)
		(layer "In2.Cu")
		(net "PWRGD_P52V_HS1_4287_PG_N")
	)
	(segment
		(start 411.72384 -27.452828)
		(end 411.2006 -26.929588)
		(width 0.254)
		(layer "F.Cu")
		(net "P12V_FAN_LED")
	)
	(segment
		(start 415.29 -22.0726)
		(end 415.671 -21.6916)
		(width 0.254)
		(layer "F.Cu")
		(net "P12V_FAN_LED")
	)
	(segment
		(start 411.2006 -23.800054)
		(end 412.928054 -22.0726)
		(width 0.254)
		(layer "F.Cu")
		(net "P12V_FAN_LED")
	)
	(segment
		(start 412.928054 -22.0726)
		(end 415.29 -22.0726)
		(width 0.254)
		(layer "F.Cu")
		(net "P12V_FAN_LED")
	)
	(segment
		(start 411.2006 -26.929588)
		(end 411.2006 -23.800054)
		(width 0.254)
		(layer "F.Cu")
		(net "P12V_FAN_LED")
	)
	(via
		(at 419.363398 -25.332436)
		(size 0.508)
		(drill 0.254)
		(layers "F.Cu" "B.Cu")
		(net "P12V_FAN_LED")
	)
	(via
		(at 417.966398 -26.450036)
		(size 0.508)
		(drill 0.254)
		(layers "F.Cu" "B.Cu")
		(net "P12V_FAN_LED")
	)
	(via
		(at 418.211 -23.876)
		(size 0.762)
		(drill 0.381)
		(layers "F.Cu" "B.Cu")
		(net "P12V_FAN_LED")
	)
	(via
		(at 416.188398 -26.450036)
		(size 0.508)
		(drill 0.254)
		(layers "F.Cu" "B.Cu")
		(net "P12V_FAN_LED")
	)
	(via
		(at 417.077398 -26.450036)
		(size 0.508)
		(drill 0.254)
		(layers "F.Cu" "B.Cu")
		(net "P12V_FAN_LED")
	)
	(via
		(at 418.5412 -20.3708)
		(size 0.508)
		(drill 0.254)
		(layers "F.Cu" "B.Cu")
		(net "P12V_FAN_LED")
	)
	(via
		(at 418.5412 -21.1328)
		(size 0.508)
		(drill 0.254)
		(layers "F.Cu" "B.Cu")
		(net "P12V_FAN_LED")
	)
	(via
		(at 418.347398 -25.764236)
		(size 0.508)
		(drill 0.254)
		(layers "F.Cu" "B.Cu")
		(net "P12V_FAN_LED")
	)
	(via
		(at 417.458398 -25.764236)
		(size 0.508)
		(drill 0.254)
		(layers "F.Cu" "B.Cu")
		(net "P12V_FAN_LED")
	)
	(via
		(at 416.569398 -25.764236)
		(size 0.508)
		(drill 0.254)
		(layers "F.Cu" "B.Cu")
		(net "P12V_FAN_LED")
	)
	(via
		(at 418.5412 -19.6088)
		(size 0.508)
		(drill 0.254)
		(layers "F.Cu" "B.Cu")
		(net "P12V_FAN_LED")
	)
	(segment
		(start 376.818398 -2.832862)
		(end 376.9614 -3.181096)
		(width 0.4572)
		(layer "B.Cu")
		(net "P12V_FAN_LED")
	)
	(segment
		(start 376.9614 -3.181096)
		(end 376.9614 -3.937)
		(width 0.4572)
		(layer "B.Cu")
		(net "P12V_FAN_LED")
	)
	(segment
		(start 376.9614 -3.937)
		(end 377.4694 -4.445)
		(width 0.4572)
		(layer "B.Cu")
		(net "P12V_FAN_LED")
	)
	(segment
		(start 374.95099 -2.286)
		(end 376.271536 -2.286)
		(width 0.4572)
		(layer "B.Cu")
		(net "P12V_FAN_LED")
	)
	(segment
		(start 374.700038 -2.035048)
		(end 374.95099 -2.286)
		(width 0.4572)
		(layer "B.Cu")
		(net "P12V_FAN_LED")
	)
	(segment
		(start 376.271536 -2.286)
		(end 376.818398 -2.832862)
		(width 0.4572)
		(layer "B.Cu")
		(net "P12V_FAN_LED")
	)
	(segment
		(start 370.328444 -1.524)
		(end 371.671596 -2.867152)
		(width 0.4572)
		(layer "In2.Cu")
		(net "P12V_FAN_LED")
	)
	(segment
		(start 372.544848 -2.867152)
		(end 373.093742 -2.318258)
		(width 0.254)
		(layer "In2.Cu")
		(net "P12V_FAN_LED")
	)
	(segment
		(start 73.62063 -2.035048)
		(end 74.448924 -2.863342)
		(width 0.4572)
		(layer "In2.Cu")
		(net "P12V_FAN_LED")
	)
	(segment
		(start 371.671596 -2.867152)
		(end 372.544848 -2.867152)
		(width 0.254)
		(layer "In2.Cu")
		(net "P12V_FAN_LED")
	)
	(segment
		(start 373.376952 -2.035048)
		(end 374.700038 -2.035048)
		(width 0.4572)
		(layer "In2.Cu")
		(net "P12V_FAN_LED")
	)
	(segment
		(start 74.448924 -2.863342)
		(end 74.503788 -2.995676)
		(width 0.4572)
		(layer "In2.Cu")
		(net "P12V_FAN_LED")
	)
	(segment
		(start 72.300084 -2.035048)
		(end 73.62063 -2.035048)
		(width 0.4572)
		(layer "In2.Cu")
		(net "P12V_FAN_LED")
	)
	(segment
		(start 373.093742 -2.318258)
		(end 373.376952 -2.035048)
		(width 0.4572)
		(layer "In2.Cu")
		(net "P12V_FAN_LED")
	)
	(segment
		(start 74.503788 -3.556)
		(end 75.519788 -4.572)
		(width 0.4572)
		(layer "In2.Cu")
		(net "P12V_FAN_LED")
	)
	(segment
		(start 74.503788 -2.995676)
		(end 74.503788 -3.556)
		(width 0.4572)
		(layer "In2.Cu")
		(net "P12V_FAN_LED")
	)
	(segment
		(start 82.296 -1.524)
		(end 370.328444 -1.524)
		(width 0.4572)
		(layer "In2.Cu")
		(net "P12V_FAN_LED")
	)
	(segment
		(start 79.248 -4.572)
		(end 82.296 -1.524)
		(width 0.4572)
		(layer "In2.Cu")
		(net "P12V_FAN_LED")
	)
	(segment
		(start 75.519788 -4.572)
		(end 79.248 -4.572)
		(width 0.4572)
		(layer "In2.Cu")
		(net "P12V_FAN_LED")
	)
	(segment
		(start 448.127628 -86.457028)
		(end 447.73342 -86.457028)
		(width 0.1778)
		(layer "F.Cu")
		(net "P3V3_HPDB_EN")
	)
	(segment
		(start 450.045582 -87.400892)
		(end 450.01307 -87.36838)
		(width 0.1778)
		(layer "F.Cu")
		(net "P3V3_HPDB_EN")
	)
	(segment
		(start 450.045582 -88.465152)
		(end 450.045582 -89.48547)
		(width 0.1778)
		(layer "F.Cu")
		(net "P3V3_HPDB_EN")
	)
	(segment
		(start 450.045582 -88.465152)
		(end 450.045582 -87.400892)
		(width 0.1778)
		(layer "F.Cu")
		(net "P3V3_HPDB_EN")
	)
	(segment
		(start 448.9958 -87.9348)
		(end 448.9958 -87.3252)
		(width 0.1778)
		(layer "F.Cu")
		(net "P3V3_HPDB_EN")
	)
	(segment
		(start 449.56222 -87.36838)
		(end 448.9958 -87.9348)
		(width 0.1778)
		(layer "F.Cu")
		(net "P3V3_HPDB_EN")
	)
	(segment
		(start 450.01307 -87.36838)
		(end 449.56222 -87.36838)
		(width 0.1778)
		(layer "F.Cu")
		(net "P3V3_HPDB_EN")
	)
	(segment
		(start 448.9958 -87.3252)
		(end 448.127628 -86.457028)
		(width 0.1778)
		(layer "F.Cu")
		(net "P3V3_HPDB_EN")
	)
	(via
		(at 448.9958 -87.9348)
		(size 0.508)
		(drill 0.254)
		(layers "F.Cu" "B.Cu")
		(net "P3V3_HPDB_EN")
	)
	(segment
		(start 456.0824 -78.232)
		(end 456.0824 -86.233)
		(width 0.17272)
		(layer "F.Cu")
		(net "P12V_HPDB_PWRGD")
	)
	(segment
		(start 454.94702 -87.36838)
		(end 450.81317 -87.36838)
		(width 0.17272)
		(layer "F.Cu")
		(net "P12V_HPDB_PWRGD")
	)
	(segment
		(start 456.0824 -86.233)
		(end 454.94702 -87.36838)
		(width 0.17272)
		(layer "F.Cu")
		(net "P12V_HPDB_PWRGD")
	)
	(via
		(at 456.0824 -78.232)
		(size 0.508)
		(drill 0.254)
		(layers "F.Cu" "B.Cu")
		(net "P12V_HPDB_PWRGD")
	)
	(segment
		(start 468.056976 -78.232)
		(end 469.635078 -79.810102)
		(width 0.12954)
		(layer "In7.Cu")
		(net "P12V_HPDB_PWRGD")
	)
	(segment
		(start 456.0824 -78.232)
		(end 468.056976 -78.232)
		(width 0.12954)
		(layer "In7.Cu")
		(net "P12V_HPDB_PWRGD")
	)
	(segment
		(start 450.845682 -89.48547)
		(end 451.455282 -89.48547)
		(width 0.4572)
		(layer "F.Cu")
		(net "P12V_HPDB")
	)
	(via
		(at 453.14489 -98.94189)
		(size 0.508)
		(drill 0.254)
		(layers "F.Cu" "B.Cu")
		(net "P12V_HPDB")
	)
	(via
		(at 417.30041 -29.0703)
		(size 0.4572)
		(drill 0.254)
		(layers "F.Cu" "B.Cu")
		(net "P12V_HPDB")
	)
	(via
		(at 416.400488 -28.4353)
		(size 0.4572)
		(drill 0.254)
		(layers "F.Cu" "B.Cu")
		(net "P12V_HPDB")
	)
	(via
		(at 417.30041 -28.4353)
		(size 0.4572)
		(drill 0.254)
		(layers "F.Cu" "B.Cu")
		(net "P12V_HPDB")
	)
	(via
		(at 452.50989 -98.28149)
		(size 0.508)
		(drill 0.254)
		(layers "F.Cu" "B.Cu")
		(net "P12V_HPDB")
	)
	(via
		(at 418.200332 -29.0703)
		(size 0.4572)
		(drill 0.254)
		(layers "F.Cu" "B.Cu")
		(net "P12V_HPDB")
	)
	(via
		(at 453.14489 -102.34549)
		(size 0.508)
		(drill 0.254)
		(layers "F.Cu" "B.Cu")
		(net "P12V_HPDB")
	)
	(via
		(at 451.824852 -98.274632)
		(size 0.508)
		(drill 0.254)
		(layers "F.Cu" "B.Cu")
		(net "P12V_HPDB")
	)
	(via
		(at 451.824852 -102.338632)
		(size 0.508)
		(drill 0.254)
		(layers "F.Cu" "B.Cu")
		(net "P12V_HPDB")
	)
	(via
		(at 420.8907 -28.92044)
		(size 0.508)
		(drill 0.254)
		(layers "F.Cu" "B.Cu")
		(net "P12V_HPDB")
	)
	(via
		(at 452.50989 -102.34549)
		(size 0.508)
		(drill 0.254)
		(layers "F.Cu" "B.Cu")
		(net "P12V_HPDB")
	)
	(via
		(at 451.824852 -98.935032)
		(size 0.508)
		(drill 0.254)
		(layers "F.Cu" "B.Cu")
		(net "P12V_HPDB")
	)
	(via
		(at 424.8912 -30.5816)
		(size 0.508)
		(drill 0.254)
		(layers "F.Cu" "B.Cu")
		(net "P12V_HPDB")
	)
	(via
		(at 416.400488 -29.0703)
		(size 0.4572)
		(drill 0.254)
		(layers "F.Cu" "B.Cu")
		(net "P12V_HPDB")
	)
	(via
		(at 419.100508 -29.0703)
		(size 0.4572)
		(drill 0.254)
		(layers "F.Cu" "B.Cu")
		(net "P12V_HPDB")
	)
	(via
		(at 420.8907 -29.65704)
		(size 0.508)
		(drill 0.254)
		(layers "F.Cu" "B.Cu")
		(net "P12V_HPDB")
	)
	(via
		(at 421.7035 -28.92044)
		(size 0.508)
		(drill 0.254)
		(layers "F.Cu" "B.Cu")
		(net "P12V_HPDB")
	)
	(via
		(at 453.14489 -98.28149)
		(size 0.508)
		(drill 0.254)
		(layers "F.Cu" "B.Cu")
		(net "P12V_HPDB")
	)
	(via
		(at 453.14489 -103.00589)
		(size 0.508)
		(drill 0.254)
		(layers "F.Cu" "B.Cu")
		(net "P12V_HPDB")
	)
	(via
		(at 424.1292 -30.5816)
		(size 0.508)
		(drill 0.254)
		(layers "F.Cu" "B.Cu")
		(net "P12V_HPDB")
	)
	(via
		(at 418.200332 -28.4353)
		(size 0.4572)
		(drill 0.254)
		(layers "F.Cu" "B.Cu")
		(net "P12V_HPDB")
	)
	(via
		(at 419.100508 -28.4353)
		(size 0.4572)
		(drill 0.254)
		(layers "F.Cu" "B.Cu")
		(net "P12V_HPDB")
	)
	(via
		(at 451.455282 -89.48547)
		(size 0.508)
		(drill 0.254)
		(layers "F.Cu" "B.Cu")
		(net "P12V_HPDB")
	)
	(via
		(at 425.6532 -30.5816)
		(size 0.508)
		(drill 0.254)
		(layers "F.Cu" "B.Cu")
		(net "P12V_HPDB")
	)
	(via
		(at 421.7035 -29.65704)
		(size 0.508)
		(drill 0.254)
		(layers "F.Cu" "B.Cu")
		(net "P12V_HPDB")
	)
	(via
		(at 412.84398 -26.40076)
		(size 0.508)
		(drill 0.254)
		(layers "F.Cu" "B.Cu")
		(net "P12V_HPDB")
	)
	(via
		(at 452.50989 -98.94189)
		(size 0.508)
		(drill 0.254)
		(layers "F.Cu" "B.Cu")
		(net "P12V_HPDB")
	)
	(via
		(at 452.50989 -103.00589)
		(size 0.508)
		(drill 0.254)
		(layers "F.Cu" "B.Cu")
		(net "P12V_HPDB")
	)
	(via
		(at 451.824852 -102.999032)
		(size 0.508)
		(drill 0.254)
		(layers "F.Cu" "B.Cu")
		(net "P12V_HPDB")
	)
	(via
		(at 444.246 -105.664)
		(size 0.762)
		(drill 0.381)
		(layers "F.Cu" "B.Cu")
		(net "SW_P3V3_HPDB_FLT")
	)
	(segment
		(start 449.905628 -84.409788)
		(end 449.501768 -84.813648)
		(width 0.254)
		(layer "F.Cu")
		(net "P3V3_HPDB_REF")
	)
	(segment
		(start 449.501768 -85.000846)
		(end 449.245482 -85.257132)
		(width 0.1778)
		(layer "F.Cu")
		(net "P3V3_HPDB_REF")
	)
	(segment
		(start 449.245482 -85.257132)
		(end 447.73342 -85.257132)
		(width 0.1778)
		(layer "F.Cu")
		(net "P3V3_HPDB_REF")
	)
	(segment
		(start 450.02069 -84.409788)
		(end 449.905628 -84.409788)
		(width 0.254)
		(layer "F.Cu")
		(net "P3V3_HPDB_REF")
	)
	(segment
		(start 449.501768 -84.813648)
		(end 449.501768 -85.000846)
		(width 0.254)
		(layer "F.Cu")
		(net "P3V3_HPDB_REF")
	)
	(via
		(at 449.501768 -85.000846)
		(size 0.508)
		(drill 0.254)
		(layers "F.Cu" "B.Cu")
		(net "P3V3_HPDB_REF")
	)
	(segment
		(start 447.73342 -84.457032)
		(end 448.358768 -84.457032)
		(width 0.1778)
		(layer "F.Cu")
		(net "P3V3_HPDB_CS")
	)
	(segment
		(start 449.448682 -83.714082)
		(end 449.700396 -83.714082)
		(width 0.1778)
		(layer "F.Cu")
		(net "P3V3_HPDB_CS")
	)
	(segment
		(start 448.691 -84.1248)
		(end 448.945 -84.1248)
		(width 0.1778)
		(layer "F.Cu")
		(net "P3V3_HPDB_CS")
	)
	(segment
		(start 449.4022 -83.6676)
		(end 449.448682 -83.714082)
		(width 0.1778)
		(layer "F.Cu")
		(net "P3V3_HPDB_CS")
	)
	(segment
		(start 449.700396 -83.714082)
		(end 450.02069 -83.393788)
		(width 0.1778)
		(layer "F.Cu")
		(net "P3V3_HPDB_CS")
	)
	(segment
		(start 448.945 -84.1248)
		(end 449.4022 -83.6676)
		(width 0.1778)
		(layer "F.Cu")
		(net "P3V3_HPDB_CS")
	)
	(segment
		(start 448.358768 -84.457032)
		(end 448.691 -84.1248)
		(width 0.1778)
		(layer "F.Cu")
		(net "P3V3_HPDB_CS")
	)
	(via
		(at 449.4022 -83.6676)
		(size 0.508)
		(drill 0.254)
		(layers "F.Cu" "B.Cu")
		(net "P3V3_HPDB_CS")
	)
	(segment
		(start 444.643002 -49.46396)
		(end 444.643002 -50.292)
		(width 0.17272)
		(layer "F.Cu")
		(net "P3V3_HPDB_PG")
	)
	(segment
		(start 444.77305 -50.927)
		(end 444.643002 -50.796952)
		(width 0.17272)
		(layer "F.Cu")
		(net "P3V3_HPDB_PG")
	)
	(segment
		(start 444.643002 -50.796952)
		(end 444.643002 -50.292)
		(width 0.17272)
		(layer "F.Cu")
		(net "P3V3_HPDB_PG")
	)
	(via
		(at 442.595 -50.292)
		(size 0.6604)
		(drill 0.3302)
		(layers "F.Cu" "B.Cu")
		(net "P3V3_HPDB_PG")
	)
	(via
		(at 444.643002 -50.292)
		(size 0.508)
		(drill 0.254)
		(layers "F.Cu" "B.Cu")
		(net "P3V3_HPDB_PG")
	)
	(segment
		(start 441.96 -50.292)
		(end 442.595 -50.292)
		(width 0.17272)
		(layer "B.Cu")
		(net "P3V3_HPDB_PG")
	)
	(segment
		(start 440.92495 -47.371)
		(end 440.92495 -49.25695)
		(width 0.17272)
		(layer "B.Cu")
		(net "P3V3_HPDB_PG")
	)
	(segment
		(start 440.92495 -49.25695)
		(end 441.96 -50.292)
		(width 0.17272)
		(layer "B.Cu")
		(net "P3V3_HPDB_PG")
	)
	(segment
		(start 442.595 -50.292)
		(end 444.643002 -50.292)
		(width 0.17272)
		(layer "B.Cu")
		(net "P3V3_HPDB_PG")
	)
	(segment
		(start 450.041264 -86.270846)
		(end 449.643754 -86.270846)
		(width 0.254)
		(layer "F.Cu")
		(net "P3V3_HPDB_FB")
	)
	(segment
		(start 449.643754 -86.270846)
		(end 449.4022 -86.5124)
		(width 0.254)
		(layer "F.Cu")
		(net "P3V3_HPDB_FB")
	)
	(segment
		(start 449.4022 -86.5124)
		(end 449.160646 -86.270846)
		(width 0.254)
		(layer "F.Cu")
		(net "P3V3_HPDB_FB")
	)
	(segment
		(start 452.073264 -86.270846)
		(end 451.057264 -86.270846)
		(width 0.254)
		(layer "F.Cu")
		(net "P3V3_HPDB_FB")
	)
	(segment
		(start 451.057264 -86.270846)
		(end 450.041264 -86.270846)
		(width 0.254)
		(layer "F.Cu")
		(net "P3V3_HPDB_FB")
	)
	(segment
		(start 448.627246 -86.270846)
		(end 448.413632 -86.057232)
		(width 0.1778)
		(layer "F.Cu")
		(net "P3V3_HPDB_FB")
	)
	(segment
		(start 449.160646 -86.270846)
		(end 448.627246 -86.270846)
		(width 0.254)
		(layer "F.Cu")
		(net "P3V3_HPDB_FB")
	)
	(segment
		(start 448.413632 -86.057232)
		(end 447.73342 -86.057232)
		(width 0.1778)
		(layer "F.Cu")
		(net "P3V3_HPDB_FB")
	)
	(via
		(at 449.4022 -86.5124)
		(size 0.508)
		(drill 0.254)
		(layers "F.Cu" "B.Cu")
		(net "P3V3_HPDB_FB")
	)
	(segment
		(start 449.72605 -31.623)
		(end 450.33565 -31.623)
		(width 0.17272)
		(layer "F.Cu")
		(net "SMB_PDB_MISC_SCL_R1")
	)
	(segment
		(start 449.75145 -30.607)
		(end 449.75145 -31.5976)
		(width 0.17272)
		(layer "F.Cu")
		(net "SMB_PDB_MISC_SCL_R1")
	)
	(segment
		(start 449.75145 -31.5976)
		(end 449.72605 -31.623)
		(width 0.17272)
		(layer "F.Cu")
		(net "SMB_PDB_MISC_SCL_R1")
	)
	(segment
		(start 434.848 -40.74795)
		(end 433.6288 -40.74795)
		(width 0.17272)
		(layer "F.Cu")
		(net "SMB_PDB_MISC_SCL_R1")
	)
	(segment
		(start 433.6288 -40.30472)
		(end 433.80152 -40.132)
		(width 0.17272)
		(layer "F.Cu")
		(net "SMB_PDB_MISC_SCL_R1")
	)
	(segment
		(start 433.6288 -40.74795)
		(end 433.6288 -40.30472)
		(width 0.17272)
		(layer "F.Cu")
		(net "SMB_PDB_MISC_SCL_R1")
	)
	(segment
		(start 433.80152 -40.132)
		(end 434.2384 -40.132)
		(width 0.17272)
		(layer "F.Cu")
		(net "SMB_PDB_MISC_SCL_R1")
	)
	(via
		(at 450.33565 -31.623)
		(size 0.508)
		(drill 0.254)
		(layers "F.Cu" "B.Cu")
		(net "SMB_PDB_MISC_SCL_R1")
	)
	(via
		(at 434.2384 -40.132)
		(size 0.508)
		(drill 0.254)
		(layers "F.Cu" "B.Cu")
		(net "SMB_PDB_MISC_SCL_R1")
	)
	(segment
		(start 436.5244 -33.909)
		(end 434.2384 -36.195)
		(width 0.17272)
		(layer "B.Cu")
		(net "SMB_PDB_MISC_SCL_R1")
	)
	(segment
		(start 448.817746 -31.623)
		(end 446.531746 -33.909)
		(width 0.17272)
		(layer "B.Cu")
		(net "SMB_PDB_MISC_SCL_R1")
	)
	(segment
		(start 434.2384 -36.195)
		(end 434.2384 -40.132)
		(width 0.17272)
		(layer "B.Cu")
		(net "SMB_PDB_MISC_SCL_R1")
	)
	(segment
		(start 450.33565 -31.623)
		(end 448.817746 -31.623)
		(width 0.17272)
		(layer "B.Cu")
		(net "SMB_PDB_MISC_SCL_R1")
	)
	(segment
		(start 446.531746 -33.909)
		(end 436.5244 -33.909)
		(width 0.17272)
		(layer "B.Cu")
		(net "SMB_PDB_MISC_SCL_R1")
	)
	(segment
		(start 440.685682 -50.717704)
		(end 440.69 -50.713386)
		(width 0.17272)
		(layer "F.Cu")
		(net "PWRGD_P3V3_AUX_MB_BUF_N")
	)
	(segment
		(start 443.103 -47.370746)
		(end 443.103 -47.625)
		(width 0.17272)
		(layer "F.Cu")
		(net "PWRGD_P3V3_AUX_MB_BUF_N")
	)
	(segment
		(start 440.70905 -51.181)
		(end 440.685682 -51.157632)
		(width 0.17272)
		(layer "F.Cu")
		(net "PWRGD_P3V3_AUX_MB_BUF_N")
	)
	(segment
		(start 442.976 -47.752)
		(end 442.976 -48.91405)
		(width 0.17272)
		(layer "F.Cu")
		(net "PWRGD_P3V3_AUX_MB_BUF_N")
	)
	(segment
		(start 440.685682 -51.157632)
		(end 440.685682 -50.717704)
		(width 0.17272)
		(layer "F.Cu")
		(net "PWRGD_P3V3_AUX_MB_BUF_N")
	)
	(segment
		(start 441.767214 -46.03496)
		(end 443.103 -47.370746)
		(width 0.17272)
		(layer "F.Cu")
		(net "PWRGD_P3V3_AUX_MB_BUF_N")
	)
	(segment
		(start 441.369958 -46.03496)
		(end 441.767214 -46.03496)
		(width 0.17272)
		(layer "F.Cu")
		(net "PWRGD_P3V3_AUX_MB_BUF_N")
	)
	(segment
		(start 442.976 -48.91405)
		(end 440.70905 -51.181)
		(width 0.17272)
		(layer "F.Cu")
		(net "PWRGD_P3V3_AUX_MB_BUF_N")
	)
	(segment
		(start 443.103 -47.625)
		(end 442.976 -47.752)
		(width 0.17272)
		(layer "F.Cu")
		(net "PWRGD_P3V3_AUX_MB_BUF_N")
	)
	(segment
		(start 440.69 -50.713386)
		(end 440.69 -49.767998)
		(width 0.17272)
		(layer "F.Cu")
		(net "PWRGD_P3V3_AUX_MB_BUF_N")
	)
	(via
		(at 443.103 -47.625)
		(size 0.762)
		(drill 0.381)
		(layers "F.Cu" "B.Cu")
		(net "PWRGD_P3V3_AUX_MB_BUF_N")
	)
	(segment
		(start 175.78705 -45.212)
		(end 176.97704 -45.212)
		(width 0.17272)
		(layer "F.Cu")
		(net "GPU_HSC2_BUF_EN_N")
	)
	(segment
		(start 188.85154 -64.314578)
		(end 186.599322 -62.06236)
		(width 0.17272)
		(layer "F.Cu")
		(net "GPU_HSC2_BUF_EN_N")
	)
	(segment
		(start 184.628536 -62.06236)
		(end 181.875684 -59.309508)
		(width 0.17272)
		(layer "F.Cu")
		(net "GPU_HSC2_BUF_EN_N")
	)
	(segment
		(start 177.130202 -50.09896)
		(end 177.079402 -50.09896)
		(width 0.17272)
		(layer "F.Cu")
		(net "GPU_HSC2_BUF_EN_N")
	)
	(segment
		(start 181.875684 -59.309508)
		(end 181.875684 -54.304692)
		(width 0.17272)
		(layer "F.Cu")
		(net "GPU_HSC2_BUF_EN_N")
	)
	(segment
		(start 175.4886 -45.51045)
		(end 175.4886 -47.44339)
		(width 0.17272)
		(layer "F.Cu")
		(net "GPU_HSC2_BUF_EN_N")
	)
	(segment
		(start 175.269398 -47.752)
		(end 175.269398 -48.812704)
		(width 0.17272)
		(layer "F.Cu")
		(net "GPU_HSC2_BUF_EN_N")
	)
	(segment
		(start 175.66005 -45.339)
		(end 175.4886 -45.51045)
		(width 0.17272)
		(layer "F.Cu")
		(net "GPU_HSC2_BUF_EN_N")
	)
	(segment
		(start 175.269398 -48.812704)
		(end 176.555654 -50.09896)
		(width 0.17272)
		(layer "F.Cu")
		(net "GPU_HSC2_BUF_EN_N")
	)
	(segment
		(start 176.555654 -50.09896)
		(end 177.079402 -50.09896)
		(width 0.17272)
		(layer "F.Cu")
		(net "GPU_HSC2_BUF_EN_N")
	)
	(segment
		(start 175.4886 -47.44339)
		(end 175.269398 -47.662592)
		(width 0.17272)
		(layer "F.Cu")
		(net "GPU_HSC2_BUF_EN_N")
	)
	(segment
		(start 184.550304 -84.116164)
		(end 188.85154 -79.814928)
		(width 0.17272)
		(layer "F.Cu")
		(net "GPU_HSC2_BUF_EN_N")
	)
	(segment
		(start 181.875684 -54.304692)
		(end 178.886612 -51.31562)
		(width 0.17272)
		(layer "F.Cu")
		(net "GPU_HSC2_BUF_EN_N")
	)
	(segment
		(start 186.599322 -62.06236)
		(end 184.628536 -62.06236)
		(width 0.17272)
		(layer "F.Cu")
		(net "GPU_HSC2_BUF_EN_N")
	)
	(segment
		(start 175.66005 -45.339)
		(end 175.78705 -45.212)
		(width 0.17272)
		(layer "F.Cu")
		(net "GPU_HSC2_BUF_EN_N")
	)
	(segment
		(start 178.346862 -51.31562)
		(end 177.130202 -50.09896)
		(width 0.17272)
		(layer "F.Cu")
		(net "GPU_HSC2_BUF_EN_N")
	)
	(segment
		(start 188.85154 -79.814928)
		(end 188.85154 -64.314578)
		(width 0.17272)
		(layer "F.Cu")
		(net "GPU_HSC2_BUF_EN_N")
	)
	(segment
		(start 182.219854 -83.818984)
		(end 182.517034 -84.116164)
		(width 0.17272)
		(layer "F.Cu")
		(net "GPU_HSC2_BUF_EN_N")
	)
	(segment
		(start 182.517034 -84.116164)
		(end 184.550304 -84.116164)
		(width 0.17272)
		(layer "F.Cu")
		(net "GPU_HSC2_BUF_EN_N")
	)
	(segment
		(start 178.886612 -51.31562)
		(end 178.346862 -51.31562)
		(width 0.17272)
		(layer "F.Cu")
		(net "GPU_HSC2_BUF_EN_N")
	)
	(segment
		(start 175.269398 -47.662592)
		(end 175.269398 -47.752)
		(width 0.17272)
		(layer "F.Cu")
		(net "GPU_HSC2_BUF_EN_N")
	)
	(via
		(at 182.219854 -83.818984)
		(size 0.508)
		(drill 0.254)
		(layers "F.Cu" "B.Cu")
		(net "GPU_HSC2_BUF_EN_N")
	)
	(segment
		(start 208.3562 -94.5388)
		(end 209.7786 -94.5388)
		(width 0.12954)
		(layer "In2.Cu")
		(net "GPU_HSC2_BUF_EN_N")
	)
	(segment
		(start 182.219854 -83.818984)
		(end 181.2544 -84.784438)
		(width 0.12954)
		(layer "In2.Cu")
		(net "GPU_HSC2_BUF_EN_N")
	)
	(segment
		(start 181.2544 -90.9574)
		(end 187.452 -97.155)
		(width 0.12954)
		(layer "In2.Cu")
		(net "GPU_HSC2_BUF_EN_N")
	)
	(segment
		(start 181.2544 -84.784438)
		(end 181.2544 -90.9574)
		(width 0.12954)
		(layer "In2.Cu")
		(net "GPU_HSC2_BUF_EN_N")
	)
	(segment
		(start 187.452 -97.155)
		(end 205.74 -97.155)
		(width 0.12954)
		(layer "In2.Cu")
		(net "GPU_HSC2_BUF_EN_N")
	)
	(segment
		(start 205.74 -97.155)
		(end 208.3562 -94.5388)
		(width 0.12954)
		(layer "In2.Cu")
		(net "GPU_HSC2_BUF_EN_N")
	)
	(segment
		(start 262.48741 -47.98695)
		(end 263.5504 -47.98695)
		(width 0.17272)
		(layer "F.Cu")
		(net "GPU_HSC1_BUF_EN_N")
	)
	(segment
		(start 265.801348 -47.98695)
		(end 265.9634 -48.149002)
		(width 0.17272)
		(layer "F.Cu")
		(net "GPU_HSC1_BUF_EN_N")
	)
	(segment
		(start 263.5504 -47.98695)
		(end 265.801348 -47.98695)
		(width 0.17272)
		(layer "F.Cu")
		(net "GPU_HSC1_BUF_EN_N")
	)
	(segment
		(start 262.772398 -51.164998)
		(end 262.772398 -50.84064)
		(width 0.17272)
		(layer "F.Cu")
		(net "GPU_HSC1_BUF_EN_N")
	)
	(segment
		(start 262.08736 -49.546002)
		(end 262.08736 -48.387)
		(width 0.17272)
		(layer "F.Cu")
		(net "GPU_HSC1_BUF_EN_N")
	)
	(segment
		(start 262.772398 -50.23104)
		(end 262.08736 -49.546002)
		(width 0.17272)
		(layer "F.Cu")
		(net "GPU_HSC1_BUF_EN_N")
	)
	(segment
		(start 263.381998 -50.23104)
		(end 262.772398 -50.23104)
		(width 0.17272)
		(layer "F.Cu")
		(net "GPU_HSC1_BUF_EN_N")
	)
	(segment
		(start 262.08736 -48.387)
		(end 262.48741 -47.98695)
		(width 0.17272)
		(layer "F.Cu")
		(net "GPU_HSC1_BUF_EN_N")
	)
	(segment
		(start 262.772398 -50.84064)
		(end 263.381998 -50.23104)
		(width 0.17272)
		(layer "F.Cu")
		(net "GPU_HSC1_BUF_EN_N")
	)
	(via
		(at 259.439156 -90.418666)
		(size 0.508)
		(drill 0.254)
		(layers "F.Cu" "B.Cu")
		(net "GPU_HSC1_BUF_EN_N")
	)
	(via
		(at 262.772398 -51.164998)
		(size 0.508)
		(drill 0.254)
		(layers "F.Cu" "B.Cu")
		(net "GPU_HSC1_BUF_EN_N")
	)
	(segment
		(start 262.772398 -55.347616)
		(end 258.88696 -59.233054)
		(width 0.17272)
		(layer "B.Cu")
		(net "GPU_HSC1_BUF_EN_N")
	)
	(segment
		(start 258.88696 -89.86647)
		(end 259.439156 -90.418666)
		(width 0.17272)
		(layer "B.Cu")
		(net "GPU_HSC1_BUF_EN_N")
	)
	(segment
		(start 258.88696 -59.233054)
		(end 258.88696 -89.86647)
		(width 0.17272)
		(layer "B.Cu")
		(net "GPU_HSC1_BUF_EN_N")
	)
	(segment
		(start 262.772398 -51.164998)
		(end 262.772398 -55.347616)
		(width 0.17272)
		(layer "B.Cu")
		(net "GPU_HSC1_BUF_EN_N")
	)
	(segment
		(start 252.223016 -97.653348)
		(end 259.439156 -90.437208)
		(width 0.12954)
		(layer "In2.Cu")
		(net "GPU_HSC1_BUF_EN_N")
	)
	(segment
		(start 230.3526 -94.5388)
		(end 233.467148 -97.653348)
		(width 0.12954)
		(layer "In2.Cu")
		(net "GPU_HSC1_BUF_EN_N")
	)
	(segment
		(start 233.467148 -97.653348)
		(end 252.223016 -97.653348)
		(width 0.12954)
		(layer "In2.Cu")
		(net "GPU_HSC1_BUF_EN_N")
	)
	(segment
		(start 259.439156 -90.437208)
		(end 259.439156 -90.418666)
		(width 0.12954)
		(layer "In2.Cu")
		(net "GPU_HSC1_BUF_EN_N")
	)
	(segment
		(start 445.77 -44.196)
		(end 445.70904 -44.13504)
		(width 0.17272)
		(layer "F.Cu")
		(net "GPU_HSC_BUF_R_EN")
	)
	(segment
		(start 447.02095 -44.196)
		(end 445.77 -44.196)
		(width 0.17272)
		(layer "F.Cu")
		(net "GPU_HSC_BUF_R_EN")
	)
	(segment
		(start 445.70904 -44.13504)
		(end 443.820042 -44.13504)
		(width 0.17272)
		(layer "F.Cu")
		(net "GPU_HSC_BUF_R_EN")
	)
	(via
		(at 445.77 -44.196)
		(size 0.762)
		(drill 0.381)
		(layers "F.Cu" "B.Cu")
		(net "GPU_HSC_BUF_R_EN")
	)
	(segment
		(start 441.369958 -45.085)
		(end 439.898282 -45.085)
		(width 0.17272)
		(layer "F.Cu")
		(net "GPU_HSC_EN")
	)
	(segment
		(start 438.446164 -45.616114)
		(end 438.42305 -45.593)
		(width 0.17272)
		(layer "F.Cu")
		(net "GPU_HSC_EN")
	)
	(segment
		(start 439.898282 -45.085)
		(end 439.367168 -45.616114)
		(width 0.17272)
		(layer "F.Cu")
		(net "GPU_HSC_EN")
	)
	(segment
		(start 438.42305 -44.45)
		(end 438.42305 -45.593)
		(width 0.17272)
		(layer "F.Cu")
		(net "GPU_HSC_EN")
	)
	(segment
		(start 439.367168 -45.616114)
		(end 438.446164 -45.616114)
		(width 0.17272)
		(layer "F.Cu")
		(net "GPU_HSC_EN")
	)
	(segment
		(start 438.42305 -44.45)
		(end 439.03265 -44.45)
		(width 0.17272)
		(layer "F.Cu")
		(net "GPU_HSC_EN")
	)
	(via
		(at 459.6384 -49.53)
		(size 0.762)
		(drill 0.254)
		(layers "F.Cu" "B.Cu")
		(net "GPU_HSC_EN")
	)
	(via
		(at 439.03265 -44.45)
		(size 0.508)
		(drill 0.254)
		(layers "F.Cu" "B.Cu")
		(net "GPU_HSC_EN")
	)
	(segment
		(start 459.6384 -49.53)
		(end 461.34528 -51.23688)
		(width 0.17272)
		(layer "B.Cu")
		(net "GPU_HSC_EN")
	)
	(segment
		(start 461.34528 -76.821284)
		(end 466.874098 -82.350102)
		(width 0.17272)
		(layer "B.Cu")
		(net "GPU_HSC_EN")
	)
	(segment
		(start 466.874098 -82.350102)
		(end 469.635078 -82.350102)
		(width 0.17272)
		(layer "B.Cu")
		(net "GPU_HSC_EN")
	)
	(segment
		(start 461.34528 -51.23688)
		(end 461.34528 -76.821284)
		(width 0.17272)
		(layer "B.Cu")
		(net "GPU_HSC_EN")
	)
	(segment
		(start 443.610746 -49.53)
		(end 439.03265 -44.951904)
		(width 0.12954)
		(layer "In2.Cu")
		(net "GPU_HSC_EN")
	)
	(segment
		(start 439.03265 -44.951904)
		(end 439.03265 -44.45)
		(width 0.12954)
		(layer "In2.Cu")
		(net "GPU_HSC_EN")
	)
	(segment
		(start 459.6384 -49.53)
		(end 443.610746 -49.53)
		(width 0.12954)
		(layer "In2.Cu")
		(net "GPU_HSC_EN")
	)
	(segment
		(start 178.364642 -49.863756)
		(end 179.079398 -49.149)
		(width 0.17272)
		(layer "F.Cu")
		(net "GPU_HSC2_BUF_EN")
	)
	(segment
		(start 178.364642 -50.144426)
		(end 178.364642 -49.863756)
		(width 0.17272)
		(layer "F.Cu")
		(net "GPU_HSC2_BUF_EN")
	)
	(via
		(at 178.364642 -50.144426)
		(size 0.508)
		(drill 0.254)
		(layers "F.Cu" "B.Cu")
		(net "GPU_HSC2_BUF_EN")
	)
	(segment
		(start 178.364642 -50.402236)
		(end 178.19243 -50.574448)
		(width 0.17272)
		(layer "B.Cu")
		(net "GPU_HSC2_BUF_EN")
	)
	(segment
		(start 178.19243 -50.574448)
		(end 178.19243 -52.951888)
		(width 0.17272)
		(layer "B.Cu")
		(net "GPU_HSC2_BUF_EN")
	)
	(segment
		(start 179.088542 -53.848)
		(end 179.68595 -53.848)
		(width 0.17272)
		(layer "B.Cu")
		(net "GPU_HSC2_BUF_EN")
	)
	(segment
		(start 178.19243 -52.951888)
		(end 179.088542 -53.848)
		(width 0.17272)
		(layer "B.Cu")
		(net "GPU_HSC2_BUF_EN")
	)
	(segment
		(start 178.364642 -50.144426)
		(end 178.364642 -50.402236)
		(width 0.17272)
		(layer "B.Cu")
		(net "GPU_HSC2_BUF_EN")
	)
	(segment
		(start 260.773926 -51.789076)
		(end 260.773926 -53.109876)
		(width 0.17272)
		(layer "F.Cu")
		(net "GPU_HSC1_BUF_EN")
	)
	(segment
		(start 260.773926 -53.109876)
		(end 261.02945 -53.3654)
		(width 0.17272)
		(layer "F.Cu")
		(net "GPU_HSC1_BUF_EN")
	)
	(segment
		(start 261.02945 -53.3654)
		(end 261.02945 -54.61)
		(width 0.17272)
		(layer "F.Cu")
		(net "GPU_HSC1_BUF_EN")
	)
	(segment
		(start 261.382002 -51.181)
		(end 260.773926 -51.789076)
		(width 0.17272)
		(layer "F.Cu")
		(net "GPU_HSC1_BUF_EN")
	)
	(via
		(at 261.02945 -54.61)
		(size 0.762)
		(drill 0.254)
		(layers "F.Cu" "B.Cu")
		(net "GPU_HSC1_BUF_EN")
	)
	(segment
		(start 261.02945 -53.975)
		(end 261.02945 -54.61)
		(width 0.17272)
		(layer "B.Cu")
		(net "GPU_HSC1_BUF_EN")
	)
	(segment
		(start 435.355746 -50.546)
		(end 436.244746 -50.546)
		(width 0.17272)
		(layer "F.Cu")
		(net "PWRGD_P52V_HS_PG")
	)
	(segment
		(start 436.244746 -50.546)
		(end 437.261 -51.562254)
		(width 0.17272)
		(layer "F.Cu")
		(net "PWRGD_P52V_HS_PG")
	)
	(segment
		(start 437.261 -51.562254)
		(end 437.261 -52.07)
		(width 0.17272)
		(layer "F.Cu")
		(net "PWRGD_P52V_HS_PG")
	)
	(segment
		(start 434.447696 -49.63795)
		(end 435.355746 -50.546)
		(width 0.17272)
		(layer "F.Cu")
		(net "PWRGD_P52V_HS_PG")
	)
	(segment
		(start 433.705 -49.63795)
		(end 434.447696 -49.63795)
		(width 0.17272)
		(layer "F.Cu")
		(net "PWRGD_P52V_HS_PG")
	)
	(via
		(at 437.261 -52.07)
		(size 0.508)
		(drill 0.254)
		(layers "F.Cu" "B.Cu")
		(net "PWRGD_P52V_HS_PG")
	)
	(via
		(at 461.645 -47.752)
		(size 0.508)
		(drill 0.254)
		(layers "F.Cu" "B.Cu")
		(net "PWRGD_P52V_HS_PG")
	)
	(segment
		(start 473.6084 -79.502)
		(end 473.6084 -82.931)
		(width 0.17272)
		(layer "B.Cu")
		(net "PWRGD_P52V_HS_PG")
	)
	(segment
		(start 463.1944 -76.180696)
		(end 465.245704 -78.232)
		(width 0.17272)
		(layer "B.Cu")
		(net "PWRGD_P52V_HS_PG")
	)
	(segment
		(start 473.6084 -82.931)
		(end 472.919298 -83.620102)
		(width 0.17272)
		(layer "B.Cu")
		(net "PWRGD_P52V_HS_PG")
	)
	(segment
		(start 465.245704 -78.232)
		(end 472.3384 -78.232)
		(width 0.17272)
		(layer "B.Cu")
		(net "PWRGD_P52V_HS_PG")
	)
	(segment
		(start 463.1944 -49.3014)
		(end 463.1944 -76.180696)
		(width 0.17272)
		(layer "B.Cu")
		(net "PWRGD_P52V_HS_PG")
	)
	(segment
		(start 472.3384 -78.232)
		(end 473.6084 -79.502)
		(width 0.17272)
		(layer "B.Cu")
		(net "PWRGD_P52V_HS_PG")
	)
	(segment
		(start 472.919298 -83.620102)
		(end 470.905078 -83.620102)
		(width 0.17272)
		(layer "B.Cu")
		(net "PWRGD_P52V_HS_PG")
	)
	(segment
		(start 461.645 -47.752)
		(end 463.1944 -49.3014)
		(width 0.17272)
		(layer "B.Cu")
		(net "PWRGD_P52V_HS_PG")
	)
	(segment
		(start 437.261 -52.07)
		(end 438.277 -51.054)
		(width 0.12954)
		(layer "In2.Cu")
		(net "PWRGD_P52V_HS_PG")
	)
	(segment
		(start 459.071218 -51.054)
		(end 461.645 -48.480218)
		(width 0.12954)
		(layer "In2.Cu")
		(net "PWRGD_P52V_HS_PG")
	)
	(segment
		(start 461.645 -48.480218)
		(end 461.645 -47.752)
		(width 0.12954)
		(layer "In2.Cu")
		(net "PWRGD_P52V_HS_PG")
	)
	(segment
		(start 438.277 -51.054)
		(end 459.071218 -51.054)
		(width 0.12954)
		(layer "In2.Cu")
		(net "PWRGD_P52V_HS_PG")
	)
	(segment
		(start 426.82795 -38.989)
		(end 426.3644 -38.989)
		(width 0.17272)
		(layer "F.Cu")
		(net "BOARD_ID_1")
	)
	(segment
		(start 426.82795 -38.989)
		(end 427.44771 -38.36924)
		(width 0.17272)
		(layer "F.Cu")
		(net "BOARD_ID_1")
	)
	(segment
		(start 425.0944 -40.259)
		(end 424.560492 -40.792908)
		(width 0.17272)
		(layer "F.Cu")
		(net "BOARD_ID_1")
	)
	(segment
		(start 429.25619 -38.36924)
		(end 429.87595 -38.989)
		(width 0.17272)
		(layer "F.Cu")
		(net "BOARD_ID_1")
	)
	(segment
		(start 426.3644 -38.989)
		(end 425.0944 -40.259)
		(width 0.17272)
		(layer "F.Cu")
		(net "BOARD_ID_1")
	)
	(segment
		(start 424.560492 -40.792908)
		(end 423.291 -40.792908)
		(width 0.17272)
		(layer "F.Cu")
		(net "BOARD_ID_1")
	)
	(segment
		(start 427.44771 -38.36924)
		(end 429.25619 -38.36924)
		(width 0.17272)
		(layer "F.Cu")
		(net "BOARD_ID_1")
	)
	(via
		(at 425.0944 -40.259)
		(size 0.762)
		(drill 0.381)
		(layers "F.Cu" "B.Cu")
		(net "BOARD_ID_1")
	)
	(segment
		(start 425.05376 -41.442894)
		(end 423.291 -41.442894)
		(width 0.17272)
		(layer "F.Cu")
		(net "BOARD_ID_2")
	)
	(segment
		(start 425.7929 -40.703754)
		(end 425.05376 -41.442894)
		(width 0.17272)
		(layer "F.Cu")
		(net "BOARD_ID_2")
	)
	(segment
		(start 426.82795 -40.386)
		(end 426.110654 -40.386)
		(width 0.17272)
		(layer "F.Cu")
		(net "BOARD_ID_2")
	)
	(segment
		(start 429.25619 -39.76624)
		(end 429.87595 -40.386)
		(width 0.17272)
		(layer "F.Cu")
		(net "BOARD_ID_2")
	)
	(segment
		(start 426.110654 -40.386)
		(end 425.7929 -40.703754)
		(width 0.17272)
		(layer "F.Cu")
		(net "BOARD_ID_2")
	)
	(segment
		(start 426.82795 -40.386)
		(end 427.44771 -39.76624)
		(width 0.17272)
		(layer "F.Cu")
		(net "BOARD_ID_2")
	)
	(segment
		(start 427.44771 -39.76624)
		(end 429.25619 -39.76624)
		(width 0.17272)
		(layer "F.Cu")
		(net "BOARD_ID_2")
	)
	(via
		(at 425.7929 -40.703754)
		(size 0.508)
		(drill 0.254)
		(layers "F.Cu" "B.Cu")
		(net "BOARD_ID_2")
	)
	(segment
		(start 425.70654 -38.71976)
		(end 426.069506 -38.356794)
		(width 0.17272)
		(layer "F.Cu")
		(net "BOARD_ID_0")
	)
	(segment
		(start 423.291 -40.142922)
		(end 424.277028 -40.142922)
		(width 0.17272)
		(layer "F.Cu")
		(net "BOARD_ID_0")
	)
	(segment
		(start 426.069506 -38.350444)
		(end 426.82795 -37.592)
		(width 0.17272)
		(layer "F.Cu")
		(net "BOARD_ID_0")
	)
	(segment
		(start 429.87595 -37.592)
		(end 429.25619 -36.97224)
		(width 0.17272)
		(layer "F.Cu")
		(net "BOARD_ID_0")
	)
	(segment
		(start 428.7774 -36.97224)
		(end 427.44771 -36.97224)
		(width 0.17272)
		(layer "F.Cu")
		(net "BOARD_ID_0")
	)
	(segment
		(start 429.25619 -36.97224)
		(end 428.7774 -36.97224)
		(width 0.17272)
		(layer "F.Cu")
		(net "BOARD_ID_0")
	)
	(segment
		(start 426.069506 -38.356794)
		(end 426.069506 -38.350444)
		(width 0.17272)
		(layer "F.Cu")
		(net "BOARD_ID_0")
	)
	(segment
		(start 424.277028 -40.142922)
		(end 425.70019 -38.71976)
		(width 0.17272)
		(layer "F.Cu")
		(net "BOARD_ID_0")
	)
	(segment
		(start 425.70019 -38.71976)
		(end 425.70654 -38.71976)
		(width 0.17272)
		(layer "F.Cu")
		(net "BOARD_ID_0")
	)
	(segment
		(start 427.44771 -36.97224)
		(end 426.82795 -37.592)
		(width 0.17272)
		(layer "F.Cu")
		(net "BOARD_ID_0")
	)
	(via
		(at 428.7774 -36.97224)
		(size 0.508)
		(drill 0.254)
		(layers "F.Cu" "B.Cu")
		(net "BOARD_ID_0")
	)
	(segment
		(start 209.7786 -91.9988)
		(end 205.5876 -91.9988)
		(width 0.17272)
		(layer "F.Cu")
		(net "TP_P52V_HS2_EN")
	)
	(via
		(at 205.5876 -91.9988)
		(size 0.762)
		(drill 0.381)
		(layers "F.Cu" "B.Cu")
		(net "TP_P52V_HS2_EN")
	)
	(segment
		(start 230.3526 -91.9988)
		(end 234.4674 -91.9988)
		(width 0.17272)
		(layer "F.Cu")
		(net "TP_P52V_HS1_EN")
	)
	(via
		(at 234.4674 -91.9988)
		(size 0.762)
		(drill 0.381)
		(layers "F.Cu" "B.Cu")
		(net "TP_P52V_HS1_EN")
	)
	(segment
		(start 387.36905 -29.083)
		(end 387.2484 -28.96235)
		(width 0.17272)
		(layer "F.Cu")
		(net "P52V_HS1_EN_DISCHARGE_VBE_R")
	)
	(segment
		(start 387.2484 -28.96235)
		(end 387.2484 -28.321)
		(width 0.17272)
		(layer "F.Cu")
		(net "P52V_HS1_EN_DISCHARGE_VBE_R")
	)
	(via
		(at 398.145 -17.018)
		(size 0.508)
		(drill 0.254)
		(layers "F.Cu" "B.Cu")
		(net "P52V_HS1_EN_DISCHARGE_VBE_R")
	)
	(via
		(at 387.2484 -28.321)
		(size 0.508)
		(drill 0.254)
		(layers "F.Cu" "B.Cu")
		(net "P52V_HS1_EN_DISCHARGE_VBE_R")
	)
	(segment
		(start 398.145 -18.90395)
		(end 388.72795 -28.321)
		(width 0.12954)
		(layer "In2.Cu")
		(net "P52V_HS1_EN_DISCHARGE_VBE_R")
	)
	(segment
		(start 398.145 -17.018)
		(end 398.145 -18.90395)
		(width 0.12954)
		(layer "In2.Cu")
		(net "P52V_HS1_EN_DISCHARGE_VBE_R")
	)
	(segment
		(start 388.72795 -28.321)
		(end 387.2484 -28.321)
		(width 0.12954)
		(layer "In2.Cu")
		(net "P52V_HS1_EN_DISCHARGE_VBE_R")
	)
	(segment
		(start 388.1374 -30.353)
		(end 387.2484 -30.353)
		(width 0.17272)
		(layer "F.Cu")
		(net "P52V_HS1_EN_DISCHARGE_VBE")
	)
	(segment
		(start 386.56895 -29.67355)
		(end 386.56895 -29.083)
		(width 0.17272)
		(layer "F.Cu")
		(net "P52V_HS1_EN_DISCHARGE_VBE")
	)
	(segment
		(start 388.8994 -29.591)
		(end 388.1374 -30.353)
		(width 0.17272)
		(layer "F.Cu")
		(net "P52V_HS1_EN_DISCHARGE_VBE")
	)
	(segment
		(start 387.2484 -30.353)
		(end 386.56895 -29.67355)
		(width 0.17272)
		(layer "F.Cu")
		(net "P52V_HS1_EN_DISCHARGE_VBE")
	)
	(via
		(at 387.2484 -30.353)
		(size 0.762)
		(drill 0.381)
		(layers "F.Cu" "B.Cu")
		(net "P52V_HS1_EN_DISCHARGE_VBE")
	)
	(segment
		(start 391.4521 -25.273)
		(end 391.4521 -28.2575)
		(width 0.17272)
		(layer "F.Cu")
		(net "P52V_HS1_EN_DISCHARGE_N")
	)
	(segment
		(start 394.6144 -24.511)
		(end 395.097 -24.9936)
		(width 0.17272)
		(layer "F.Cu")
		(net "P52V_HS1_EN_DISCHARGE_N")
	)
	(segment
		(start 391.4521 -25.273)
		(end 392.2141 -24.511)
		(width 0.17272)
		(layer "F.Cu")
		(net "P52V_HS1_EN_DISCHARGE_N")
	)
	(segment
		(start 392.2141 -24.511)
		(end 393.954 -24.511)
		(width 0.17272)
		(layer "F.Cu")
		(net "P52V_HS1_EN_DISCHARGE_N")
	)
	(segment
		(start 395.097 -24.9936)
		(end 395.097 -26.479754)
		(width 0.17272)
		(layer "F.Cu")
		(net "P52V_HS1_EN_DISCHARGE_N")
	)
	(segment
		(start 391.1346 -31.343854)
		(end 391.0584 -31.420054)
		(width 0.17272)
		(layer "F.Cu")
		(net "P52V_HS1_EN_DISCHARGE_N")
	)
	(segment
		(start 391.1346 -28.575)
		(end 391.1346 -31.343854)
		(width 0.17272)
		(layer "F.Cu")
		(net "P52V_HS1_EN_DISCHARGE_N")
	)
	(segment
		(start 393.954 -24.511)
		(end 394.6144 -24.511)
		(width 0.17272)
		(layer "F.Cu")
		(net "P52V_HS1_EN_DISCHARGE_N")
	)
	(segment
		(start 391.4521 -28.2575)
		(end 391.1346 -28.575)
		(width 0.17272)
		(layer "F.Cu")
		(net "P52V_HS1_EN_DISCHARGE_N")
	)
	(via
		(at 393.954 -24.511)
		(size 0.508)
		(drill 0.254)
		(layers "F.Cu" "B.Cu")
		(net "P52V_HS1_EN_DISCHARGE_N")
	)
	(segment
		(start 389.8519 -25.922986)
		(end 389.847836 -25.92705)
		(width 0.17272)
		(layer "F.Cu")
		(net "P52V_HS1_EN_DISCHARGE")
	)
	(segment
		(start 388.4676 -25.92705)
		(end 387.223 -25.92705)
		(width 0.17272)
		(layer "F.Cu")
		(net "P52V_HS1_EN_DISCHARGE")
	)
	(segment
		(start 389.847836 -25.92705)
		(end 388.4676 -25.92705)
		(width 0.17272)
		(layer "F.Cu")
		(net "P52V_HS1_EN_DISCHARGE")
	)
	(via
		(at 388.4676 -25.92705)
		(size 0.762)
		(drill 0.381)
		(layers "F.Cu" "B.Cu")
		(net "P52V_HS1_EN_DISCHARGE")
	)
	(segment
		(start 445.2366 -30.353)
		(end 447.167 -30.353)
		(width 0.17272)
		(layer "F.Cu")
		(net "TP_9543_FAN_INT_N")
	)
	(via
		(at 447.167 -30.353)
		(size 0.762)
		(drill 0.381)
		(layers "F.Cu" "B.Cu")
		(net "TP_9543_FAN_INT_N")
	)
	(segment
		(start 447.3194 -26.543)
		(end 448.92595 -26.543)
		(width 0.17272)
		(layer "F.Cu")
		(net "PU_9543_1_FAN")
	)
	(segment
		(start 445.2366 -26.543)
		(end 447.3194 -26.543)
		(width 0.17272)
		(layer "F.Cu")
		(net "PU_9543_1_FAN")
	)
	(via
		(at 447.3194 -26.543)
		(size 0.762)
		(drill 0.381)
		(layers "F.Cu" "B.Cu")
		(net "PU_9543_1_FAN")
	)
	(segment
		(start 439.9534 -30.353)
		(end 438.0484 -30.353)
		(width 0.17272)
		(layer "F.Cu")
		(net "PU_9543_0_FAN")
	)
	(segment
		(start 438.0484 -30.353)
		(end 436.64505 -30.353)
		(width 0.17272)
		(layer "F.Cu")
		(net "PU_9543_0_FAN")
	)
	(via
		(at 438.0484 -30.353)
		(size 0.762)
		(drill 0.381)
		(layers "F.Cu" "B.Cu")
		(net "PU_9543_0_FAN")
	)
	(segment
		(start 428.7774 -41.16324)
		(end 427.44771 -41.16324)
		(width 0.17272)
		(layer "F.Cu")
		(net "SKU_ID_0")
	)
	(segment
		(start 429.25619 -41.16324)
		(end 428.7774 -41.16324)
		(width 0.17272)
		(layer "F.Cu")
		(net "SKU_ID_0")
	)
	(segment
		(start 429.87595 -41.783)
		(end 429.25619 -41.16324)
		(width 0.17272)
		(layer "F.Cu")
		(net "SKU_ID_0")
	)
	(segment
		(start 427.44771 -41.16324)
		(end 426.82795 -41.783)
		(width 0.17272)
		(layer "F.Cu")
		(net "SKU_ID_0")
	)
	(segment
		(start 423.291 -42.09288)
		(end 426.51807 -42.09288)
		(width 0.17272)
		(layer "F.Cu")
		(net "SKU_ID_0")
	)
	(segment
		(start 426.51807 -42.09288)
		(end 426.82795 -41.783)
		(width 0.17272)
		(layer "F.Cu")
		(net "SKU_ID_0")
	)
	(via
		(at 428.7774 -41.16324)
		(size 0.508)
		(drill 0.254)
		(layers "F.Cu" "B.Cu")
		(net "SKU_ID_0")
	)
	(segment
		(start 426.82795 -44.577)
		(end 426.19295 -43.942)
		(width 0.17272)
		(layer "F.Cu")
		(net "SKU_ID_2")
	)
	(segment
		(start 428.7774 -43.95724)
		(end 427.44771 -43.95724)
		(width 0.17272)
		(layer "F.Cu")
		(net "SKU_ID_2")
	)
	(segment
		(start 429.25619 -43.95724)
		(end 428.7774 -43.95724)
		(width 0.17272)
		(layer "F.Cu")
		(net "SKU_ID_2")
	)
	(segment
		(start 429.87595 -44.577)
		(end 429.25619 -43.95724)
		(width 0.17272)
		(layer "F.Cu")
		(net "SKU_ID_2")
	)
	(segment
		(start 427.44771 -43.95724)
		(end 426.82795 -44.577)
		(width 0.17272)
		(layer "F.Cu")
		(net "SKU_ID_2")
	)
	(segment
		(start 424.418506 -43.393106)
		(end 423.291 -43.393106)
		(width 0.17272)
		(layer "F.Cu")
		(net "SKU_ID_2")
	)
	(segment
		(start 426.19295 -43.942)
		(end 424.9674 -43.942)
		(width 0.17272)
		(layer "F.Cu")
		(net "SKU_ID_2")
	)
	(segment
		(start 424.9674 -43.942)
		(end 424.418506 -43.393106)
		(width 0.17272)
		(layer "F.Cu")
		(net "SKU_ID_2")
	)
	(via
		(at 428.7774 -43.95724)
		(size 0.508)
		(drill 0.254)
		(layers "F.Cu" "B.Cu")
		(net "SKU_ID_2")
	)
	(segment
		(start 426.82795 -43.18)
		(end 426.39107 -42.74312)
		(width 0.17272)
		(layer "F.Cu")
		(net "SKU_ID_1")
	)
	(segment
		(start 426.39107 -42.74312)
		(end 425.2214 -42.74312)
		(width 0.17272)
		(layer "F.Cu")
		(net "SKU_ID_1")
	)
	(segment
		(start 427.44771 -42.56024)
		(end 429.25619 -42.56024)
		(width 0.17272)
		(layer "F.Cu")
		(net "SKU_ID_1")
	)
	(segment
		(start 425.2214 -42.74312)
		(end 423.291 -42.74312)
		(width 0.17272)
		(layer "F.Cu")
		(net "SKU_ID_1")
	)
	(segment
		(start 429.25619 -42.56024)
		(end 429.87595 -43.18)
		(width 0.17272)
		(layer "F.Cu")
		(net "SKU_ID_1")
	)
	(segment
		(start 426.82795 -43.18)
		(end 427.44771 -42.56024)
		(width 0.17272)
		(layer "F.Cu")
		(net "SKU_ID_1")
	)
	(via
		(at 425.2214 -42.74312)
		(size 0.762)
		(drill 0.381)
		(layers "F.Cu" "B.Cu")
		(net "SKU_ID_1")
	)
	(via
		(at 197.104 -52.4764)
		(size 0.508)
		(drill 0.254)
		(layers "F.Cu" "B.Cu")
		(net "NC_J7_D1")
	)
	(segment
		(start 197.6628 -52.4764)
		(end 199.089264 -51.049936)
		(width 0.12954)
		(layer "In2.Cu")
		(net "NC_J7_D1")
	)
	(segment
		(start 199.089264 -51.049936)
		(end 201.190098 -51.049936)
		(width 0.12954)
		(layer "In2.Cu")
		(net "NC_J7_D1")
	)
	(segment
		(start 197.104 -52.4764)
		(end 197.6628 -52.4764)
		(width 0.12954)
		(layer "In2.Cu")
		(net "NC_J7_D1")
	)
	(via
		(at 195.7578 -52.5526)
		(size 0.508)
		(drill 0.254)
		(layers "F.Cu" "B.Cu")
		(net "NC_J7_C1")
	)
	(segment
		(start 196.1642 -52.1462)
		(end 196.1642 -50.7492)
		(width 0.12954)
		(layer "In2.Cu")
		(net "NC_J7_C1")
	)
	(segment
		(start 203.424536 -51.049936)
		(end 203.730098 -51.049936)
		(width 0.12954)
		(layer "In2.Cu")
		(net "NC_J7_C1")
	)
	(segment
		(start 202.2094 -49.8348)
		(end 203.424536 -51.049936)
		(width 0.12954)
		(layer "In2.Cu")
		(net "NC_J7_C1")
	)
	(segment
		(start 196.1642 -50.7492)
		(end 197.0786 -49.8348)
		(width 0.12954)
		(layer "In2.Cu")
		(net "NC_J7_C1")
	)
	(segment
		(start 197.0786 -49.8348)
		(end 202.2094 -49.8348)
		(width 0.12954)
		(layer "In2.Cu")
		(net "NC_J7_C1")
	)
	(segment
		(start 195.7578 -52.5526)
		(end 196.1642 -52.1462)
		(width 0.12954)
		(layer "In2.Cu")
		(net "NC_J7_C1")
	)
	(via
		(at 242.4684 -52.6288)
		(size 0.508)
		(drill 0.254)
		(layers "F.Cu" "B.Cu")
		(net "NC_J6_D1")
	)
	(segment
		(start 241.7318 -53.3654)
		(end 231.9782 -53.3654)
		(width 0.12954)
		(layer "In2.Cu")
		(net "NC_J6_D1")
	)
	(segment
		(start 231.9782 -53.3654)
		(end 231.190038 -52.577238)
		(width 0.12954)
		(layer "In2.Cu")
		(net "NC_J6_D1")
	)
	(segment
		(start 242.4684 -52.6288)
		(end 241.7318 -53.3654)
		(width 0.12954)
		(layer "In2.Cu")
		(net "NC_J6_D1")
	)
	(segment
		(start 231.190038 -52.577238)
		(end 231.190038 -51.049936)
		(width 0.12954)
		(layer "In2.Cu")
		(net "NC_J6_D1")
	)
	(via
		(at 242.3668 -50.8508)
		(size 0.508)
		(drill 0.254)
		(layers "F.Cu" "B.Cu")
		(net "NC_J6_C1")
	)
	(segment
		(start 242.3668 -50.8508)
		(end 240.6396 -52.578)
		(width 0.12954)
		(layer "In2.Cu")
		(net "NC_J6_C1")
	)
	(segment
		(start 234.4166 -52.578)
		(end 233.730038 -51.891438)
		(width 0.12954)
		(layer "In2.Cu")
		(net "NC_J6_C1")
	)
	(segment
		(start 240.6396 -52.578)
		(end 234.4166 -52.578)
		(width 0.12954)
		(layer "In2.Cu")
		(net "NC_J6_C1")
	)
	(segment
		(start 233.730038 -51.891438)
		(end 233.730038 -51.049936)
		(width 0.12954)
		(layer "In2.Cu")
		(net "NC_J6_C1")
	)
	(segment
		(start 445.856106 -36.489894)
		(end 446.786 -35.56)
		(width 0.17272)
		(layer "F.Cu")
		(net "NC_U2_READY")
	)
	(segment
		(start 444.827406 -36.489894)
		(end 445.856106 -36.489894)
		(width 0.17272)
		(layer "F.Cu")
		(net "NC_U2_READY")
	)
	(via
		(at 446.786 -35.56)
		(size 0.762)
		(drill 0.381)
		(layers "F.Cu" "B.Cu")
		(net "NC_U2_READY")
	)
	(segment
		(start 444.827406 -40.426894)
		(end 445.983106 -40.426894)
		(width 0.17272)
		(layer "F.Cu")
		(net "NC_U1_READY")
	)
	(segment
		(start 445.983106 -40.426894)
		(end 446.786 -39.624)
		(width 0.17272)
		(layer "F.Cu")
		(net "NC_U1_READY")
	)
	(via
		(at 446.786 -39.624)
		(size 0.762)
		(drill 0.381)
		(layers "F.Cu" "B.Cu")
		(net "NC_U1_READY")
	)
	(segment
		(start 53.57495 -29.3751)
		(end 53.57495 -29.35605)
		(width 0.17272)
		(layer "F.Cu")
		(net "P52V_HS2_EN_DISCHARGE_VBE_R")
	)
	(segment
		(start 52.832 -30.11805)
		(end 53.57495 -29.3751)
		(width 0.17272)
		(layer "F.Cu")
		(net "P52V_HS2_EN_DISCHARGE_VBE_R")
	)
	(via
		(at 53.57495 -29.35605)
		(size 0.508)
		(drill 0.254)
		(layers "F.Cu" "B.Cu")
		(net "P52V_HS2_EN_DISCHARGE_VBE_R")
	)
	(via
		(at 44.90339 -25.908)
		(size 0.508)
		(drill 0.254)
		(layers "F.Cu" "B.Cu")
		(net "P52V_HS2_EN_DISCHARGE_VBE_R")
	)
	(segment
		(start 45.2374 -25.908)
		(end 44.90339 -25.908)
		(width 0.12954)
		(layer "In2.Cu")
		(net "P52V_HS2_EN_DISCHARGE_VBE_R")
	)
	(segment
		(start 53.57495 -29.35605)
		(end 48.68545 -29.35605)
		(width 0.12954)
		(layer "In2.Cu")
		(net "P52V_HS2_EN_DISCHARGE_VBE_R")
	)
	(segment
		(start 48.68545 -29.35605)
		(end 45.2374 -25.908)
		(width 0.12954)
		(layer "In2.Cu")
		(net "P52V_HS2_EN_DISCHARGE_VBE_R")
	)
	(segment
		(start 52.832 -26.14295)
		(end 51.542696 -26.14295)
		(width 0.17272)
		(layer "F.Cu")
		(net "P52V_HS2_EN_DISCHARGE")
	)
	(segment
		(start 50.359564 -26.14295)
		(end 50.1015 -26.401014)
		(width 0.17272)
		(layer "F.Cu")
		(net "P52V_HS2_EN_DISCHARGE")
	)
	(segment
		(start 51.542696 -26.14295)
		(end 50.359564 -26.14295)
		(width 0.17272)
		(layer "F.Cu")
		(net "P52V_HS2_EN_DISCHARGE")
	)
	(via
		(at 51.542696 -26.14295)
		(size 0.762)
		(drill 0.381)
		(layers "F.Cu" "B.Cu")
		(net "P52V_HS2_EN_DISCHARGE")
	)
	(segment
		(start 48.73879 -30.226)
		(end 48.73879 -27.28849)
		(width 0.17272)
		(layer "F.Cu")
		(net "P52V_HS2_EN_DISCHARGE_N")
	)
	(segment
		(start 39.82339 -28.003754)
		(end 39.82339 -25.72639)
		(width 0.254)
		(layer "F.Cu")
		(net "P52V_HS2_EN_DISCHARGE_N")
	)
	(segment
		(start 48.73879 -30.226)
		(end 48.73879 -32.889444)
		(width 0.17272)
		(layer "F.Cu")
		(net "P52V_HS2_EN_DISCHARGE_N")
	)
	(segment
		(start 48.73879 -32.889444)
		(end 48.9204 -33.071054)
		(width 0.17272)
		(layer "F.Cu")
		(net "P52V_HS2_EN_DISCHARGE_N")
	)
	(segment
		(start 48.73879 -27.28849)
		(end 48.5013 -27.051)
		(width 0.17272)
		(layer "F.Cu")
		(net "P52V_HS2_EN_DISCHARGE_N")
	)
	(segment
		(start 48.5013 -27.051)
		(end 47.6504 -27.051)
		(width 0.17272)
		(layer "F.Cu")
		(net "P52V_HS2_EN_DISCHARGE_N")
	)
	(via
		(at 47.6504 -27.051)
		(size 0.508)
		(drill 0.254)
		(layers "F.Cu" "B.Cu")
		(net "P52V_HS2_EN_DISCHARGE_N")
	)
	(via
		(at 39.82339 -25.72639)
		(size 0.508)
		(drill 0.254)
		(layers "F.Cu" "B.Cu")
		(net "P52V_HS2_EN_DISCHARGE_N")
	)
	(segment
		(start 47.6504 -27.051)
		(end 45.8724 -25.273)
		(width 0.12954)
		(layer "In2.Cu")
		(net "P52V_HS2_EN_DISCHARGE_N")
	)
	(segment
		(start 40.290496 -25.273)
		(end 40.277542 -25.274524)
		(width 0.12954)
		(layer "In2.Cu")
		(net "P52V_HS2_EN_DISCHARGE_N")
	)
	(segment
		(start 40.26662 -25.28316)
		(end 39.82339 -25.72639)
		(width 0.12954)
		(layer "In2.Cu")
		(net "P52V_HS2_EN_DISCHARGE_N")
	)
	(segment
		(start 40.277542 -25.274524)
		(end 40.26662 -25.28316)
		(width 0.12954)
		(layer "In2.Cu")
		(net "P52V_HS2_EN_DISCHARGE_N")
	)
	(segment
		(start 45.8724 -25.273)
		(end 40.290496 -25.273)
		(width 0.12954)
		(layer "In2.Cu")
		(net "P52V_HS2_EN_DISCHARGE_N")
	)
	(segment
		(start 50.97399 -29.21)
		(end 52.06619 -28.1178)
		(width 0.17272)
		(layer "F.Cu")
		(net "P52V_HS2_EN_DISCHARGE_VBE")
	)
	(segment
		(start 52.06619 -28.1178)
		(end 52.5526 -28.1178)
		(width 0.17272)
		(layer "F.Cu")
		(net "P52V_HS2_EN_DISCHARGE_VBE")
	)
	(segment
		(start 52.832 -28.3972)
		(end 52.832 -29.31795)
		(width 0.17272)
		(layer "F.Cu")
		(net "P52V_HS2_EN_DISCHARGE_VBE")
	)
	(segment
		(start 52.5526 -28.1178)
		(end 52.832 -28.3972)
		(width 0.17272)
		(layer "F.Cu")
		(net "P52V_HS2_EN_DISCHARGE_VBE")
	)
	(via
		(at 52.5526 -28.1178)
		(size 0.762)
		(drill 0.381)
		(layers "F.Cu" "B.Cu")
		(net "P52V_HS2_EN_DISCHARGE_VBE")
	)
	(segment
		(start 420.13632 -45.069506)
		(end 420.46652 -44.739306)
		(width 0.17272)
		(layer "F.Cu")
		(net "TP_U8_P06")
	)
	(segment
		(start 420.13632 -47.77232)
		(end 420.13632 -45.069506)
		(width 0.17272)
		(layer "F.Cu")
		(net "TP_U8_P06")
	)
	(segment
		(start 418.643308 -40.142922)
		(end 417.449 -40.142922)
		(width 0.17272)
		(layer "F.Cu")
		(net "TP_U8_P06")
	)
	(segment
		(start 421.005 -48.641)
		(end 420.13632 -47.77232)
		(width 0.17272)
		(layer "F.Cu")
		(net "TP_U8_P06")
	)
	(segment
		(start 420.46652 -41.966134)
		(end 418.643308 -40.142922)
		(width 0.17272)
		(layer "F.Cu")
		(net "TP_U8_P06")
	)
	(segment
		(start 420.46652 -44.739306)
		(end 420.46652 -41.966134)
		(width 0.17272)
		(layer "F.Cu")
		(net "TP_U8_P06")
	)
	(via
		(at 421.005 -48.641)
		(size 0.762)
		(drill 0.254)
		(layers "F.Cu" "B.Cu")
		(net "TP_U8_P06")
	)
	(segment
		(start 419.510718 -44.344336)
		(end 419.510718 -42.574718)
		(width 0.17272)
		(layer "F.Cu")
		(net "TP_U8_P04")
	)
	(segment
		(start 419.129718 -45.72)
		(end 419.129718 -44.725336)
		(width 0.17272)
		(layer "F.Cu")
		(net "TP_U8_P04")
	)
	(segment
		(start 419.510718 -42.574718)
		(end 418.378894 -41.442894)
		(width 0.17272)
		(layer "F.Cu")
		(net "TP_U8_P04")
	)
	(segment
		(start 419.129718 -44.725336)
		(end 419.510718 -44.344336)
		(width 0.17272)
		(layer "F.Cu")
		(net "TP_U8_P04")
	)
	(segment
		(start 418.378894 -41.442894)
		(end 417.449 -41.442894)
		(width 0.17272)
		(layer "F.Cu")
		(net "TP_U8_P04")
	)
	(via
		(at 419.129718 -45.72)
		(size 0.508)
		(drill 0.254)
		(layers "F.Cu" "B.Cu")
		(net "TP_U8_P04")
	)
	(segment
		(start 274.4724 -74.676)
		(end 274.4724 -82.296)
		(width 0.17272)
		(layer "F.Cu")
		(net "P52V_HS1_OV")
	)
	(via
		(at 273.6342 -74.676)
		(size 0.6604)
		(drill 0.3302)
		(layers "F.Cu" "B.Cu")
		(net "P52V_HS1_OV")
	)
	(via
		(at 274.4724 -82.296)
		(size 0.508)
		(drill 0.254)
		(layers "F.Cu" "B.Cu")
		(net "P52V_HS1_OV")
	)
	(via
		(at 294.89146 -64.042036)
		(size 0.508)
		(drill 0.254)
		(layers "F.Cu" "B.Cu")
		(net "P52V_HS1_OV")
	)
	(via
		(at 274.4724 -74.676)
		(size 0.508)
		(drill 0.254)
		(layers "F.Cu" "B.Cu")
		(net "P52V_HS1_OV")
	)
	(segment
		(start 274.8534 -75.057)
		(end 274.8534 -76.05395)
		(width 0.17272)
		(layer "B.Cu")
		(net "P52V_HS1_OV")
	)
	(segment
		(start 294.89146 -65.241932)
		(end 294.89146 -64.042036)
		(width 0.17272)
		(layer "B.Cu")
		(net "P52V_HS1_OV")
	)
	(segment
		(start 293.772336 -66.361056)
		(end 294.89146 -65.241932)
		(width 0.17272)
		(layer "B.Cu")
		(net "P52V_HS1_OV")
	)
	(segment
		(start 274.8534 -76.05395)
		(end 275.8694 -76.05395)
		(width 0.17272)
		(layer "B.Cu")
		(net "P52V_HS1_OV")
	)
	(segment
		(start 274.4724 -82.296)
		(end 274.4724 -83.25104)
		(width 0.17272)
		(layer "B.Cu")
		(net "P52V_HS1_OV")
	)
	(segment
		(start 273.6342 -74.676)
		(end 274.4724 -74.676)
		(width 0.17272)
		(layer "B.Cu")
		(net "P52V_HS1_OV")
	)
	(segment
		(start 274.4724 -74.676)
		(end 274.8534 -75.057)
		(width 0.17272)
		(layer "B.Cu")
		(net "P52V_HS1_OV")
	)
	(segment
		(start 272.90522 -73.74382)
		(end 273.6342 -74.4728)
		(width 0.17272)
		(layer "B.Cu")
		(net "P52V_HS1_OV")
	)
	(segment
		(start 272.90522 -73.04532)
		(end 272.90522 -73.74382)
		(width 0.17272)
		(layer "B.Cu")
		(net "P52V_HS1_OV")
	)
	(segment
		(start 273.6342 -74.4728)
		(end 273.6342 -74.676)
		(width 0.17272)
		(layer "B.Cu")
		(net "P52V_HS1_OV")
	)
	(segment
		(start 293.772336 -66.703956)
		(end 293.772336 -66.361056)
		(width 0.17272)
		(layer "B.Cu")
		(net "P52V_HS1_OV")
	)
	(segment
		(start 296.0878 -64.659764)
		(end 295.470072 -64.042036)
		(width 0.12954)
		(layer "In2.Cu")
		(net "P52V_HS1_OV")
	)
	(segment
		(start 283.2608 -83.4644)
		(end 295.275 -83.4644)
		(width 0.12954)
		(layer "In2.Cu")
		(net "P52V_HS1_OV")
	)
	(segment
		(start 274.4724 -74.676)
		(end 283.2608 -83.4644)
		(width 0.12954)
		(layer "In2.Cu")
		(net "P52V_HS1_OV")
	)
	(segment
		(start 295.470072 -64.042036)
		(end 294.89146 -64.042036)
		(width 0.12954)
		(layer "In2.Cu")
		(net "P52V_HS1_OV")
	)
	(segment
		(start 297.0276 -71.094346)
		(end 296.0878 -70.154546)
		(width 0.12954)
		(layer "In2.Cu")
		(net "P52V_HS1_OV")
	)
	(segment
		(start 297.0276 -79.7052)
		(end 297.0276 -71.094346)
		(width 0.12954)
		(layer "In2.Cu")
		(net "P52V_HS1_OV")
	)
	(segment
		(start 296.2148 -82.5246)
		(end 296.2148 -80.518)
		(width 0.12954)
		(layer "In2.Cu")
		(net "P52V_HS1_OV")
	)
	(segment
		(start 295.275 -83.4644)
		(end 296.2148 -82.5246)
		(width 0.12954)
		(layer "In2.Cu")
		(net "P52V_HS1_OV")
	)
	(segment
		(start 296.0878 -70.154546)
		(end 296.0878 -64.659764)
		(width 0.12954)
		(layer "In2.Cu")
		(net "P52V_HS1_OV")
	)
	(segment
		(start 296.2148 -80.518)
		(end 297.0276 -79.7052)
		(width 0.12954)
		(layer "In2.Cu")
		(net "P52V_HS1_OV")
	)
	(segment
		(start 378.517912 -17.507204)
		(end 378.517912 -16.891)
		(width 0.17272)
		(layer "F.Cu")
		(net "SMB_PDB_FAN_0_R_SDA")
	)
	(via
		(at 378.517912 -16.891)
		(size 0.508)
		(drill 0.254)
		(layers "F.Cu" "B.Cu")
		(net "SMB_PDB_FAN_0_R_SDA")
	)
	(segment
		(start 372.60276 -7.09676)
		(end 378.841 -13.335)
		(width 0.17272)
		(layer "B.Cu")
		(net "SMB_PDB_FAN_0_R_SDA")
	)
	(segment
		(start 378.841 -13.335)
		(end 378.841 -16.567912)
		(width 0.17272)
		(layer "B.Cu")
		(net "SMB_PDB_FAN_0_R_SDA")
	)
	(segment
		(start 372.160038 -4.575048)
		(end 372.60276 -5.01777)
		(width 0.17272)
		(layer "B.Cu")
		(net "SMB_PDB_FAN_0_R_SDA")
	)
	(segment
		(start 378.841 -16.567912)
		(end 378.517912 -16.891)
		(width 0.17272)
		(layer "B.Cu")
		(net "SMB_PDB_FAN_0_R_SDA")
	)
	(segment
		(start 372.60276 -5.01777)
		(end 372.60276 -7.09676)
		(width 0.17272)
		(layer "B.Cu")
		(net "SMB_PDB_FAN_0_R_SDA")
	)
	(segment
		(start 379.660912 -17.507204)
		(end 379.660912 -16.891)
		(width 0.17272)
		(layer "F.Cu")
		(net "SMB_PDB_FAN_0_R_SCL")
	)
	(via
		(at 379.476 -15.113)
		(size 0.6604)
		(drill 0.3302)
		(layers "F.Cu" "B.Cu")
		(net "SMB_PDB_FAN_0_R_SCL")
	)
	(via
		(at 379.660912 -16.891)
		(size 0.508)
		(drill 0.254)
		(layers "F.Cu" "B.Cu")
		(net "SMB_PDB_FAN_0_R_SCL")
	)
	(segment
		(start 379.476 -16.706088)
		(end 379.660912 -16.891)
		(width 0.17272)
		(layer "B.Cu")
		(net "SMB_PDB_FAN_0_R_SCL")
	)
	(segment
		(start 379.476 -13.081)
		(end 379.476 -15.113)
		(width 0.17272)
		(layer "B.Cu")
		(net "SMB_PDB_FAN_0_R_SCL")
	)
	(segment
		(start 373.430038 -7.035038)
		(end 379.476 -13.081)
		(width 0.17272)
		(layer "B.Cu")
		(net "SMB_PDB_FAN_0_R_SCL")
	)
	(segment
		(start 373.430038 -5.845048)
		(end 373.430038 -7.035038)
		(width 0.17272)
		(layer "B.Cu")
		(net "SMB_PDB_FAN_0_R_SCL")
	)
	(segment
		(start 379.476 -15.113)
		(end 379.476 -16.706088)
		(width 0.17272)
		(layer "B.Cu")
		(net "SMB_PDB_FAN_0_R_SCL")
	)
	(segment
		(start 415.23285 -45.99305)
		(end 417.449 -45.99305)
		(width 0.17272)
		(layer "F.Cu")
		(net "PU_U8_PIN1")
	)
	(segment
		(start 413.91205 -46.482)
		(end 414.54705 -45.847)
		(width 0.17272)
		(layer "F.Cu")
		(net "PU_U8_PIN1")
	)
	(segment
		(start 414.54705 -45.847)
		(end 415.0868 -45.847)
		(width 0.17272)
		(layer "F.Cu")
		(net "PU_U8_PIN1")
	)
	(segment
		(start 415.0868 -45.847)
		(end 415.23285 -45.99305)
		(width 0.17272)
		(layer "F.Cu")
		(net "PU_U8_PIN1")
	)
	(via
		(at 415.0868 -45.847)
		(size 0.762)
		(drill 0.381)
		(layers "F.Cu" "B.Cu")
		(net "PU_U8_PIN1")
	)
	(segment
		(start 381.946912 -18.307304)
		(end 381.946912 -18.917158)
		(width 0.17272)
		(layer "F.Cu")
		(net "FAN_PWR_EN_BUF")
	)
	(segment
		(start 82.804 -18.30705)
		(end 82.804 -18.916904)
		(width 0.17272)
		(layer "F.Cu")
		(net "FAN_PWR_EN_BUF")
	)
	(via
		(at 82.804 -18.916904)
		(size 0.508)
		(drill 0.254)
		(layers "F.Cu" "B.Cu")
		(net "FAN_PWR_EN_BUF")
	)
	(via
		(at 450.469 -32.893)
		(size 0.508)
		(drill 0.254)
		(layers "F.Cu" "B.Cu")
		(net "FAN_PWR_EN_BUF")
	)
	(via
		(at 381.946912 -18.917158)
		(size 0.508)
		(drill 0.254)
		(layers "F.Cu" "B.Cu")
		(net "FAN_PWR_EN_BUF")
	)
	(segment
		(start 436.245 -36.068254)
		(end 437.825134 -34.48812)
		(width 0.17272)
		(layer "B.Cu")
		(net "FAN_PWR_EN_BUF")
	)
	(segment
		(start 439.674 -44.72305)
		(end 439.674 -44.069)
		(width 0.17272)
		(layer "B.Cu")
		(net "FAN_PWR_EN_BUF")
	)
	(segment
		(start 450.469 -32.893)
		(end 451.612 -32.893)
		(width 0.17272)
		(layer "B.Cu")
		(net "FAN_PWR_EN_BUF")
	)
	(segment
		(start 469.43518 -85.09)
		(end 469.635078 -84.890102)
		(width 0.17272)
		(layer "B.Cu")
		(net "FAN_PWR_EN_BUF")
	)
	(segment
		(start 438.785 -43.18)
		(end 438.15 -43.18)
		(width 0.17272)
		(layer "B.Cu")
		(net "FAN_PWR_EN_BUF")
	)
	(segment
		(start 437.825134 -34.48812)
		(end 446.84188 -34.48812)
		(width 0.17272)
		(layer "B.Cu")
		(net "FAN_PWR_EN_BUF")
	)
	(segment
		(start 466.979 -85.09)
		(end 469.43518 -85.09)
		(width 0.17272)
		(layer "B.Cu")
		(net "FAN_PWR_EN_BUF")
	)
	(segment
		(start 458.05852 -39.33952)
		(end 458.05852 -49.22012)
		(width 0.17272)
		(layer "B.Cu")
		(net "FAN_PWR_EN_BUF")
	)
	(segment
		(start 451.612 -32.893)
		(end 458.05852 -39.33952)
		(width 0.17272)
		(layer "B.Cu")
		(net "FAN_PWR_EN_BUF")
	)
	(segment
		(start 439.674 -44.069)
		(end 438.785 -43.18)
		(width 0.17272)
		(layer "B.Cu")
		(net "FAN_PWR_EN_BUF")
	)
	(segment
		(start 458.05852 -49.22012)
		(end 460.2734 -51.435)
		(width 0.17272)
		(layer "B.Cu")
		(net "FAN_PWR_EN_BUF")
	)
	(segment
		(start 448.437 -32.893)
		(end 450.469 -32.893)
		(width 0.17272)
		(layer "B.Cu")
		(net "FAN_PWR_EN_BUF")
	)
	(segment
		(start 460.2734 -78.3844)
		(end 466.979 -85.09)
		(width 0.17272)
		(layer "B.Cu")
		(net "FAN_PWR_EN_BUF")
	)
	(segment
		(start 435.737 -40.767)
		(end 435.737 -39.751)
		(width 0.17272)
		(layer "B.Cu")
		(net "FAN_PWR_EN_BUF")
	)
	(segment
		(start 460.2734 -51.435)
		(end 460.2734 -78.3844)
		(width 0.17272)
		(layer "B.Cu")
		(net "FAN_PWR_EN_BUF")
	)
	(segment
		(start 435.737 -39.751)
		(end 436.245 -39.243)
		(width 0.17272)
		(layer "B.Cu")
		(net "FAN_PWR_EN_BUF")
	)
	(segment
		(start 440.92495 -45.974)
		(end 439.674 -44.72305)
		(width 0.17272)
		(layer "B.Cu")
		(net "FAN_PWR_EN_BUF")
	)
	(segment
		(start 446.84188 -34.48812)
		(end 448.437 -32.893)
		(width 0.17272)
		(layer "B.Cu")
		(net "FAN_PWR_EN_BUF")
	)
	(segment
		(start 436.245 -39.243)
		(end 436.245 -36.068254)
		(width 0.17272)
		(layer "B.Cu")
		(net "FAN_PWR_EN_BUF")
	)
	(segment
		(start 438.15 -43.18)
		(end 435.737 -40.767)
		(width 0.17272)
		(layer "B.Cu")
		(net "FAN_PWR_EN_BUF")
	)
	(segment
		(start 381.084328 -19.812)
		(end 377.0376 -19.812)
		(width 0.12954)
		(layer "In2.Cu")
		(net "FAN_PWR_EN_BUF")
	)
	(segment
		(start 354.530914 -9.01446)
		(end 350.142302 -4.625848)
		(width 0.12954)
		(layer "In2.Cu")
		(net "FAN_PWR_EN_BUF")
	)
	(segment
		(start 373.48287 -23.36673)
		(end 366.597438 -23.36673)
		(width 0.12954)
		(layer "In2.Cu")
		(net "FAN_PWR_EN_BUF")
	)
	(segment
		(start 382.869186 -8.545068)
		(end 385.826254 -5.588)
		(width 0.12954)
		(layer "In2.Cu")
		(net "FAN_PWR_EN_BUF")
	)
	(segment
		(start 363.35462 -20.123912)
		(end 363.35462 -9.972802)
		(width 0.12954)
		(layer "In2.Cu")
		(net "FAN_PWR_EN_BUF")
	)
	(segment
		(start 363.35462 -9.972802)
		(end 362.396278 -9.01446)
		(width 0.12954)
		(layer "In2.Cu")
		(net "FAN_PWR_EN_BUF")
	)
	(segment
		(start 381.946912 -18.949416)
		(end 381.084328 -19.812)
		(width 0.12954)
		(layer "In2.Cu")
		(net "FAN_PWR_EN_BUF")
	)
	(segment
		(start 350.142302 -4.625848)
		(end 105.609136 -4.625848)
		(width 0.12954)
		(layer "In2.Cu")
		(net "FAN_PWR_EN_BUF")
	)
	(segment
		(start 90.408506 -19.827494)
		(end 83.688174 -19.827494)
		(width 0.12954)
		(layer "In2.Cu")
		(net "FAN_PWR_EN_BUF")
	)
	(segment
		(start 377.0376 -19.812)
		(end 373.48287 -23.36673)
		(width 0.12954)
		(layer "In2.Cu")
		(net "FAN_PWR_EN_BUF")
	)
	(segment
		(start 105.609136 -4.625848)
		(end 90.408506 -19.827494)
		(width 0.12954)
		(layer "In2.Cu")
		(net "FAN_PWR_EN_BUF")
	)
	(segment
		(start 83.688174 -19.827494)
		(end 82.804 -18.94332)
		(width 0.12954)
		(layer "In2.Cu")
		(net "FAN_PWR_EN_BUF")
	)
	(segment
		(start 427.746922 -21.79574)
		(end 436.958486 -21.79574)
		(width 0.12954)
		(layer "In2.Cu")
		(net "FAN_PWR_EN_BUF")
	)
	(segment
		(start 449.453 -31.877)
		(end 450.469 -32.893)
		(width 0.12954)
		(layer "In2.Cu")
		(net "FAN_PWR_EN_BUF")
	)
	(segment
		(start 382.869186 -17.994884)
		(end 382.869186 -8.545068)
		(width 0.12954)
		(layer "In2.Cu")
		(net "FAN_PWR_EN_BUF")
	)
	(segment
		(start 439.547 -31.115)
		(end 441.071 -32.639)
		(width 0.12954)
		(layer "In2.Cu")
		(net "FAN_PWR_EN_BUF")
	)
	(segment
		(start 439.547 -24.384254)
		(end 439.547 -31.115)
		(width 0.12954)
		(layer "In2.Cu")
		(net "FAN_PWR_EN_BUF")
	)
	(segment
		(start 411.539182 -5.588)
		(end 427.746922 -21.79574)
		(width 0.12954)
		(layer "In2.Cu")
		(net "FAN_PWR_EN_BUF")
	)
	(segment
		(start 448.564 -29.718)
		(end 449.453 -30.607)
		(width 0.12954)
		(layer "In2.Cu")
		(net "FAN_PWR_EN_BUF")
	)
	(segment
		(start 381.946912 -18.917158)
		(end 381.946912 -18.949416)
		(width 0.12954)
		(layer "In2.Cu")
		(net "FAN_PWR_EN_BUF")
	)
	(segment
		(start 381.946912 -18.917158)
		(end 382.869186 -17.994884)
		(width 0.12954)
		(layer "In2.Cu")
		(net "FAN_PWR_EN_BUF")
	)
	(segment
		(start 447.04 -29.718)
		(end 448.564 -29.718)
		(width 0.12954)
		(layer "In2.Cu")
		(net "FAN_PWR_EN_BUF")
	)
	(segment
		(start 441.071 -32.639)
		(end 444.119 -32.639)
		(width 0.12954)
		(layer "In2.Cu")
		(net "FAN_PWR_EN_BUF")
	)
	(segment
		(start 385.826254 -5.588)
		(end 411.539182 -5.588)
		(width 0.12954)
		(layer "In2.Cu")
		(net "FAN_PWR_EN_BUF")
	)
	(segment
		(start 82.804 -18.94332)
		(end 82.804 -18.916904)
		(width 0.12954)
		(layer "In2.Cu")
		(net "FAN_PWR_EN_BUF")
	)
	(segment
		(start 366.597438 -23.36673)
		(end 363.35462 -20.123912)
		(width 0.12954)
		(layer "In2.Cu")
		(net "FAN_PWR_EN_BUF")
	)
	(segment
		(start 436.958486 -21.79574)
		(end 439.547 -24.384254)
		(width 0.12954)
		(layer "In2.Cu")
		(net "FAN_PWR_EN_BUF")
	)
	(segment
		(start 362.396278 -9.01446)
		(end 354.530914 -9.01446)
		(width 0.12954)
		(layer "In2.Cu")
		(net "FAN_PWR_EN_BUF")
	)
	(segment
		(start 449.453 -30.607)
		(end 449.453 -31.877)
		(width 0.12954)
		(layer "In2.Cu")
		(net "FAN_PWR_EN_BUF")
	)
	(segment
		(start 444.119 -32.639)
		(end 447.04 -29.718)
		(width 0.12954)
		(layer "In2.Cu")
		(net "FAN_PWR_EN_BUF")
	)
	(segment
		(start 160.575244 -81.896204)
		(end 160.274 -81.59496)
		(width 0.4572)
		(layer "F.Cu")
		(net "P52V_2_BUSBAR")
	)
	(segment
		(start 160.575244 -86.084918)
		(end 160.575244 -81.896204)
		(width 0.4572)
		(layer "F.Cu")
		(net "P52V_2_BUSBAR")
	)
	(via
		(at 158.369 -96.266)
		(size 0.508)
		(drill 0.254)
		(layers "F.Cu" "B.Cu")
		(net "P52V_2_BUSBAR")
	)
	(via
		(at 160.575244 -86.084918)
		(size 0.508)
		(drill 0.254)
		(layers "F.Cu" "B.Cu")
		(net "P52V_2_BUSBAR")
	)
	(via
		(at 200.1774 -97.282)
		(size 0.6604)
		(drill 0.3302)
		(layers "F.Cu" "B.Cu")
		(net "P52V_2_BUSBAR")
	)
	(segment
		(start 161.6202 -99.5172)
		(end 197.9422 -99.5172)
		(width 0.4572)
		(layer "B.Cu")
		(net "P52V_2_BUSBAR")
	)
	(segment
		(start 158.369 -96.266)
		(end 161.6202 -99.5172)
		(width 0.4572)
		(layer "B.Cu")
		(net "P52V_2_BUSBAR")
	)
	(segment
		(start 215.1888 -82.2706)
		(end 200.1774 -97.282)
		(width 0.4572)
		(layer "B.Cu")
		(net "P52V_2_BUSBAR")
	)
	(segment
		(start 215.1888 -56.159654)
		(end 215.1888 -82.2706)
		(width 0.4572)
		(layer "B.Cu")
		(net "P52V_2_BUSBAR")
	)
	(segment
		(start 197.9422 -99.5172)
		(end 200.1774 -97.282)
		(width 0.4572)
		(layer "B.Cu")
		(net "P52V_2_BUSBAR")
	)
	(segment
		(start 210.079082 -51.049936)
		(end 215.1888 -56.159654)
		(width 0.4572)
		(layer "B.Cu")
		(net "P52V_2_BUSBAR")
	)
	(segment
		(start 208.810098 -51.049936)
		(end 210.079082 -51.049936)
		(width 0.4572)
		(layer "B.Cu")
		(net "P52V_2_BUSBAR")
	)
	(segment
		(start 160.575244 -86.084918)
		(end 158.369 -88.291162)
		(width 0.4572)
		(layer "In2.Cu")
		(net "P52V_2_BUSBAR")
	)
	(segment
		(start 158.369 -88.291162)
		(end 158.369 -96.266)
		(width 0.4572)
		(layer "In2.Cu")
		(net "P52V_2_BUSBAR")
	)
	(segment
		(start 382.2954 -17.158716)
		(end 381.946912 -17.507204)
		(width 0.17272)
		(layer "F.Cu")
		(net "FAN_PWR_EN_0_R")
	)
	(segment
		(start 382.2954 -16.383)
		(end 382.2954 -17.158716)
		(width 0.17272)
		(layer "F.Cu")
		(net "FAN_PWR_EN_0_R")
	)
	(via
		(at 382.2954 -16.383)
		(size 0.508)
		(drill 0.254)
		(layers "F.Cu" "B.Cu")
		(net "FAN_PWR_EN_0_R")
	)
	(segment
		(start 374.549416 -3.305048)
		(end 373.430038 -3.305048)
		(width 0.17272)
		(layer "B.Cu")
		(net "FAN_PWR_EN_0_R")
	)
	(segment
		(start 375.491502 -4.247134)
		(end 374.549416 -3.305048)
		(width 0.17272)
		(layer "B.Cu")
		(net "FAN_PWR_EN_0_R")
	)
	(segment
		(start 381.171196 -15.512796)
		(end 381.171196 -12.998196)
		(width 0.17272)
		(layer "B.Cu")
		(net "FAN_PWR_EN_0_R")
	)
	(segment
		(start 375.158 -5.236464)
		(end 375.491502 -4.902962)
		(width 0.17272)
		(layer "B.Cu")
		(net "FAN_PWR_EN_0_R")
	)
	(segment
		(start 375.491502 -4.902962)
		(end 375.491502 -4.247134)
		(width 0.17272)
		(layer "B.Cu")
		(net "FAN_PWR_EN_0_R")
	)
	(segment
		(start 381.171196 -12.998196)
		(end 375.158 -6.985)
		(width 0.17272)
		(layer "B.Cu")
		(net "FAN_PWR_EN_0_R")
	)
	(segment
		(start 382.2954 -16.383)
		(end 382.0414 -16.383)
		(width 0.17272)
		(layer "B.Cu")
		(net "FAN_PWR_EN_0_R")
	)
	(segment
		(start 382.0414 -16.383)
		(end 381.171196 -15.512796)
		(width 0.17272)
		(layer "B.Cu")
		(net "FAN_PWR_EN_0_R")
	)
	(segment
		(start 375.158 -6.985)
		(end 375.158 -5.236464)
		(width 0.17272)
		(layer "B.Cu")
		(net "FAN_PWR_EN_0_R")
	)
	(via
		(at 264.5156 -93.6244)
		(size 0.6604)
		(drill 0.3302)
		(layers "F.Cu" "B.Cu")
		(net "P52V_1_BUSBAR")
	)
	(segment
		(start 266.573 -91.567)
		(end 272.86204 -91.567)
		(width 0.4572)
		(layer "B.Cu")
		(net "P52V_1_BUSBAR")
	)
	(segment
		(start 237.046516 -49.286414)
		(end 228.71684 -49.286414)
		(width 0.4572)
		(layer "B.Cu")
		(net "P52V_1_BUSBAR")
	)
	(segment
		(start 228.71684 -49.286414)
		(end 224.986342 -53.016912)
		(width 0.4572)
		(layer "B.Cu")
		(net "P52V_1_BUSBAR")
	)
	(segment
		(start 264.5156 -93.6244)
		(end 266.573 -91.567)
		(width 0.4572)
		(layer "B.Cu")
		(net "P52V_1_BUSBAR")
	)
	(segment
		(start 224.986342 -53.016912)
		(end 224.986342 -83.062064)
		(width 0.4572)
		(layer "B.Cu")
		(net "P52V_1_BUSBAR")
	)
	(segment
		(start 242.211352 -100.287074)
		(end 262.069326 -100.287074)
		(width 0.4572)
		(layer "B.Cu")
		(net "P52V_1_BUSBAR")
	)
	(segment
		(start 238.810038 -51.049936)
		(end 237.046516 -49.286414)
		(width 0.4572)
		(layer "B.Cu")
		(net "P52V_1_BUSBAR")
	)
	(segment
		(start 263.3472 -94.7928)
		(end 264.5156 -93.6244)
		(width 0.4572)
		(layer "B.Cu")
		(net "P52V_1_BUSBAR")
	)
	(segment
		(start 262.069326 -100.287074)
		(end 263.3472 -99.0092)
		(width 0.4572)
		(layer "B.Cu")
		(net "P52V_1_BUSBAR")
	)
	(segment
		(start 263.3472 -99.0092)
		(end 263.3472 -94.7928)
		(width 0.4572)
		(layer "B.Cu")
		(net "P52V_1_BUSBAR")
	)
	(segment
		(start 224.986342 -83.062064)
		(end 242.211352 -100.287074)
		(width 0.4572)
		(layer "B.Cu")
		(net "P52V_1_BUSBAR")
	)
	(segment
		(start 425.3484 -44.704)
		(end 426.6184 -45.974)
		(width 0.17272)
		(layer "F.Cu")
		(net "PCA9555_A0")
	)
	(segment
		(start 426.6184 -45.974)
		(end 426.82795 -45.974)
		(width 0.17272)
		(layer "F.Cu")
		(net "PCA9555_A0")
	)
	(segment
		(start 424.9293 -44.704)
		(end 425.3484 -44.704)
		(width 0.17272)
		(layer "F.Cu")
		(net "PCA9555_A0")
	)
	(segment
		(start 429.24095 -45.339)
		(end 429.87595 -45.974)
		(width 0.17272)
		(layer "F.Cu")
		(net "PCA9555_A0")
	)
	(segment
		(start 426.82795 -45.974)
		(end 427.46295 -45.339)
		(width 0.17272)
		(layer "F.Cu")
		(net "PCA9555_A0")
	)
	(segment
		(start 427.46295 -45.339)
		(end 429.24095 -45.339)
		(width 0.17272)
		(layer "F.Cu")
		(net "PCA9555_A0")
	)
	(segment
		(start 423.291 -44.043092)
		(end 424.268392 -44.043092)
		(width 0.17272)
		(layer "F.Cu")
		(net "PCA9555_A0")
	)
	(segment
		(start 424.268392 -44.043092)
		(end 424.9293 -44.704)
		(width 0.17272)
		(layer "F.Cu")
		(net "PCA9555_A0")
	)
	(via
		(at 425.3484 -44.704)
		(size 0.762)
		(drill 0.381)
		(layers "F.Cu" "B.Cu")
		(net "PCA9555_A0")
	)
	(segment
		(start 415.950146 -45.212)
		(end 413.91205 -45.212)
		(width 0.17272)
		(layer "F.Cu")
		(net "PCA9555_A1")
	)
	(segment
		(start 411.734 -45.847)
		(end 411.48 -45.593)
		(width 0.17272)
		(layer "F.Cu")
		(net "PCA9555_A1")
	)
	(segment
		(start 413.638746 -45.847)
		(end 411.734 -45.847)
		(width 0.17272)
		(layer "F.Cu")
		(net "PCA9555_A1")
	)
	(segment
		(start 413.91205 -45.573696)
		(end 413.638746 -45.847)
		(width 0.17272)
		(layer "F.Cu")
		(net "PCA9555_A1")
	)
	(segment
		(start 411.099 -45.466)
		(end 411.099 -46.33595)
		(width 0.17272)
		(layer "F.Cu")
		(net "PCA9555_A1")
	)
	(segment
		(start 411.48 -45.593)
		(end 411.48 -45.085)
		(width 0.17272)
		(layer "F.Cu")
		(net "PCA9555_A1")
	)
	(segment
		(start 413.91205 -45.212)
		(end 413.91205 -45.573696)
		(width 0.17272)
		(layer "F.Cu")
		(net "PCA9555_A1")
	)
	(segment
		(start 416.08121 -45.343064)
		(end 415.950146 -45.212)
		(width 0.17272)
		(layer "F.Cu")
		(net "PCA9555_A1")
	)
	(segment
		(start 417.449 -45.343064)
		(end 416.08121 -45.343064)
		(width 0.17272)
		(layer "F.Cu")
		(net "PCA9555_A1")
	)
	(segment
		(start 411.48 -45.085)
		(end 411.099 -45.466)
		(width 0.17272)
		(layer "F.Cu")
		(net "PCA9555_A1")
	)
	(via
		(at 411.48 -45.085)
		(size 0.762)
		(drill 0.381)
		(layers "F.Cu" "B.Cu")
		(net "PCA9555_A1")
	)
	(segment
		(start 430.9364 -30.226)
		(end 430.9364 -29.21)
		(width 0.17272)
		(layer "F.Cu")
		(net "SMB_FRU_CLK")
	)
	(segment
		(start 448.95135 -30.607)
		(end 448.3354 -30.607)
		(width 0.17272)
		(layer "F.Cu")
		(net "SMB_FRU_CLK")
	)
	(segment
		(start 430.9364 -29.21)
		(end 432.0794 -28.067)
		(width 0.17272)
		(layer "F.Cu")
		(net "SMB_FRU_CLK")
	)
	(segment
		(start 448.3354 -30.607)
		(end 448.0814 -30.353)
		(width 0.17272)
		(layer "F.Cu")
		(net "SMB_FRU_CLK")
	)
	(segment
		(start 432.0794 -28.067)
		(end 432.0794 -27.2542)
		(width 0.17272)
		(layer "F.Cu")
		(net "SMB_FRU_CLK")
	)
	(via
		(at 448.0814 -30.353)
		(size 0.508)
		(drill 0.254)
		(layers "F.Cu" "B.Cu")
		(net "SMB_FRU_CLK")
	)
	(via
		(at 430.9364 -30.226)
		(size 0.508)
		(drill 0.254)
		(layers "F.Cu" "B.Cu")
		(net "SMB_FRU_CLK")
	)
	(segment
		(start 448.0814 -30.353)
		(end 447.3194 -30.353)
		(width 0.12954)
		(layer "In2.Cu")
		(net "SMB_FRU_CLK")
	)
	(segment
		(start 447.3194 -30.353)
		(end 444.2714 -33.401)
		(width 0.12954)
		(layer "In2.Cu")
		(net "SMB_FRU_CLK")
	)
	(segment
		(start 433.8066 -30.226)
		(end 430.9364 -30.226)
		(width 0.12954)
		(layer "In2.Cu")
		(net "SMB_FRU_CLK")
	)
	(segment
		(start 444.2714 -33.401)
		(end 436.9816 -33.401)
		(width 0.12954)
		(layer "In2.Cu")
		(net "SMB_FRU_CLK")
	)
	(segment
		(start 436.9816 -33.401)
		(end 433.8066 -30.226)
		(width 0.12954)
		(layer "In2.Cu")
		(net "SMB_FRU_CLK")
	)
	(segment
		(start 418.82695 -49.256696)
		(end 418.82695 -49.276)
		(width 0.17272)
		(layer "F.Cu")
		(net "PWRGD_P52V_HS1_4287_PG")
	)
	(segment
		(start 418.82695 -49.276)
		(end 419.71595 -50.165)
		(width 0.17272)
		(layer "F.Cu")
		(net "PWRGD_P52V_HS1_4287_PG")
	)
	(segment
		(start 418.084254 -48.514)
		(end 418.82695 -49.256696)
		(width 0.17272)
		(layer "F.Cu")
		(net "PWRGD_P52V_HS1_4287_PG")
	)
	(segment
		(start 417.331398 -48.514)
		(end 418.084254 -48.514)
		(width 0.17272)
		(layer "F.Cu")
		(net "PWRGD_P52V_HS1_4287_PG")
	)
	(segment
		(start 419.71595 -50.165)
		(end 419.71595 -50.546)
		(width 0.17272)
		(layer "F.Cu")
		(net "PWRGD_P52V_HS1_4287_PG")
	)
	(via
		(at 418.82695 -49.276)
		(size 0.762)
		(drill 0.381)
		(layers "F.Cu" "B.Cu")
		(net "PWRGD_P52V_HS1_4287_PG")
	)
	(segment
		(start 413.91205 -43.815)
		(end 414.790128 -44.693078)
		(width 0.17272)
		(layer "F.Cu")
		(net "PCA9555_A2")
	)
	(segment
		(start 413.27705 -43.18)
		(end 413.91205 -43.815)
		(width 0.17272)
		(layer "F.Cu")
		(net "PCA9555_A2")
	)
	(segment
		(start 411.607 -43.307)
		(end 411.734 -43.18)
		(width 0.17272)
		(layer "F.Cu")
		(net "PCA9555_A2")
	)
	(segment
		(start 410.972 -43.942)
		(end 411.607 -43.307)
		(width 0.17272)
		(layer "F.Cu")
		(net "PCA9555_A2")
	)
	(segment
		(start 411.734 -43.18)
		(end 413.27705 -43.18)
		(width 0.17272)
		(layer "F.Cu")
		(net "PCA9555_A2")
	)
	(segment
		(start 410.35605 -43.942)
		(end 410.972 -43.942)
		(width 0.17272)
		(layer "F.Cu")
		(net "PCA9555_A2")
	)
	(segment
		(start 414.790128 -44.693078)
		(end 417.449 -44.693078)
		(width 0.17272)
		(layer "F.Cu")
		(net "PCA9555_A2")
	)
	(via
		(at 411.607 -43.307)
		(size 0.762)
		(drill 0.381)
		(layers "F.Cu" "B.Cu")
		(net "PCA9555_A2")
	)
	(via
		(at 252.464316 -33.288224)
		(size 0.508)
		(drill 0.254)
		(layers "F.Cu" "B.Cu")
		(net "P52V_1")
	)
	(via
		(at 299.4914 -63.754)
		(size 0.508)
		(drill 0.254)
		(layers "F.Cu" "B.Cu")
		(net "P52V_1")
	)
	(via
		(at 299.4914 -64.516)
		(size 0.508)
		(drill 0.254)
		(layers "F.Cu" "B.Cu")
		(net "P52V_1")
	)
	(via
		(at 298.7294 -31.4452)
		(size 0.508)
		(drill 0.254)
		(layers "F.Cu" "B.Cu")
		(net "P52V_1")
	)
	(via
		(at 298.7294 -26.8732)
		(size 0.508)
		(drill 0.254)
		(layers "F.Cu" "B.Cu")
		(net "P52V_1")
	)
	(via
		(at 300.2534 -31.4452)
		(size 0.508)
		(drill 0.254)
		(layers "F.Cu" "B.Cu")
		(net "P52V_1")
	)
	(via
		(at 300.2534 -29.9212)
		(size 0.508)
		(drill 0.254)
		(layers "F.Cu" "B.Cu")
		(net "P52V_1")
	)
	(via
		(at 276.6822 -86.233)
		(size 0.508)
		(drill 0.254)
		(layers "F.Cu" "B.Cu")
		(net "P52V_1")
	)
	(via
		(at 300.2534 -28.3972)
		(size 0.508)
		(drill 0.254)
		(layers "F.Cu" "B.Cu")
		(net "P52V_1")
	)
	(via
		(at 299.4914 -61.468)
		(size 0.508)
		(drill 0.254)
		(layers "F.Cu" "B.Cu")
		(net "P52V_1")
	)
	(via
		(at 298.7294 -62.23)
		(size 0.508)
		(drill 0.254)
		(layers "F.Cu" "B.Cu")
		(net "P52V_1")
	)
	(via
		(at 298.7294 -60.706)
		(size 0.508)
		(drill 0.254)
		(layers "F.Cu" "B.Cu")
		(net "P52V_1")
	)
	(via
		(at 299.4914 -62.992)
		(size 0.508)
		(drill 0.254)
		(layers "F.Cu" "B.Cu")
		(net "P52V_1")
	)
	(via
		(at 300.2534 -60.706)
		(size 0.508)
		(drill 0.254)
		(layers "F.Cu" "B.Cu")
		(net "P52V_1")
	)
	(via
		(at 298.7294 -29.1592)
		(size 0.508)
		(drill 0.254)
		(layers "F.Cu" "B.Cu")
		(net "P52V_1")
	)
	(via
		(at 266.827 -85.471)
		(size 0.6604)
		(drill 0.3302)
		(layers "F.Cu" "B.Cu")
		(net "P52V_1")
	)
	(via
		(at 300.2534 -64.516)
		(size 0.508)
		(drill 0.254)
		(layers "F.Cu" "B.Cu")
		(net "P52V_1")
	)
	(via
		(at 299.4914 -30.6832)
		(size 0.508)
		(drill 0.254)
		(layers "F.Cu" "B.Cu")
		(net "P52V_1")
	)
	(via
		(at 251.702316 -32.526224)
		(size 0.508)
		(drill 0.254)
		(layers "F.Cu" "B.Cu")
		(net "P52V_1")
	)
	(via
		(at 270.0782 -86.233)
		(size 0.508)
		(drill 0.254)
		(layers "F.Cu" "B.Cu")
		(net "P52V_1")
	)
	(via
		(at 299.4914 -32.2072)
		(size 0.508)
		(drill 0.254)
		(layers "F.Cu" "B.Cu")
		(net "P52V_1")
	)
	(via
		(at 299.4914 -29.1592)
		(size 0.508)
		(drill 0.254)
		(layers "F.Cu" "B.Cu")
		(net "P52V_1")
	)
	(via
		(at 298.7294 -65.278)
		(size 0.508)
		(drill 0.254)
		(layers "F.Cu" "B.Cu")
		(net "P52V_1")
	)
	(via
		(at 300.2534 -29.1592)
		(size 0.508)
		(drill 0.254)
		(layers "F.Cu" "B.Cu")
		(net "P52V_1")
	)
	(via
		(at 298.7294 -62.992)
		(size 0.508)
		(drill 0.254)
		(layers "F.Cu" "B.Cu")
		(net "P52V_1")
	)
	(via
		(at 300.2534 -63.754)
		(size 0.508)
		(drill 0.254)
		(layers "F.Cu" "B.Cu")
		(net "P52V_1")
	)
	(via
		(at 270.7132 -86.233)
		(size 0.508)
		(drill 0.254)
		(layers "F.Cu" "B.Cu")
		(net "P52V_1")
	)
	(via
		(at 299.4914 -65.278)
		(size 0.508)
		(drill 0.254)
		(layers "F.Cu" "B.Cu")
		(net "P52V_1")
	)
	(via
		(at 272.7452 -86.233)
		(size 0.508)
		(drill 0.254)
		(layers "F.Cu" "B.Cu")
		(net "P52V_1")
	)
	(via
		(at 300.2534 -26.8732)
		(size 0.508)
		(drill 0.254)
		(layers "F.Cu" "B.Cu")
		(net "P52V_1")
	)
	(via
		(at 299.4914 -66.04)
		(size 0.508)
		(drill 0.254)
		(layers "F.Cu" "B.Cu")
		(net "P52V_1")
	)
	(via
		(at 297.5864 -61.341)
		(size 0.508)
		(drill 0.254)
		(layers "F.Cu" "B.Cu")
		(net "P52V_1")
	)
	(via
		(at 300.2534 -62.23)
		(size 0.508)
		(drill 0.254)
		(layers "F.Cu" "B.Cu")
		(net "P52V_1")
	)
	(via
		(at 300.2534 -62.992)
		(size 0.508)
		(drill 0.254)
		(layers "F.Cu" "B.Cu")
		(net "P52V_1")
	)
	(via
		(at 272.1102 -86.233)
		(size 0.508)
		(drill 0.254)
		(layers "F.Cu" "B.Cu")
		(net "P52V_1")
	)
	(via
		(at 300.2534 -30.6832)
		(size 0.508)
		(drill 0.254)
		(layers "F.Cu" "B.Cu")
		(net "P52V_1")
	)
	(via
		(at 251.702316 -33.288224)
		(size 0.508)
		(drill 0.254)
		(layers "F.Cu" "B.Cu")
		(net "P52V_1")
	)
	(via
		(at 300.2534 -32.2072)
		(size 0.508)
		(drill 0.254)
		(layers "F.Cu" "B.Cu")
		(net "P52V_1")
	)
	(via
		(at 298.7294 -61.468)
		(size 0.508)
		(drill 0.254)
		(layers "F.Cu" "B.Cu")
		(net "P52V_1")
	)
	(via
		(at 282.702 -86.106)
		(size 0.6604)
		(drill 0.3302)
		(layers "F.Cu" "B.Cu")
		(net "P52V_1")
	)
	(via
		(at 299.4914 -28.3972)
		(size 0.508)
		(drill 0.254)
		(layers "F.Cu" "B.Cu")
		(net "P52V_1")
	)
	(via
		(at 300.2534 -61.468)
		(size 0.508)
		(drill 0.254)
		(layers "F.Cu" "B.Cu")
		(net "P52V_1")
	)
	(via
		(at 299.4914 -62.23)
		(size 0.508)
		(drill 0.254)
		(layers "F.Cu" "B.Cu")
		(net "P52V_1")
	)
	(via
		(at 298.7294 -30.6832)
		(size 0.508)
		(drill 0.254)
		(layers "F.Cu" "B.Cu")
		(net "P52V_1")
	)
	(via
		(at 300.2534 -65.278)
		(size 0.508)
		(drill 0.254)
		(layers "F.Cu" "B.Cu")
		(net "P52V_1")
	)
	(via
		(at 300.2534 -27.6352)
		(size 0.508)
		(drill 0.254)
		(layers "F.Cu" "B.Cu")
		(net "P52V_1")
	)
	(via
		(at 298.7294 -28.3972)
		(size 0.508)
		(drill 0.254)
		(layers "F.Cu" "B.Cu")
		(net "P52V_1")
	)
	(via
		(at 252.464316 -32.526224)
		(size 0.508)
		(drill 0.254)
		(layers "F.Cu" "B.Cu")
		(net "P52V_1")
	)
	(via
		(at 299.4914 -60.706)
		(size 0.508)
		(drill 0.254)
		(layers "F.Cu" "B.Cu")
		(net "P52V_1")
	)
	(via
		(at 299.4914 -26.8732)
		(size 0.508)
		(drill 0.254)
		(layers "F.Cu" "B.Cu")
		(net "P52V_1")
	)
	(via
		(at 300.2534 -66.04)
		(size 0.508)
		(drill 0.254)
		(layers "F.Cu" "B.Cu")
		(net "P52V_1")
	)
	(via
		(at 299.4914 -31.4452)
		(size 0.508)
		(drill 0.254)
		(layers "F.Cu" "B.Cu")
		(net "P52V_1")
	)
	(via
		(at 298.7294 -29.9212)
		(size 0.508)
		(drill 0.254)
		(layers "F.Cu" "B.Cu")
		(net "P52V_1")
	)
	(via
		(at 299.4914 -27.6352)
		(size 0.508)
		(drill 0.254)
		(layers "F.Cu" "B.Cu")
		(net "P52V_1")
	)
	(via
		(at 274.7772 -86.233)
		(size 0.508)
		(drill 0.254)
		(layers "F.Cu" "B.Cu")
		(net "P52V_1")
	)
	(via
		(at 298.7294 -32.2072)
		(size 0.508)
		(drill 0.254)
		(layers "F.Cu" "B.Cu")
		(net "P52V_1")
	)
	(via
		(at 276.0472 -86.233)
		(size 0.508)
		(drill 0.254)
		(layers "F.Cu" "B.Cu")
		(net "P52V_1")
	)
	(via
		(at 253.226316 -32.526224)
		(size 0.762)
		(drill 0.254)
		(layers "F.Cu" "B.Cu")
		(net "P52V_1")
	)
	(via
		(at 274.1422 -86.233)
		(size 0.508)
		(drill 0.254)
		(layers "F.Cu" "B.Cu")
		(net "P52V_1")
	)
	(via
		(at 298.7294 -64.516)
		(size 0.508)
		(drill 0.254)
		(layers "F.Cu" "B.Cu")
		(net "P52V_1")
	)
	(via
		(at 298.7294 -27.6352)
		(size 0.508)
		(drill 0.254)
		(layers "F.Cu" "B.Cu")
		(net "P52V_1")
	)
	(via
		(at 299.4914 -29.9212)
		(size 0.508)
		(drill 0.254)
		(layers "F.Cu" "B.Cu")
		(net "P52V_1")
	)
	(via
		(at 298.7294 -66.04)
		(size 0.508)
		(drill 0.254)
		(layers "F.Cu" "B.Cu")
		(net "P52V_1")
	)
	(via
		(at 298.7294 -63.754)
		(size 0.508)
		(drill 0.254)
		(layers "F.Cu" "B.Cu")
		(net "P52V_1")
	)
	(via
		(at 297.5864 -60.452)
		(size 0.762)
		(drill 0.254)
		(layers "F.Cu" "B.Cu")
		(net "P52V_1")
	)
	(via
		(at 253.226316 -33.288224)
		(size 0.508)
		(drill 0.254)
		(layers "F.Cu" "B.Cu")
		(net "P52V_1")
	)
	(segment
		(start 282.702 -86.106)
		(end 282.702 -87.82304)
		(width 0.4572)
		(layer "B.Cu")
		(net "P52V_1")
	)
	(segment
		(start 281.74696 -85.15096)
		(end 282.702 -86.106)
		(width 0.4572)
		(layer "B.Cu")
		(net "P52V_1")
	)
	(segment
		(start 276.3774 -85.15096)
		(end 281.74696 -85.15096)
		(width 0.4572)
		(layer "B.Cu")
		(net "P52V_1")
	)
	(segment
		(start 431.8254 -29.337)
		(end 432.1429 -29.0195)
		(width 0.17272)
		(layer "F.Cu")
		(net "SMB_FRU_DAT")
	)
	(segment
		(start 433.3494 -27.813)
		(end 433.3494 -27.2542)
		(width 0.17272)
		(layer "F.Cu")
		(net "SMB_FRU_DAT")
	)
	(segment
		(start 431.8254 -30.94355)
		(end 431.8254 -29.337)
		(width 0.17272)
		(layer "F.Cu")
		(net "SMB_FRU_DAT")
	)
	(segment
		(start 432.1429 -29.0195)
		(end 433.3494 -27.813)
		(width 0.17272)
		(layer "F.Cu")
		(net "SMB_FRU_DAT")
	)
	(via
		(at 432.1429 -29.0195)
		(size 0.508)
		(drill 0.254)
		(layers "F.Cu" "B.Cu")
		(net "SMB_FRU_DAT")
	)
	(segment
		(start 304.616358 -63.798958)
		(end 304.616358 -63.925958)
		(width 0.254)
		(layer "F.Cu")
		(net "P52V_HS1_SENSE_P_R1")
	)
	(segment
		(start 301.6758 -68.199)
		(end 301.6758 -67.4624)
		(width 0.4572)
		(layer "F.Cu")
		(net "P52V_HS1_SENSE_P_R1")
	)
	(segment
		(start 301.6758 -71.755)
		(end 301.6758 -69.977)
		(width 0.4572)
		(layer "F.Cu")
		(net "P52V_HS1_SENSE_P_R1")
	)
	(segment
		(start 304.1904 -63.373)
		(end 304.616358 -63.798958)
		(width 0.254)
		(layer "F.Cu")
		(net "P52V_HS1_SENSE_P_R1")
	)
	(segment
		(start 303.839626 -63.373)
		(end 304.1904 -63.373)
		(width 0.254)
		(layer "F.Cu")
		(net "P52V_HS1_SENSE_P_R1")
	)
	(segment
		(start 301.6758 -71.755)
		(end 301.6758 -73.152)
		(width 0.4572)
		(layer "F.Cu")
		(net "P52V_HS1_SENSE_P_R1")
	)
	(segment
		(start 301.6758 -69.977)
		(end 301.6758 -68.199)
		(width 0.4572)
		(layer "F.Cu")
		(net "P52V_HS1_SENSE_P_R1")
	)
	(via
		(at 301.6758 -67.4624)
		(size 0.508)
		(drill 0.254)
		(layers "F.Cu" "B.Cu")
		(net "P52V_HS1_SENSE_P_R1")
	)
	(via
		(at 301.6758 -73.152)
		(size 0.762)
		(drill 0.381)
		(layers "F.Cu" "B.Cu")
		(net "P52V_HS1_SENSE_P_R1")
	)
	(via
		(at 304.616358 -63.925958)
		(size 0.508)
		(drill 0.254)
		(layers "F.Cu" "B.Cu")
		(net "P52V_HS1_SENSE_P_R1")
	)
	(segment
		(start 304.616358 -66.684906)
		(end 304.616358 -63.925958)
		(width 0.4572)
		(layer "In2.Cu")
		(net "P52V_HS1_SENSE_P_R1")
	)
	(segment
		(start 304.050446 -67.250818)
		(end 304.616358 -66.684906)
		(width 0.4572)
		(layer "In2.Cu")
		(net "P52V_HS1_SENSE_P_R1")
	)
	(segment
		(start 301.6758 -67.4624)
		(end 301.887382 -67.250818)
		(width 0.4572)
		(layer "In2.Cu")
		(net "P52V_HS1_SENSE_P_R1")
	)
	(segment
		(start 301.887382 -67.250818)
		(end 304.050446 -67.250818)
		(width 0.4572)
		(layer "In2.Cu")
		(net "P52V_HS1_SENSE_P_R1")
	)
	(segment
		(start 307.467 -69.977)
		(end 307.467 -68.199)
		(width 0.4572)
		(layer "F.Cu")
		(net "P52V_HS1_SENSE_N_R1")
	)
	(segment
		(start 304.616358 -62.909958)
		(end 304.616358 -62.820042)
		(width 0.254)
		(layer "F.Cu")
		(net "P52V_HS1_SENSE_N_R1")
	)
	(segment
		(start 305.39309 -63.373)
		(end 305.0794 -63.373)
		(width 0.254)
		(layer "F.Cu")
		(net "P52V_HS1_SENSE_N_R1")
	)
	(segment
		(start 307.467 -68.199)
		(end 307.467 -67.4624)
		(width 0.4572)
		(layer "F.Cu")
		(net "P52V_HS1_SENSE_N_R1")
	)
	(segment
		(start 307.467 -71.755)
		(end 307.467 -69.977)
		(width 0.4572)
		(layer "F.Cu")
		(net "P52V_HS1_SENSE_N_R1")
	)
	(segment
		(start 305.0794 -63.373)
		(end 304.616358 -62.909958)
		(width 0.254)
		(layer "F.Cu")
		(net "P52V_HS1_SENSE_N_R1")
	)
	(via
		(at 307.467 -67.4624)
		(size 0.508)
		(drill 0.254)
		(layers "F.Cu" "B.Cu")
		(net "P52V_HS1_SENSE_N_R1")
	)
	(via
		(at 304.616358 -62.820042)
		(size 0.508)
		(drill 0.254)
		(layers "F.Cu" "B.Cu")
		(net "P52V_HS1_SENSE_N_R1")
	)
	(segment
		(start 305.251358 -63.455042)
		(end 304.616358 -62.820042)
		(width 0.4572)
		(layer "In2.Cu")
		(net "P52V_HS1_SENSE_N_R1")
	)
	(segment
		(start 305.193446 -66.934334)
		(end 305.200558 -66.926968)
		(width 0.4572)
		(layer "In2.Cu")
		(net "P52V_HS1_SENSE_N_R1")
	)
	(segment
		(start 305.251358 -64.189102)
		(end 305.251358 -63.455042)
		(width 0.4572)
		(layer "In2.Cu")
		(net "P52V_HS1_SENSE_N_R1")
	)
	(segment
		(start 305.721512 -67.4624)
		(end 305.193446 -66.934334)
		(width 0.4572)
		(layer "In2.Cu")
		(net "P52V_HS1_SENSE_N_R1")
	)
	(segment
		(start 307.467 -67.4624)
		(end 305.721512 -67.4624)
		(width 0.4572)
		(layer "In2.Cu")
		(net "P52V_HS1_SENSE_N_R1")
	)
	(segment
		(start 305.200558 -66.926968)
		(end 305.200558 -64.239902)
		(width 0.4572)
		(layer "In2.Cu")
		(net "P52V_HS1_SENSE_N_R1")
	)
	(segment
		(start 305.200558 -64.239902)
		(end 305.251358 -64.189102)
		(width 0.4572)
		(layer "In2.Cu")
		(net "P52V_HS1_SENSE_N_R1")
	)
	(segment
		(start 279.06345 -73.025)
		(end 279.2984 -73.025)
		(width 0.4572)
		(layer "F.Cu")
		(net "P52V_HS1_VCAP")
	)
	(segment
		(start 279.06345 -74.041)
		(end 279.2984 -74.041)
		(width 0.4572)
		(layer "F.Cu")
		(net "P52V_HS1_VCAP")
	)
	(segment
		(start 279.2984 -74.041)
		(end 279.8064 -73.533)
		(width 0.4572)
		(layer "F.Cu")
		(net "P52V_HS1_VCAP")
	)
	(segment
		(start 279.2984 -73.025)
		(end 279.8064 -73.533)
		(width 0.4572)
		(layer "F.Cu")
		(net "P52V_HS1_VCAP")
	)
	(via
		(at 279.8064 -73.533)
		(size 0.508)
		(drill 0.254)
		(layers "F.Cu" "B.Cu")
		(net "P52V_HS1_VCAP")
	)
	(via
		(at 276.1234 -71.755)
		(size 0.508)
		(drill 0.254)
		(layers "F.Cu" "B.Cu")
		(net "P52V_HS1_VCAP")
	)
	(segment
		(start 279.19045 -73.533)
		(end 279.8064 -73.533)
		(width 0.4572)
		(layer "B.Cu")
		(net "P52V_HS1_VCAP")
	)
	(segment
		(start 276.1234 -71.755)
		(end 277.9014 -73.533)
		(width 0.4572)
		(layer "In2.Cu")
		(net "P52V_HS1_VCAP")
	)
	(segment
		(start 277.9014 -73.533)
		(end 279.8064 -73.533)
		(width 0.4572)
		(layer "In2.Cu")
		(net "P52V_HS1_VCAP")
	)
	(segment
		(start 280.34996 -83.75396)
		(end 287.528 -90.932)
		(width 0.17272)
		(layer "F.Cu")
		(net "P52V_HS1_EN")
	)
	(segment
		(start 274.908264 -69.84492)
		(end 274.0914 -69.028056)
		(width 0.17272)
		(layer "F.Cu")
		(net "P52V_HS1_EN")
	)
	(segment
		(start 259.104638 -64.826642)
		(end 259.104638 -74.963528)
		(width 0.17272)
		(layer "F.Cu")
		(net "P52V_HS1_EN")
	)
	(segment
		(start 274.0914 -69.028056)
		(end 274.0914 -66.754248)
		(width 0.17272)
		(layer "F.Cu")
		(net "P52V_HS1_EN")
	)
	(segment
		(start 276.372066 -69.84492)
		(end 274.908264 -69.84492)
		(width 0.17272)
		(layer "F.Cu")
		(net "P52V_HS1_EN")
	)
	(segment
		(start 287.528 -90.932)
		(end 287.528 -93.218)
		(width 0.17272)
		(layer "F.Cu")
		(net "P52V_HS1_EN")
	)
	(segment
		(start 260.171184 -76.030074)
		(end 262.927846 -76.030074)
		(width 0.17272)
		(layer "F.Cu")
		(net "P52V_HS1_EN")
	)
	(segment
		(start 259.104638 -74.963528)
		(end 260.171184 -76.030074)
		(width 0.17272)
		(layer "F.Cu")
		(net "P52V_HS1_EN")
	)
	(segment
		(start 268.411452 -66.04)
		(end 264.440162 -62.06871)
		(width 0.17272)
		(layer "F.Cu")
		(net "P52V_HS1_EN")
	)
	(segment
		(start 261.86257 -62.06871)
		(end 259.104638 -64.826642)
		(width 0.17272)
		(layer "F.Cu")
		(net "P52V_HS1_EN")
	)
	(segment
		(start 264.440162 -62.06871)
		(end 261.86257 -62.06871)
		(width 0.17272)
		(layer "F.Cu")
		(net "P52V_HS1_EN")
	)
	(segment
		(start 270.651732 -83.75396)
		(end 280.34996 -83.75396)
		(width 0.17272)
		(layer "F.Cu")
		(net "P52V_HS1_EN")
	)
	(segment
		(start 262.927846 -76.030074)
		(end 270.651732 -83.75396)
		(width 0.17272)
		(layer "F.Cu")
		(net "P52V_HS1_EN")
	)
	(segment
		(start 273.377152 -66.04)
		(end 268.411452 -66.04)
		(width 0.17272)
		(layer "F.Cu")
		(net "P52V_HS1_EN")
	)
	(segment
		(start 387.223 -25.12695)
		(end 387.8834 -25.12695)
		(width 0.17272)
		(layer "F.Cu")
		(net "P52V_HS1_EN")
	)
	(segment
		(start 274.0914 -66.754248)
		(end 273.377152 -66.04)
		(width 0.17272)
		(layer "F.Cu")
		(net "P52V_HS1_EN")
	)
	(via
		(at 221.623382 -7.475728)
		(size 0.508)
		(drill 0.254)
		(layers "F.Cu" "B.Cu")
		(net "P52V_HS1_EN")
	)
	(via
		(at 387.8834 -25.12695)
		(size 0.508)
		(drill 0.254)
		(layers "F.Cu" "B.Cu")
		(net "P52V_HS1_EN")
	)
	(via
		(at 227.203 -100.711)
		(size 0.508)
		(drill 0.254)
		(layers "F.Cu" "B.Cu")
		(net "P52V_HS1_EN")
	)
	(via
		(at 258.3942 -97.9424)
		(size 0.508)
		(drill 0.254)
		(layers "F.Cu" "B.Cu")
		(net "P52V_HS1_EN")
	)
	(via
		(at 276.372066 -69.84492)
		(size 0.508)
		(drill 0.254)
		(layers "F.Cu" "B.Cu")
		(net "P52V_HS1_EN")
	)
	(via
		(at 258.3942 -81.915)
		(size 0.508)
		(drill 0.254)
		(layers "F.Cu" "B.Cu")
		(net "P52V_HS1_EN")
	)
	(via
		(at 286.9692 -67.4116)
		(size 0.508)
		(drill 0.254)
		(layers "F.Cu" "B.Cu")
		(net "P52V_HS1_EN")
	)
	(via
		(at 287.528 -93.218)
		(size 0.508)
		(drill 0.254)
		(layers "F.Cu" "B.Cu")
		(net "P52V_HS1_EN")
	)
	(segment
		(start 221.623382 -85.479382)
		(end 221.623382 -7.475728)
		(width 0.17272)
		(layer "B.Cu")
		(net "P52V_HS1_EN")
	)
	(segment
		(start 286.568896 -93.02496)
		(end 287.33496 -93.02496)
		(width 0.17272)
		(layer "B.Cu")
		(net "P52V_HS1_EN")
	)
	(segment
		(start 287.782 -67.4116)
		(end 286.9692 -67.4116)
		(width 0.17272)
		(layer "B.Cu")
		(net "P52V_HS1_EN")
	)
	(segment
		(start 226.1108 -89.9668)
		(end 221.623382 -85.479382)
		(width 0.17272)
		(layer "B.Cu")
		(net "P52V_HS1_EN")
	)
	(segment
		(start 289.724338 -69.353938)
		(end 287.782 -67.4116)
		(width 0.17272)
		(layer "B.Cu")
		(net "P52V_HS1_EN")
	)
	(segment
		(start 287.33496 -93.02496)
		(end 287.528 -93.218)
		(width 0.17272)
		(layer "B.Cu")
		(net "P52V_HS1_EN")
	)
	(segment
		(start 227.203 -100.711)
		(end 226.1108 -99.6188)
		(width 0.17272)
		(layer "B.Cu")
		(net "P52V_HS1_EN")
	)
	(segment
		(start 290.122356 -69.353938)
		(end 289.724338 -69.353938)
		(width 0.17272)
		(layer "B.Cu")
		(net "P52V_HS1_EN")
	)
	(segment
		(start 226.1108 -99.6188)
		(end 226.1108 -89.9668)
		(width 0.17272)
		(layer "B.Cu")
		(net "P52V_HS1_EN")
	)
	(segment
		(start 274.1041 -69.84492)
		(end 276.372066 -69.84492)
		(width 0.17272)
		(layer "B.Cu")
		(net "P52V_HS1_EN")
	)
	(segment
		(start 258.3942 -81.915)
		(end 258.3942 -97.9424)
		(width 0.17272)
		(layer "B.Cu")
		(net "P52V_HS1_EN")
	)
	(segment
		(start 266.788138 -72.681338)
		(end 269.390114 -72.681338)
		(width 0.12954)
		(layer "In2.Cu")
		(net "P52V_HS1_EN")
	)
	(segment
		(start 258.3942 -97.9424)
		(end 255.6256 -100.711)
		(width 0.12954)
		(layer "In2.Cu")
		(net "P52V_HS1_EN")
	)
	(segment
		(start 273.818096 -73.3298)
		(end 276.372066 -70.77583)
		(width 0.12954)
		(layer "In2.Cu")
		(net "P52V_HS1_EN")
	)
	(segment
		(start 270.038576 -73.3298)
		(end 273.818096 -73.3298)
		(width 0.12954)
		(layer "In2.Cu")
		(net "P52V_HS1_EN")
	)
	(segment
		(start 365.868204 -25.12695)
		(end 387.8834 -25.12695)
		(width 0.12954)
		(layer "In2.Cu")
		(net "P52V_HS1_EN")
	)
	(segment
		(start 255.6256 -100.711)
		(end 227.203 -100.711)
		(width 0.12954)
		(layer "In2.Cu")
		(net "P52V_HS1_EN")
	)
	(segment
		(start 286.9692 -67.4116)
		(end 286.9692 -68.6562)
		(width 0.12954)
		(layer "In2.Cu")
		(net "P52V_HS1_EN")
	)
	(segment
		(start 349.413068 -6.386068)
		(end 361.5944 -18.5674)
		(width 0.12954)
		(layer "In2.Cu")
		(net "P52V_HS1_EN")
	)
	(segment
		(start 361.5944 -20.853146)
		(end 365.868204 -25.12695)
		(width 0.12954)
		(layer "In2.Cu")
		(net "P52V_HS1_EN")
	)
	(segment
		(start 262.604504 -76.864972)
		(end 266.788138 -72.681338)
		(width 0.12954)
		(layer "In2.Cu")
		(net "P52V_HS1_EN")
	)
	(segment
		(start 276.646386 -69.5706)
		(end 276.372066 -69.84492)
		(width 0.12954)
		(layer "In2.Cu")
		(net "P52V_HS1_EN")
	)
	(segment
		(start 286.9692 -68.6562)
		(end 286.0548 -69.5706)
		(width 0.12954)
		(layer "In2.Cu")
		(net "P52V_HS1_EN")
	)
	(segment
		(start 221.623382 -7.475728)
		(end 222.713042 -6.386068)
		(width 0.12954)
		(layer "In2.Cu")
		(net "P52V_HS1_EN")
	)
	(segment
		(start 361.5944 -18.5674)
		(end 361.5944 -20.853146)
		(width 0.12954)
		(layer "In2.Cu")
		(net "P52V_HS1_EN")
	)
	(segment
		(start 286.0548 -69.5706)
		(end 276.646386 -69.5706)
		(width 0.12954)
		(layer "In2.Cu")
		(net "P52V_HS1_EN")
	)
	(segment
		(start 258.3942 -81.915)
		(end 262.604504 -77.704696)
		(width 0.12954)
		(layer "In2.Cu")
		(net "P52V_HS1_EN")
	)
	(segment
		(start 276.372066 -70.77583)
		(end 276.372066 -69.84492)
		(width 0.12954)
		(layer "In2.Cu")
		(net "P52V_HS1_EN")
	)
	(segment
		(start 269.390114 -72.681338)
		(end 270.038576 -73.3298)
		(width 0.12954)
		(layer "In2.Cu")
		(net "P52V_HS1_EN")
	)
	(segment
		(start 222.713042 -6.386068)
		(end 349.413068 -6.386068)
		(width 0.12954)
		(layer "In2.Cu")
		(net "P52V_HS1_EN")
	)
	(segment
		(start 262.604504 -77.704696)
		(end 262.604504 -76.864972)
		(width 0.12954)
		(layer "In2.Cu")
		(net "P52V_HS1_EN")
	)
	(segment
		(start 280.05659 -74.66076)
		(end 280.67635 -74.041)
		(width 0.17272)
		(layer "F.Cu")
		(net "P52V_HS1_ADR0")
	)
	(segment
		(start 278.88311 -74.66076)
		(end 280.05659 -74.66076)
		(width 0.17272)
		(layer "F.Cu")
		(net "P52V_HS1_ADR0")
	)
	(segment
		(start 277.7744 -71.3486)
		(end 277.7744 -73.55205)
		(width 0.17272)
		(layer "F.Cu")
		(net "P52V_HS1_ADR0")
	)
	(segment
		(start 277.3172 -69.941186)
		(end 276.723094 -69.34708)
		(width 0.17272)
		(layer "F.Cu")
		(net "P52V_HS1_ADR0")
	)
	(segment
		(start 277.3172 -70.8914)
		(end 277.3172 -69.941186)
		(width 0.17272)
		(layer "F.Cu")
		(net "P52V_HS1_ADR0")
	)
	(segment
		(start 276.723094 -69.34708)
		(end 275.1074 -69.34708)
		(width 0.17272)
		(layer "F.Cu")
		(net "P52V_HS1_ADR0")
	)
	(segment
		(start 277.7744 -73.55205)
		(end 278.26335 -74.041)
		(width 0.17272)
		(layer "F.Cu")
		(net "P52V_HS1_ADR0")
	)
	(segment
		(start 280.67635 -74.041)
		(end 280.67635 -73.406)
		(width 0.17272)
		(layer "F.Cu")
		(net "P52V_HS1_ADR0")
	)
	(segment
		(start 277.3172 -70.8914)
		(end 277.7744 -71.3486)
		(width 0.17272)
		(layer "F.Cu")
		(net "P52V_HS1_ADR0")
	)
	(segment
		(start 278.26335 -74.041)
		(end 278.88311 -74.66076)
		(width 0.17272)
		(layer "F.Cu")
		(net "P52V_HS1_ADR0")
	)
	(via
		(at 277.3172 -70.8914)
		(size 0.762)
		(drill 0.381)
		(layers "F.Cu" "B.Cu")
		(net "P52V_HS1_ADR0")
	)
	(via
		(at 275.1074 -69.34708)
		(size 0.508)
		(drill 0.254)
		(layers "F.Cu" "B.Cu")
		(net "P52V_HS1_ADR0")
	)
	(via
		(at 291.9984 -64.77)
		(size 0.508)
		(drill 0.254)
		(layers "F.Cu" "B.Cu")
		(net "P52V_HS1_ADR0")
	)
	(via
		(at 280.67635 -73.406)
		(size 0.508)
		(drill 0.254)
		(layers "F.Cu" "B.Cu")
		(net "P52V_HS1_ADR0")
	)
	(segment
		(start 274.1041 -69.34708)
		(end 275.1074 -69.34708)
		(width 0.17272)
		(layer "B.Cu")
		(net "P52V_HS1_ADR0")
	)
	(segment
		(start 291.77234 -66.703956)
		(end 291.77234 -64.99606)
		(width 0.17272)
		(layer "B.Cu")
		(net "P52V_HS1_ADR0")
	)
	(segment
		(start 291.9984 -63.39205)
		(end 292.61816 -62.77229)
		(width 0.17272)
		(layer "B.Cu")
		(net "P52V_HS1_ADR0")
	)
	(segment
		(start 292.61816 -62.77229)
		(end 292.61816 -61.85281)
		(width 0.17272)
		(layer "B.Cu")
		(net "P52V_HS1_ADR0")
	)
	(segment
		(start 291.9984 -63.39205)
		(end 291.9984 -64.77)
		(width 0.17272)
		(layer "B.Cu")
		(net "P52V_HS1_ADR0")
	)
	(segment
		(start 291.77234 -64.99606)
		(end 291.9984 -64.77)
		(width 0.17272)
		(layer "B.Cu")
		(net "P52V_HS1_ADR0")
	)
	(segment
		(start 292.61816 -61.85281)
		(end 291.9984 -61.23305)
		(width 0.17272)
		(layer "B.Cu")
		(net "P52V_HS1_ADR0")
	)
	(segment
		(start 288.518854 -71.8058)
		(end 289.3568 -70.967854)
		(width 0.12954)
		(layer "In2.Cu")
		(net "P52V_HS1_ADR0")
	)
	(segment
		(start 280.67635 -72.81545)
		(end 282.30703 -71.18477)
		(width 0.12954)
		(layer "In2.Cu")
		(net "P52V_HS1_ADR0")
	)
	(segment
		(start 289.3568 -65.98666)
		(end 290.57346 -64.77)
		(width 0.12954)
		(layer "In2.Cu")
		(net "P52V_HS1_ADR0")
	)
	(segment
		(start 290.57346 -64.77)
		(end 291.9984 -64.77)
		(width 0.12954)
		(layer "In2.Cu")
		(net "P52V_HS1_ADR0")
	)
	(segment
		(start 285.92145 -71.18477)
		(end 286.54248 -71.8058)
		(width 0.12954)
		(layer "In2.Cu")
		(net "P52V_HS1_ADR0")
	)
	(segment
		(start 289.3568 -70.967854)
		(end 289.3568 -65.98666)
		(width 0.12954)
		(layer "In2.Cu")
		(net "P52V_HS1_ADR0")
	)
	(segment
		(start 282.30703 -71.18477)
		(end 285.92145 -71.18477)
		(width 0.12954)
		(layer "In2.Cu")
		(net "P52V_HS1_ADR0")
	)
	(segment
		(start 286.54248 -71.8058)
		(end 288.518854 -71.8058)
		(width 0.12954)
		(layer "In2.Cu")
		(net "P52V_HS1_ADR0")
	)
	(segment
		(start 280.67635 -73.406)
		(end 280.67635 -72.81545)
		(width 0.12954)
		(layer "In2.Cu")
		(net "P52V_HS1_ADR0")
	)
	(segment
		(start 441.369958 -44.13504)
		(end 440.309 -44.13504)
		(width 0.4572)
		(layer "F.Cu")
		(net "GND")
	)
	(segment
		(start 414.946084 -47.949358)
		(end 415.331402 -47.56404)
		(width 0.4572)
		(layer "F.Cu")
		(net "GND")
	)
	(segment
		(start 415.37636 -38.75659)
		(end 415.29 -38.84295)
		(width 0.4572)
		(layer "F.Cu")
		(net "GND")
	)
	(segment
		(start 182.753 -80.137)
		(end 182.992014 -79.897986)
		(width 0.4572)
		(layer "F.Cu")
		(net "GND")
	)
	(segment
		(start 415.40938 -32.16656)
		(end 416.550602 -31.025338)
		(width 0.254)
		(layer "F.Cu")
		(net "GND")
	)
	(segment
		(start 439.9534 -26.543)
		(end 438.7088 -26.543)
		(width 0.4572)
		(layer "F.Cu")
		(net "GND")
	)
	(segment
		(start 437.62295 -45.593)
		(end 436.9054 -45.593)
		(width 0.4572)
		(layer "F.Cu")
		(net "GND")
	)
	(segment
		(start 418.550598 -30.152848)
		(end 418.550598 -30.940248)
		(width 0.17272)
		(layer "F.Cu")
		(net "GND")
	)
	(segment
		(start 264.58545 -48.78705)
		(end 263.5504 -48.78705)
		(width 0.4572)
		(layer "F.Cu")
		(net "GND")
	)
	(segment
		(start 433.05095 -32.893)
		(end 432.44135 -32.893)
		(width 0.4572)
		(layer "F.Cu")
		(net "GND")
	)
	(segment
		(start 447.82105 -46.101)
		(end 447.82105 -45.4406)
		(width 0.4572)
		(layer "F.Cu")
		(net "GND")
	)
	(segment
		(start 50.1015 -27.700986)
		(end 50.9524 -27.700986)
		(width 0.4572)
		(layer "F.Cu")
		(net "GND")
	)
	(segment
		(start 427.62805 -43.18)
		(end 428.237904 -43.18)
		(width 0.4572)
		(layer "F.Cu")
		(net "GND")
	)
	(segment
		(start 427.62805 -45.974)
		(end 428.237904 -45.974)
		(width 0.4572)
		(layer "F.Cu")
		(net "GND")
	)
	(segment
		(start 440.362594 -40.426894)
		(end 439.270394 -40.426894)
		(width 0.3556)
		(layer "F.Cu")
		(net "GND")
	)
	(segment
		(start 174.85995 -45.339)
		(end 174.85995 -46.68139)
		(width 0.4572)
		(layer "F.Cu")
		(net "GND")
	)
	(segment
		(start 414.42259 -47.949358)
		(end 414.946084 -47.949358)
		(width 0.4572)
		(layer "F.Cu")
		(net "GND")
	)
	(segment
		(start 419.7604 -53.848)
		(end 418.115496 -53.848)
		(width 0.4572)
		(layer "F.Cu")
		(net "GND")
	)
	(segment
		(start 417.449 -38.84295)
		(end 415.29 -38.84295)
		(width 0.3556)
		(layer "F.Cu")
		(net "GND")
	)
	(segment
		(start 427.62805 -37.592)
		(end 428.237904 -37.592)
		(width 0.4572)
		(layer "F.Cu")
		(net "GND")
	)
	(segment
		(start 265.01344 -50.499518)
		(end 265.01344 -50.148998)
		(width 0.4572)
		(layer "F.Cu")
		(net "GND")
	)
	(segment
		(start 444.643002 -47.56404)
		(end 445.58204 -47.56404)
		(width 0.4572)
		(layer "F.Cu")
		(net "GND")
	)
	(segment
		(start 429.2854 -34.53765)
		(end 429.9204 -34.53765)
		(width 0.4572)
		(layer "F.Cu")
		(net "GND")
	)
	(segment
		(start 427.62805 -41.783)
		(end 428.237904 -41.783)
		(width 0.4572)
		(layer "F.Cu")
		(net "GND")
	)
	(segment
		(start 450.845682 -88.465152)
		(end 451.455282 -88.465152)
		(width 0.381)
		(layer "F.Cu")
		(net "GND")
	)
	(segment
		(start 416.550602 -31.025338)
		(end 416.550602 -30.152848)
		(width 0.254)
		(layer "F.Cu")
		(net "GND")
	)
	(segment
		(start 176.241202 -48.19904)
		(end 177.079402 -48.19904)
		(width 0.4572)
		(layer "F.Cu")
		(net "GND")
	)
	(segment
		(start 415.37636 -37.862002)
		(end 415.37636 -38.75659)
		(width 0.4572)
		(layer "F.Cu")
		(net "GND")
	)
	(segment
		(start 165.989 -83.03895)
		(end 167.005 -83.03895)
		(width 0.4572)
		(layer "F.Cu")
		(net "GND")
	)
	(segment
		(start 448.660266 -84.857082)
		(end 447.73342 -84.857082)
		(width 0.1778)
		(layer "F.Cu")
		(net "GND")
	)
	(segment
		(start 416.814 -52.546504)
		(end 416.814 -51.96205)
		(width 0.4572)
		(layer "F.Cu")
		(net "GND")
	)
	(segment
		(start 413.11195 -43.815)
		(end 412.2674 -43.815)
		(width 0.4572)
		(layer "F.Cu")
		(net "GND")
	)
	(segment
		(start 448.856354 -84.660994)
		(end 448.660266 -84.857082)
		(width 0.1778)
		(layer "F.Cu")
		(net "GND")
	)
	(segment
		(start 432.32705 -52.6161)
		(end 432.32705 -52.197)
		(width 0.4572)
		(layer "F.Cu")
		(net "GND")
	)
	(segment
		(start 449.59905 -44.196)
		(end 450.215 -44.196)
		(width 0.4572)
		(layer "F.Cu")
		(net "GND")
	)
	(segment
		(start 265.01344 -49.21504)
		(end 264.58545 -48.78705)
		(width 0.4572)
		(layer "F.Cu")
		(net "GND")
	)
	(segment
		(start 427.62805 -40.386)
		(end 428.237904 -40.386)
		(width 0.4572)
		(layer "F.Cu")
		(net "GND")
	)
	(segment
		(start 428.0154 -31.74365)
		(end 428.0154 -32.385)
		(width 0.4572)
		(layer "F.Cu")
		(net "GND")
	)
	(segment
		(start 182.992014 -79.897986)
		(end 182.992014 -79.43596)
		(width 0.4572)
		(layer "F.Cu")
		(net "GND")
	)
	(segment
		(start 438.105296 -51.36896)
		(end 438.105296 -52.140104)
		(width 0.4572)
		(layer "F.Cu")
		(net "GND")
	)
	(segment
		(start 418.115496 -53.848)
		(end 416.814 -52.546504)
		(width 0.4572)
		(layer "F.Cu")
		(net "GND")
	)
	(segment
		(start 432.54295 -52.832)
		(end 432.32705 -52.6161)
		(width 0.4572)
		(layer "F.Cu")
		(net "GND")
	)
	(segment
		(start 413.11195 -45.212)
		(end 412.2674 -45.212)
		(width 0.4572)
		(layer "F.Cu")
		(net "GND")
	)
	(segment
		(start 433.05095 -34.163)
		(end 433.05095 -32.893)
		(width 0.4572)
		(layer "F.Cu")
		(net "GND")
	)
	(segment
		(start 439.166 -46.609)
		(end 438.42305 -46.609)
		(width 0.4572)
		(layer "F.Cu")
		(net "GND")
	)
	(segment
		(start 50.97399 -31.242)
		(end 52.0954 -31.242)
		(width 0.4572)
		(layer "F.Cu")
		(net "GND")
	)
	(segment
		(start 261.6454 -52.705)
		(end 262.21944 -52.13096)
		(width 0.4572)
		(layer "F.Cu")
		(net "GND")
	)
	(segment
		(start 427.62805 -38.989)
		(end 428.237904 -38.989)
		(width 0.4572)
		(layer "F.Cu")
		(net "GND")
	)
	(segment
		(start 405.79802 -29.21)
		(end 405.11222 -29.21)
		(width 0.4572)
		(layer "F.Cu")
		(net "GND")
	)
	(segment
		(start 449.72605 -34.163)
		(end 449.72605 -34.798)
		(width 0.4572)
		(layer "F.Cu")
		(net "GND")
	)
	(segment
		(start 173.269402 -46.80204)
		(end 174.9806 -46.80204)
		(width 0.4572)
		(layer "F.Cu")
		(net "GND")
	)
	(segment
		(start 422.148 -27.53995)
		(end 422.148 -26.924)
		(width 0.4572)
		(layer "F.Cu")
		(net "GND")
	)
	(segment
		(start 171.266104 -80.20304)
		(end 170.434 -80.20304)
		(width 0.4572)
		(layer "F.Cu")
		(net "GND")
	)
	(segment
		(start 169.672 -79.121)
		(end 169.672 -80.0354)
		(width 0.4572)
		(layer "F.Cu")
		(net "GND")
	)
	(segment
		(start 434.60035 -48.133)
		(end 434.60035 -47.498)
		(width 0.4572)
		(layer "F.Cu")
		(net "GND")
	)
	(segment
		(start 448.83705 -38.862)
		(end 448.83705 -39.492936)
		(width 0.4572)
		(layer "F.Cu")
		(net "GND")
	)
	(segment
		(start 262.21944 -52.13096)
		(end 263.381998 -52.13096)
		(width 0.4572)
		(layer "F.Cu")
		(net "GND")
	)
	(segment
		(start 441.63996 -47.768002)
		(end 441.63996 -48.641)
		(width 0.4572)
		(layer "F.Cu")
		(net "GND")
	)
	(segment
		(start 423.69105 -48.133)
		(end 423.69105 -47.371)
		(width 0.4572)
		(layer "F.Cu")
		(net "GND")
	)
	(segment
		(start 164.860986 -80.58404)
		(end 164.860986 -79.756)
		(width 0.4572)
		(layer "F.Cu")
		(net "GND")
	)
	(segment
		(start 263.381998 -52.13096)
		(end 265.01344 -50.499518)
		(width 0.4572)
		(layer "F.Cu")
		(net "GND")
	)
	(segment
		(start 265.01344 -50.148998)
		(end 265.01344 -49.21504)
		(width 0.4572)
		(layer "F.Cu")
		(net "GND")
	)
	(segment
		(start 440.362594 -36.489894)
		(end 439.270394 -36.489894)
		(width 0.3556)
		(layer "F.Cu")
		(net "GND")
	)
	(segment
		(start 152.76195 -77.55255)
		(end 152.76195 -76.2)
		(width 0.4572)
		(layer "F.Cu")
		(net "GND")
	)
	(segment
		(start 34.20237 -30.607)
		(end 34.88817 -30.607)
		(width 0.4572)
		(layer "F.Cu")
		(net "GND")
	)
	(segment
		(start 388.8994 -27.559)
		(end 387.8834 -27.559)
		(width 0.4572)
		(layer "F.Cu")
		(net "GND")
	)
	(segment
		(start 419.35146 -30.996636)
		(end 419.050724 -30.6959)
		(width 0.17272)
		(layer "F.Cu")
		(net "GND")
	)
	(segment
		(start 291.19195 -63.881)
		(end 290.449 -63.881)
		(width 0.4572)
		(layer "F.Cu")
		(net "GND")
	)
	(segment
		(start 389.8519 -24.623014)
		(end 389.0264 -24.623014)
		(width 0.4572)
		(layer "F.Cu")
		(net "GND")
	)
	(segment
		(start 419.050724 -30.6959)
		(end 419.050724 -30.152848)
		(width 0.17272)
		(layer "F.Cu")
		(net "GND")
	)
	(segment
		(start 415.40938 -33.2359)
		(end 415.40938 -32.16656)
		(width 0.254)
		(layer "F.Cu")
		(net "GND")
	)
	(segment
		(start 185.928 -78.88605)
		(end 186.563 -78.88605)
		(width 0.4572)
		(layer "F.Cu")
		(net "GND")
	)
	(segment
		(start 447.663316 -82.01787)
		(end 447.663316 -81.368138)
		(width 0.4572)
		(layer "F.Cu")
		(net "GND")
	)
	(segment
		(start 174.85995 -46.68139)
		(end 174.9806 -46.80204)
		(width 0.4572)
		(layer "F.Cu")
		(net "GND")
	)
	(segment
		(start 448.83705 -42.799)
		(end 449.446904 -42.799)
		(width 0.4572)
		(layer "F.Cu")
		(net "GND")
	)
	(segment
		(start 168.529 -79.121)
		(end 168.529 -79.86395)
		(width 0.4572)
		(layer "F.Cu")
		(net "GND")
	)
	(segment
		(start 448.199002 -47.56404)
		(end 449.072 -47.56404)
		(width 0.4572)
		(layer "F.Cu")
		(net "GND")
	)
	(segment
		(start 420.27221 -26.00452)
		(end 420.8907 -26.00452)
		(width 0.254)
		(layer "F.Cu")
		(net "GND")
	)
	(segment
		(start 152.82545 -77.61605)
		(end 152.76195 -77.55255)
		(width 0.4572)
		(layer "F.Cu")
		(net "GND")
	)
	(segment
		(start 427.62805 -44.577)
		(end 428.237904 -44.577)
		(width 0.4572)
		(layer "F.Cu")
		(net "GND")
	)
	(via
		(at 443.206886 -87.71509)
		(size 0.508)
		(drill 0.254)
		(layers "F.Cu" "B.Cu")
		(net "GND")
	)
	(via
		(at 81.534 -16.002)
		(size 0.508)
		(drill 0.254)
		(layers "F.Cu" "B.Cu")
		(net "GND")
	)
	(via
		(at 410.4132 -19.4818)
		(size 0.508)
		(drill 0.254)
		(layers "F.Cu" "B.Cu")
		(net "GND")
	)
	(via
		(at 256.54 -58.801)
		(size 0.508)
		(drill 0.254)
		(layers "F.Cu" "B.Cu")
		(net "GND")
	)
	(via
		(at 408.7114 -21.717)
		(size 0.508)
		(drill 0.254)
		(layers "F.Cu" "B.Cu")
		(net "GND")
	)
	(via
		(at 426.510704 -49.46904)
		(size 0.508)
		(drill 0.254)
		(layers "F.Cu" "B.Cu")
		(net "GND")
	)
	(via
		(at 475.236032 -121.186448)
		(size 0.508)
		(drill 0.254)
		(layers "F.Cu" "B.Cu")
		(net "GND")
	)
	(via
		(at 122.287284 -86.668864)
		(size 0.508)
		(drill 0.254)
		(layers "F.Cu" "B.Cu")
		(net "GND")
	)
	(via
		(at 243.75872 -102.23754)
		(size 0.508)
		(drill 0.254)
		(layers "F.Cu" "B.Cu")
		(net "GND")
	)
	(via
		(at 247.523 -58.039)
		(size 0.508)
		(drill 0.254)
		(layers "F.Cu" "B.Cu")
		(net "GND")
	)
	(via
		(at 203.11872 -102.23754)
		(size 0.508)
		(drill 0.254)
		(layers "F.Cu" "B.Cu")
		(net "GND")
	)
	(via
		(at 438.7088 -26.543)
		(size 0.508)
		(drill 0.254)
		(layers "F.Cu" "B.Cu")
		(net "GND")
	)
	(via
		(at 475.236032 -44.986448)
		(size 0.508)
		(drill 0.254)
		(layers "F.Cu" "B.Cu")
		(net "GND")
	)
	(via
		(at 166.315136 -25.146)
		(size 0.508)
		(drill 0.254)
		(layers "F.Cu" "B.Cu")
		(net "GND")
	)
	(via
		(at 182.88 -58.039)
		(size 0.508)
		(drill 0.254)
		(layers "F.Cu" "B.Cu")
		(net "GND")
	)
	(via
		(at 352.268028 -130.692906)
		(size 0.508)
		(drill 0.254)
		(layers "F.Cu" "B.Cu")
		(net "GND")
	)
	(via
		(at 0.766572 -72.11822)
		(size 0.508)
		(drill 0.254)
		(layers "F.Cu" "B.Cu")
		(net "GND")
	)
	(via
		(at 406.9334 -22.606)
		(size 0.508)
		(drill 0.254)
		(layers "F.Cu" "B.Cu")
		(net "GND")
	)
	(via
		(at 343.48674 -9.878822)
		(size 0.508)
		(drill 0.254)
		(layers "F.Cu" "B.Cu")
		(net "GND")
	)
	(via
		(at 316.46622 -91.223592)
		(size 0.508)
		(drill 0.254)
		(layers "F.Cu" "B.Cu")
		(net "GND")
	)
	(via
		(at 409.9814 -27.94)
		(size 0.508)
		(drill 0.254)
		(layers "F.Cu" "B.Cu")
		(net "GND")
	)
	(via
		(at 280.924 -92.583)
		(size 0.508)
		(drill 0.254)
		(layers "F.Cu" "B.Cu")
		(net "GND")
	)
	(via
		(at 0.766572 -148.31822)
		(size 0.508)
		(drill 0.254)
		(layers "F.Cu" "B.Cu")
		(net "GND")
	)
	(via
		(at 273.685 -25.146)
		(size 0.508)
		(drill 0.254)
		(layers "F.Cu" "B.Cu")
		(net "GND")
	)
	(via
		(at 449.446904 -42.799)
		(size 0.508)
		(drill 0.254)
		(layers "F.Cu" "B.Cu")
		(net "GND")
	)
	(via
		(at 327.434702 -95.329248)
		(size 0.508)
		(drill 0.254)
		(layers "F.Cu" "B.Cu")
		(net "GND")
	)
	(via
		(at 407.9494 -17.653)
		(size 0.508)
		(drill 0.254)
		(layers "F.Cu" "B.Cu")
		(net "GND")
	)
	(via
		(at 128.250442 -9.513824)
		(size 0.508)
		(drill 0.254)
		(layers "F.Cu" "B.Cu")
		(net "GND")
	)
	(via
		(at 164.029136 -25.146)
		(size 0.508)
		(drill 0.254)
		(layers "F.Cu" "B.Cu")
		(net "GND")
	)
	(via
		(at 185.928 -58.801)
		(size 0.508)
		(drill 0.254)
		(layers "F.Cu" "B.Cu")
		(net "GND")
	)
	(via
		(at 177.71872 -102.23754)
		(size 0.508)
		(drill 0.254)
		(layers "F.Cu" "B.Cu")
		(net "GND")
	)
	(via
		(at 80.712564 -9.959594)
		(size 0.508)
		(drill 0.254)
		(layers "F.Cu" "B.Cu")
		(net "GND")
	)
	(via
		(at 0.766572 -77.19822)
		(size 0.508)
		(drill 0.254)
		(layers "F.Cu" "B.Cu")
		(net "GND")
	)
	(via
		(at 183.642 -58.039)
		(size 0.508)
		(drill 0.254)
		(layers "F.Cu" "B.Cu")
		(net "GND")
	)
	(via
		(at 58.392314 -23.44547)
		(size 0.508)
		(drill 0.254)
		(layers "F.Cu" "B.Cu")
		(net "GND")
	)
	(via
		(at 318.49822 -96.430592)
		(size 0.508)
		(drill 0.254)
		(layers "F.Cu" "B.Cu")
		(net "GND")
	)
	(via
		(at 0.766572 -107.67822)
		(size 0.508)
		(drill 0.254)
		(layers "F.Cu" "B.Cu")
		(net "GND")
	)
	(via
		(at 345.34348 -102.34676)
		(size 0.508)
		(drill 0.254)
		(layers "F.Cu" "B.Cu")
		(net "GND")
	)
	(via
		(at 87.734648 -125.734318)
		(size 0.508)
		(drill 0.254)
		(layers "F.Cu" "B.Cu")
		(net "GND")
	)
	(via
		(at 377.423172 -28.136342)
		(size 0.508)
		(drill 0.254)
		(layers "F.Cu" "B.Cu")
		(net "GND")
	)
	(via
		(at 275.971 -10.287)
		(size 0.508)
		(drill 0.254)
		(layers "F.Cu" "B.Cu")
		(net "GND")
	)
	(via
		(at 142.15872 -102.23754)
		(size 0.508)
		(drill 0.254)
		(layers "F.Cu" "B.Cu")
		(net "GND")
	)
	(via
		(at 328.196702 -96.091248)
		(size 0.508)
		(drill 0.254)
		(layers "F.Cu" "B.Cu")
		(net "GND")
	)
	(via
		(at 164.791136 -24.384)
		(size 0.508)
		(drill 0.254)
		(layers "F.Cu" "B.Cu")
		(net "GND")
	)
	(via
		(at 442.495686 -84.84489)
		(size 0.508)
		(drill 0.254)
		(layers "F.Cu" "B.Cu")
		(net "GND")
	)
	(via
		(at 387.8834 -27.559)
		(size 0.508)
		(drill 0.254)
		(layers "F.Cu" "B.Cu")
		(net "GND")
	)
	(via
		(at 460.66329 -17.535398)
		(size 0.508)
		(drill 0.254)
		(layers "F.Cu" "B.Cu")
		(net "GND")
	)
	(via
		(at 87.734648 -130.814318)
		(size 0.508)
		(drill 0.254)
		(layers "F.Cu" "B.Cu")
		(net "GND")
	)
	(via
		(at 445.42329 -17.535398)
		(size 0.508)
		(drill 0.254)
		(layers "F.Cu" "B.Cu")
		(net "GND")
	)
	(via
		(at 428.0154 -32.385)
		(size 0.508)
		(drill 0.254)
		(layers "F.Cu" "B.Cu")
		(net "GND")
	)
	(via
		(at 116.572284 -86.668864)
		(size 0.508)
		(drill 0.254)
		(layers "F.Cu" "B.Cu")
		(net "GND")
	)
	(via
		(at 406.9334 -17.653)
		(size 0.508)
		(drill 0.254)
		(layers "F.Cu" "B.Cu")
		(net "GND")
	)
	(via
		(at 440.3344 -98.425)
		(size 0.508)
		(drill 0.254)
		(layers "F.Cu" "B.Cu")
		(net "GND")
	)
	(via
		(at 442.495686 -86.97849)
		(size 0.508)
		(drill 0.254)
		(layers "F.Cu" "B.Cu")
		(net "GND")
	)
	(via
		(at 0.766572 -31.47822)
		(size 0.508)
		(drill 0.254)
		(layers "F.Cu" "B.Cu")
		(net "GND")
	)
	(via
		(at 443.206886 -87.00389)
		(size 0.508)
		(drill 0.254)
		(layers "F.Cu" "B.Cu")
		(net "GND")
	)
	(via
		(at 387.560566 -170.885612)
		(size 0.508)
		(drill 0.254)
		(layers "F.Cu" "B.Cu")
		(net "GND")
	)
	(via
		(at 192.95872 -102.23754)
		(size 0.508)
		(drill 0.254)
		(layers "F.Cu" "B.Cu")
		(net "GND")
	)
	(via
		(at 444.9064 -59.182)
		(size 0.508)
		(drill 0.254)
		(layers "F.Cu" "B.Cu")
		(net "GND")
	)
	(via
		(at 451.13956 -92.55887)
		(size 0.508)
		(drill 0.254)
		(layers "F.Cu" "B.Cu")
		(net "GND")
	)
	(via
		(at 475.236032 -75.466448)
		(size 0.508)
		(drill 0.254)
		(layers "F.Cu" "B.Cu")
		(net "GND")
	)
	(via
		(at 410.4132 -20.2438)
		(size 0.508)
		(drill 0.254)
		(layers "F.Cu" "B.Cu")
		(net "GND")
	)
	(via
		(at 428.237904 -41.783)
		(size 0.508)
		(drill 0.254)
		(layers "F.Cu" "B.Cu")
		(net "GND")
	)
	(via
		(at 115.810284 -90.732864)
		(size 0.508)
		(drill 0.254)
		(layers "F.Cu" "B.Cu")
		(net "GND")
	)
	(via
		(at 450.50329 -17.535398)
		(size 0.508)
		(drill 0.254)
		(layers "F.Cu" "B.Cu")
		(net "GND")
	)
	(via
		(at 272.923 -10.287)
		(size 0.508)
		(drill 0.254)
		(layers "F.Cu" "B.Cu")
		(net "GND")
	)
	(via
		(at 453.122538 -61.670692)
		(size 0.508)
		(drill 0.254)
		(layers "F.Cu" "B.Cu")
		(net "GND")
	)
	(via
		(at 165.553136 -25.146)
		(size 0.508)
		(drill 0.254)
		(layers "F.Cu" "B.Cu")
		(net "GND")
	)
	(via
		(at 289.47872 -102.23754)
		(size 0.508)
		(drill 0.254)
		(layers "F.Cu" "B.Cu")
		(net "GND")
	)
	(via
		(at 412.2674 -43.815)
		(size 0.508)
		(drill 0.254)
		(layers "F.Cu" "B.Cu")
		(net "GND")
	)
	(via
		(at 325.03872 -102.23754)
		(size 0.508)
		(drill 0.254)
		(layers "F.Cu" "B.Cu")
		(net "GND")
	)
	(via
		(at 249.809 -58.801)
		(size 0.508)
		(drill 0.254)
		(layers "F.Cu" "B.Cu")
		(net "GND")
	)
	(via
		(at 182.88 -58.801)
		(size 0.508)
		(drill 0.254)
		(layers "F.Cu" "B.Cu")
		(net "GND")
	)
	(via
		(at 377.423172 -26.612342)
		(size 0.508)
		(drill 0.254)
		(layers "F.Cu" "B.Cu")
		(net "GND")
	)
	(via
		(at 408.235404 -165.213792)
		(size 0.508)
		(drill 0.254)
		(layers "F.Cu" "B.Cu")
		(net "GND")
	)
	(via
		(at 442.1124 -61.087)
		(size 0.508)
		(drill 0.254)
		(layers "F.Cu" "B.Cu")
		(net "GND")
	)
	(via
		(at 164.029136 -10.287)
		(size 0.508)
		(drill 0.254)
		(layers "F.Cu" "B.Cu")
		(net "GND")
	)
	(via
		(at 310.099964 -9.774428)
		(size 0.508)
		(drill 0.254)
		(layers "F.Cu" "B.Cu")
		(net "GND")
	)
	(via
		(at 440.127644 -14.849094)
		(size 0.508)
		(drill 0.254)
		(layers "F.Cu" "B.Cu")
		(net "GND")
	)
	(via
		(at 25.757124 -0.772668)
		(size 0.508)
		(drill 0.254)
		(layers "F.Cu" "B.Cu")
		(net "GND")
	)
	(via
		(at 293.2684 -81.5467)
		(size 0.508)
		(drill 0.254)
		(layers "F.Cu" "B.Cu")
		(net "GND")
	)
	(via
		(at 443.843664 -89.361518)
		(size 0.508)
		(drill 0.254)
		(layers "F.Cu" "B.Cu")
		(net "GND")
	)
	(via
		(at 122.287284 -85.906864)
		(size 0.508)
		(drill 0.254)
		(layers "F.Cu" "B.Cu")
		(net "GND")
	)
	(via
		(at 406.9334 -20.828)
		(size 0.508)
		(drill 0.254)
		(layers "F.Cu" "B.Cu")
		(net "GND")
	)
	(via
		(at 0.766572 -36.55822)
		(size 0.508)
		(drill 0.254)
		(layers "F.Cu" "B.Cu")
		(net "GND")
	)
	(via
		(at 247.523 -58.801)
		(size 0.508)
		(drill 0.254)
		(layers "F.Cu" "B.Cu")
		(net "GND")
	)
	(via
		(at 475.236032 -111.026448)
		(size 0.508)
		(drill 0.254)
		(layers "F.Cu" "B.Cu")
		(net "GND")
	)
	(via
		(at 165.553136 -11.049)
		(size 0.508)
		(drill 0.254)
		(layers "F.Cu" "B.Cu")
		(net "GND")
	)
	(via
		(at 443.79769 -91.329256)
		(size 0.508)
		(drill 0.254)
		(layers "F.Cu" "B.Cu")
		(net "GND")
	)
	(via
		(at 449.72605 -34.798)
		(size 0.508)
		(drill 0.254)
		(layers "F.Cu" "B.Cu")
		(net "GND")
	)
	(via
		(at 79.236824 -165.486588)
		(size 0.508)
		(drill 0.254)
		(layers "F.Cu" "B.Cu")
		(net "GND")
	)
	(via
		(at 192.659 -58.801)
		(size 0.508)
		(drill 0.254)
		(layers "F.Cu" "B.Cu")
		(net "GND")
	)
	(via
		(at 249.047 -58.801)
		(size 0.508)
		(drill 0.254)
		(layers "F.Cu" "B.Cu")
		(net "GND")
	)
	(via
		(at 57.376314 -23.44547)
		(size 0.508)
		(drill 0.254)
		(layers "F.Cu" "B.Cu")
		(net "GND")
	)
	(via
		(at 119.112284 -85.906864)
		(size 0.508)
		(drill 0.254)
		(layers "F.Cu" "B.Cu")
		(net "GND")
	)
	(via
		(at 315.70422 -90.461592)
		(size 0.508)
		(drill 0.254)
		(layers "F.Cu" "B.Cu")
		(net "GND")
	)
	(via
		(at 152.31872 -102.23754)
		(size 0.508)
		(drill 0.254)
		(layers "F.Cu" "B.Cu")
		(net "GND")
	)
	(via
		(at 342.72474 -9.878822)
		(size 0.508)
		(drill 0.254)
		(layers "F.Cu" "B.Cu")
		(net "GND")
	)
	(via
		(at 64.713612 -170.885866)
		(size 0.508)
		(drill 0.254)
		(layers "F.Cu" "B.Cu")
		(net "GND")
	)
	(via
		(at 152.82545 -77.61605)
		(size 0.508)
		(drill 0.254)
		(layers "F.Cu" "B.Cu")
		(net "GND")
	)
	(via
		(at 409.9814 -33.02)
		(size 0.508)
		(drill 0.254)
		(layers "F.Cu" "B.Cu")
		(net "GND")
	)
	(via
		(at 167.005 -83.03895)
		(size 0.508)
		(drill 0.254)
		(layers "F.Cu" "B.Cu")
		(net "GND")
	)
	(via
		(at 443.79769 -94.332806)
		(size 0.508)
		(drill 0.254)
		(layers "F.Cu" "B.Cu")
		(net "GND")
	)
	(via
		(at 408.7114 -16.764)
		(size 0.508)
		(drill 0.254)
		(layers "F.Cu" "B.Cu")
		(net "GND")
	)
	(via
		(at 2.665222 -1.48082)
		(size 0.508)
		(drill 0.254)
		(layers "F.Cu" "B.Cu")
		(net "GND")
	)
	(via
		(at 312.91022 -90.461592)
		(size 0.508)
		(drill 0.254)
		(layers "F.Cu" "B.Cu")
		(net "GND")
	)
	(via
		(at 57.360566 -26.266648)
		(size 0.508)
		(drill 0.254)
		(layers "F.Cu" "B.Cu")
		(net "GND")
	)
	(via
		(at 111.67872 -102.23754)
		(size 0.508)
		(drill 0.254)
		(layers "F.Cu" "B.Cu")
		(net "GND")
	)
	(via
		(at 275.209 -11.049)
		(size 0.508)
		(drill 0.254)
		(layers "F.Cu" "B.Cu")
		(net "GND")
	)
	(via
		(at 352.268028 -145.932906)
		(size 0.508)
		(drill 0.254)
		(layers "F.Cu" "B.Cu")
		(net "GND")
	)
	(via
		(at 304.71872 -102.23754)
		(size 0.508)
		(drill 0.254)
		(layers "F.Cu" "B.Cu")
		(net "GND")
	)
	(via
		(at 326.672702 -96.091248)
		(size 0.508)
		(drill 0.254)
		(layers "F.Cu" "B.Cu")
		(net "GND")
	)
	(via
		(at 40.997124 -0.772668)
		(size 0.508)
		(drill 0.254)
		(layers "F.Cu" "B.Cu")
		(net "GND")
	)
	(via
		(at 185.166 -58.039)
		(size 0.508)
		(drill 0.254)
		(layers "F.Cu" "B.Cu")
		(net "GND")
	)
	(via
		(at 445.58204 -47.56404)
		(size 0.508)
		(drill 0.254)
		(layers "F.Cu" "B.Cu")
		(net "GND")
	)
	(via
		(at 119.112284 -86.668864)
		(size 0.508)
		(drill 0.254)
		(layers "F.Cu" "B.Cu")
		(net "GND")
	)
	(via
		(at 411.1752 -19.4818)
		(size 0.508)
		(drill 0.254)
		(layers "F.Cu" "B.Cu")
		(net "GND")
	)
	(via
		(at 412.2674 -45.212)
		(size 0.508)
		(drill 0.254)
		(layers "F.Cu" "B.Cu")
		(net "GND")
	)
	(via
		(at 443.484 -48.57496)
		(size 0.508)
		(drill 0.254)
		(layers "F.Cu" "B.Cu")
		(net "GND")
	)
	(via
		(at 332.832964 -9.774428)
		(size 0.508)
		(drill 0.254)
		(layers "F.Cu" "B.Cu")
		(net "GND")
	)
	(via
		(at 208.19872 -102.23754)
		(size 0.508)
		(drill 0.254)
		(layers "F.Cu" "B.Cu")
		(net "GND")
	)
	(via
		(at 451.455282 -88.465152)
		(size 0.508)
		(drill 0.254)
		(layers "F.Cu" "B.Cu")
		(net "GND")
	)
	(via
		(at 352.969322 -155.631642)
		(size 0.508)
		(drill 0.254)
		(layers "F.Cu" "B.Cu")
		(net "GND")
	)
	(via
		(at 442.495686 -85.55609)
		(size 0.508)
		(drill 0.254)
		(layers "F.Cu" "B.Cu")
		(net "GND")
	)
	(via
		(at 258.99872 -102.23754)
		(size 0.508)
		(drill 0.254)
		(layers "F.Cu" "B.Cu")
		(net "GND")
	)
	(via
		(at 428.237904 -44.577)
		(size 0.508)
		(drill 0.254)
		(layers "F.Cu" "B.Cu")
		(net "GND")
	)
	(via
		(at 450.965316 -130.999484)
		(size 0.508)
		(drill 0.254)
		(layers "F.Cu" "B.Cu")
		(net "GND")
	)
	(via
		(at 432.32705 -52.197)
		(size 0.508)
		(drill 0.254)
		(layers "F.Cu" "B.Cu")
		(net "GND")
	)
	(via
		(at 255.778 -58.801)
		(size 0.508)
		(drill 0.254)
		(layers "F.Cu" "B.Cu")
		(net "GND")
	)
	(via
		(at 429.9204 -34.53765)
		(size 0.508)
		(drill 0.254)
		(layers "F.Cu" "B.Cu")
		(net "GND")
	)
	(via
		(at 444.9064 -61.087)
		(size 0.508)
		(drill 0.254)
		(layers "F.Cu" "B.Cu")
		(net "GND")
	)
	(via
		(at 443.206886 -84.87029)
		(size 0.508)
		(drill 0.254)
		(layers "F.Cu" "B.Cu")
		(net "GND")
	)
	(via
		(at 121.525284 -86.668864)
		(size 0.508)
		(drill 0.254)
		(layers "F.Cu" "B.Cu")
		(net "GND")
	)
	(via
		(at 95.298768 -9.757918)
		(size 0.508)
		(drill 0.254)
		(layers "F.Cu" "B.Cu")
		(net "GND")
	)
	(via
		(at 444.9064 -59.817)
		(size 0.508)
		(drill 0.254)
		(layers "F.Cu" "B.Cu")
		(net "GND")
	)
	(via
		(at 93.774768 -9.757918)
		(size 0.508)
		(drill 0.254)
		(layers "F.Cu" "B.Cu")
		(net "GND")
	)
	(via
		(at 317.22822 -91.223592)
		(size 0.508)
		(drill 0.254)
		(layers "F.Cu" "B.Cu")
		(net "GND")
	)
	(via
		(at 289.306 -93.091)
		(size 0.508)
		(drill 0.254)
		(layers "F.Cu" "B.Cu")
		(net "GND")
	)
	(via
		(at 311.38622 -90.461592)
		(size 0.508)
		(drill 0.254)
		(layers "F.Cu" "B.Cu")
		(net "GND")
	)
	(via
		(at 261.6454 -52.705)
		(size 0.508)
		(drill 0.254)
		(layers "F.Cu" "B.Cu")
		(net "GND")
	)
	(via
		(at 166.315136 -10.287)
		(size 0.508)
		(drill 0.254)
		(layers "F.Cu" "B.Cu")
		(net "GND")
	)
	(via
		(at 279.781 -68.199)
		(size 0.508)
		(drill 0.254)
		(layers "F.Cu" "B.Cu")
		(net "GND")
	)
	(via
		(at 418.896038 -33.76041)
		(size 0.508)
		(drill 0.254)
		(layers "F.Cu" "B.Cu")
		(net "GND")
	)
	(via
		(at 96.43872 -102.23754)
		(size 0.508)
		(drill 0.254)
		(layers "F.Cu" "B.Cu")
		(net "GND")
	)
	(via
		(at 439.23585 -148.018754)
		(size 0.508)
		(drill 0.254)
		(layers "F.Cu" "B.Cu")
		(net "GND")
	)
	(via
		(at 272.923 -24.384)
		(size 0.508)
		(drill 0.254)
		(layers "F.Cu" "B.Cu")
		(net "GND")
	)
	(via
		(at 333.594964 -9.774428)
		(size 0.508)
		(drill 0.254)
		(layers "F.Cu" "B.Cu")
		(net "GND")
	)
	(via
		(at 475.236032 -90.706448)
		(size 0.508)
		(drill 0.254)
		(layers "F.Cu" "B.Cu")
		(net "GND")
	)
	(via
		(at 255.016 -58.039)
		(size 0.508)
		(drill 0.254)
		(layers "F.Cu" "B.Cu")
		(net "GND")
	)
	(via
		(at 376.661172 -28.136342)
		(size 0.508)
		(drill 0.254)
		(layers "F.Cu" "B.Cu")
		(net "GND")
	)
	(via
		(at 158.696152 -59.89066)
		(size 0.508)
		(drill 0.254)
		(layers "F.Cu" "B.Cu")
		(net "GND")
	)
	(via
		(at 51.157124 -0.772668)
		(size 0.508)
		(drill 0.254)
		(layers "F.Cu" "B.Cu")
		(net "GND")
	)
	(via
		(at 166.315136 -11.049)
		(size 0.508)
		(drill 0.254)
		(layers "F.Cu" "B.Cu")
		(net "GND")
	)
	(via
		(at 448.83705 -39.492936)
		(size 0.508)
		(drill 0.254)
		(layers "F.Cu" "B.Cu")
		(net "GND")
	)
	(via
		(at 248.285 -58.039)
		(size 0.508)
		(drill 0.254)
		(layers "F.Cu" "B.Cu")
		(net "GND")
	)
	(via
		(at 164.791136 -25.146)
		(size 0.508)
		(drill 0.254)
		(layers "F.Cu" "B.Cu")
		(net "GND")
	)
	(via
		(at 442.1124 -59.182)
		(size 0.508)
		(drill 0.254)
		(layers "F.Cu" "B.Cu")
		(net "GND")
	)
	(via
		(at 377.423172 -28.898342)
		(size 0.508)
		(drill 0.254)
		(layers "F.Cu" "B.Cu")
		(net "GND")
	)
	(via
		(at 415.29 -38.84295)
		(size 0.508)
		(drill 0.254)
		(layers "F.Cu" "B.Cu")
		(net "GND")
	)
	(via
		(at 443.79769 -90.421206)
		(size 0.508)
		(drill 0.254)
		(layers "F.Cu" "B.Cu")
		(net "GND")
	)
	(via
		(at 56.237124 -0.772668)
		(size 0.508)
		(drill 0.254)
		(layers "F.Cu" "B.Cu")
		(net "GND")
	)
	(via
		(at 320.88836 -90.496136)
		(size 0.508)
		(drill 0.254)
		(layers "F.Cu" "B.Cu")
		(net "GND")
	)
	(via
		(at 448.856354 -84.660994)
		(size 0.508)
		(drill 0.254)
		(layers "F.Cu" "B.Cu")
		(net "GND")
	)
	(via
		(at 0.766572 -87.35822)
		(size 0.508)
		(drill 0.254)
		(layers "F.Cu" "B.Cu")
		(net "GND")
	)
	(via
		(at 192.659 -58.039)
		(size 0.508)
		(drill 0.254)
		(layers "F.Cu" "B.Cu")
		(net "GND")
	)
	(via
		(at 362.903516 -170.318938)
		(size 0.508)
		(drill 0.254)
		(layers "F.Cu" "B.Cu")
		(net "GND")
	)
	(via
		(at 352.268028 -151.012906)
		(size 0.508)
		(drill 0.254)
		(layers "F.Cu" "B.Cu")
		(net "GND")
	)
	(via
		(at 52.085494 -21.717)
		(size 0.508)
		(drill 0.254)
		(layers "F.Cu" "B.Cu")
		(net "GND")
	)
	(via
		(at 58.408062 -24.32812)
		(size 0.508)
		(drill 0.254)
		(layers "F.Cu" "B.Cu")
		(net "GND")
	)
	(via
		(at 413.679132 -157.546294)
		(size 0.508)
		(drill 0.254)
		(layers "F.Cu" "B.Cu")
		(net "GND")
	)
	(via
		(at 312.14822 -91.223592)
		(size 0.508)
		(drill 0.254)
		(layers "F.Cu" "B.Cu")
		(net "GND")
	)
	(via
		(at 182.79872 -102.23754)
		(size 0.508)
		(drill 0.254)
		(layers "F.Cu" "B.Cu")
		(net "GND")
	)
	(via
		(at 129.012442 -9.513824)
		(size 0.508)
		(drill 0.254)
		(layers "F.Cu" "B.Cu")
		(net "GND")
	)
	(via
		(at 362.02874 -10.282174)
		(size 0.508)
		(drill 0.254)
		(layers "F.Cu" "B.Cu")
		(net "GND")
	)
	(via
		(at 183.642 -58.801)
		(size 0.508)
		(drill 0.254)
		(layers "F.Cu" "B.Cu")
		(net "GND")
	)
	(via
		(at 290.3474 -81.28)
		(size 0.508)
		(drill 0.254)
		(layers "F.Cu" "B.Cu")
		(net "GND")
	)
	(via
		(at 29.190442 -158.491428)
		(size 0.508)
		(drill 0.254)
		(layers "F.Cu" "B.Cu")
		(net "GND")
	)
	(via
		(at 447.82105 -45.4406)
		(size 0.508)
		(drill 0.254)
		(layers "F.Cu" "B.Cu")
		(net "GND")
	)
	(via
		(at 451.1294 -91.821)
		(size 0.508)
		(drill 0.254)
		(layers "F.Cu" "B.Cu")
		(net "GND")
	)
	(via
		(at 471.299286 -130.987038)
		(size 0.508)
		(drill 0.254)
		(layers "F.Cu" "B.Cu")
		(net "GND")
	)
	(via
		(at 360.76509 -161.388552)
		(size 0.508)
		(drill 0.254)
		(layers "F.Cu" "B.Cu")
		(net "GND")
	)
	(via
		(at 418.973 -44.043092)
		(size 0.508)
		(drill 0.254)
		(layers "F.Cu" "B.Cu")
		(net "GND")
	)
	(via
		(at 418.550598 -30.940248)
		(size 0.508)
		(drill 0.254)
		(layers "F.Cu" "B.Cu")
		(net "GND")
	)
	(via
		(at 447.663316 -81.368138)
		(size 0.508)
		(drill 0.254)
		(layers "F.Cu" "B.Cu")
		(net "GND")
	)
	(via
		(at 376.661172 -28.898342)
		(size 0.508)
		(drill 0.254)
		(layers "F.Cu" "B.Cu")
		(net "GND")
	)
	(via
		(at 297.6118 -88.8746)
		(size 0.508)
		(drill 0.254)
		(layers "F.Cu" "B.Cu")
		(net "GND")
	)
	(via
		(at 359.74274 -10.282174)
		(size 0.508)
		(drill 0.254)
		(layers "F.Cu" "B.Cu")
		(net "GND")
	)
	(via
		(at 442.1124 -59.817)
		(size 0.508)
		(drill 0.254)
		(layers "F.Cu" "B.Cu")
		(net "GND")
	)
	(via
		(at 411.1752 -20.2438)
		(size 0.508)
		(drill 0.254)
		(layers "F.Cu" "B.Cu")
		(net "GND")
	)
	(via
		(at 453.122538 -60.908692)
		(size 0.508)
		(drill 0.254)
		(layers "F.Cu" "B.Cu")
		(net "GND")
	)
	(via
		(at 84.14639 -157.482032)
		(size 0.508)
		(drill 0.254)
		(layers "F.Cu" "B.Cu")
		(net "GND")
	)
	(via
		(at 125.964442 -9.513824)
		(size 0.508)
		(drill 0.254)
		(layers "F.Cu" "B.Cu")
		(net "GND")
	)
	(via
		(at 428.237904 -37.592)
		(size 0.508)
		(drill 0.254)
		(layers "F.Cu" "B.Cu")
		(net "GND")
	)
	(via
		(at 116.572284 -90.732864)
		(size 0.508)
		(drill 0.254)
		(layers "F.Cu" "B.Cu")
		(net "GND")
	)
	(via
		(at 320.386964 -9.774428)
		(size 0.508)
		(drill 0.254)
		(layers "F.Cu" "B.Cu")
		(net "GND")
	)
	(via
		(at 406.9334 -16.764)
		(size 0.508)
		(drill 0.254)
		(layers "F.Cu" "B.Cu")
		(net "GND")
	)
	(via
		(at 450.963538 -61.670692)
		(size 0.508)
		(drill 0.254)
		(layers "F.Cu" "B.Cu")
		(net "GND")
	)
	(via
		(at 115.810284 -86.668864)
		(size 0.508)
		(drill 0.254)
		(layers "F.Cu" "B.Cu")
		(net "GND")
	)
	(via
		(at 119.874284 -85.906864)
		(size 0.508)
		(drill 0.254)
		(layers "F.Cu" "B.Cu")
		(net "GND")
	)
	(via
		(at 321.39636 -96.465136)
		(size 0.508)
		(drill 0.254)
		(layers "F.Cu" "B.Cu")
		(net "GND")
	)
	(via
		(at 344.17 -51.9176)
		(size 0.508)
		(drill 0.254)
		(layers "F.Cu" "B.Cu")
		(net "GND")
	)
	(via
		(at 449.59905 -46.101)
		(size 0.508)
		(drill 0.254)
		(layers "F.Cu" "B.Cu")
		(net "GND")
	)
	(via
		(at 328.196702 -94.567248)
		(size 0.508)
		(drill 0.254)
		(layers "F.Cu" "B.Cu")
		(net "GND")
	)
	(via
		(at 443.968886 -87.00389)
		(size 0.508)
		(drill 0.254)
		(layers "F.Cu" "B.Cu")
		(net "GND")
	)
	(via
		(at 87.734648 -115.574318)
		(size 0.508)
		(drill 0.254)
		(layers "F.Cu" "B.Cu")
		(net "GND")
	)
	(via
		(at 137.07872 -102.23754)
		(size 0.508)
		(drill 0.254)
		(layers "F.Cu" "B.Cu")
		(net "GND")
	)
	(via
		(at 275.209 -10.287)
		(size 0.508)
		(drill 0.254)
		(layers "F.Cu" "B.Cu")
		(net "GND")
	)
	(via
		(at 57.392062 -24.32812)
		(size 0.508)
		(drill 0.254)
		(layers "F.Cu" "B.Cu")
		(net "GND")
	)
	(via
		(at 345.01074 -9.878822)
		(size 0.508)
		(drill 0.254)
		(layers "F.Cu" "B.Cu")
		(net "GND")
	)
	(via
		(at 470.82329 -17.535398)
		(size 0.508)
		(drill 0.254)
		(layers "F.Cu" "B.Cu")
		(net "GND")
	)
	(via
		(at 91.980258 -103.278432)
		(size 0.508)
		(drill 0.254)
		(layers "F.Cu" "B.Cu")
		(net "GND")
	)
	(via
		(at 167.386 -72.136)
		(size 0.508)
		(drill 0.254)
		(layers "F.Cu" "B.Cu")
		(net "GND")
	)
	(via
		(at 442.495686 -86.26729)
		(size 0.508)
		(drill 0.254)
		(layers "F.Cu" "B.Cu")
		(net "GND")
	)
	(via
		(at 272.923 -25.146)
		(size 0.508)
		(drill 0.254)
		(layers "F.Cu" "B.Cu")
		(net "GND")
	)
	(via
		(at 0.766572 -143.23822)
		(size 0.508)
		(drill 0.254)
		(layers "F.Cu" "B.Cu")
		(net "GND")
	)
	(via
		(at 447.929 -28.702)
		(size 0.508)
		(drill 0.254)
		(layers "F.Cu" "B.Cu")
		(net "GND")
	)
	(via
		(at 123.049284 -85.906864)
		(size 0.508)
		(drill 0.254)
		(layers "F.Cu" "B.Cu")
		(net "GND")
	)
	(via
		(at 0.766572 -112.75822)
		(size 0.508)
		(drill 0.254)
		(layers "F.Cu" "B.Cu")
		(net "GND")
	)
	(via
		(at 448.677538 -61.670692)
		(size 0.508)
		(drill 0.254)
		(layers "F.Cu" "B.Cu")
		(net "GND")
	)
	(via
		(at 332.070964 -9.774428)
		(size 0.508)
		(drill 0.254)
		(layers "F.Cu" "B.Cu")
		(net "GND")
	)
	(via
		(at 434.60035 -47.498)
		(size 0.508)
		(drill 0.254)
		(layers "F.Cu" "B.Cu")
		(net "GND")
	)
	(via
		(at 119.874284 -86.668864)
		(size 0.508)
		(drill 0.254)
		(layers "F.Cu" "B.Cu")
		(net "GND")
	)
	(via
		(at 147.23872 -102.23754)
		(size 0.508)
		(drill 0.254)
		(layers "F.Cu" "B.Cu")
		(net "GND")
	)
	(via
		(at 273.685 -24.384)
		(size 0.508)
		(drill 0.254)
		(layers "F.Cu" "B.Cu")
		(net "GND")
	)
	(via
		(at 3.973068 -157.40761)
		(size 0.508)
		(drill 0.254)
		(layers "F.Cu" "B.Cu")
		(net "GND")
	)
	(via
		(at 443.79769 -95.240856)
		(size 0.508)
		(drill 0.254)
		(layers "F.Cu" "B.Cu")
		(net "GND")
	)
	(via
		(at 423.84345 -157.537404)
		(size 0.508)
		(drill 0.254)
		(layers "F.Cu" "B.Cu")
		(net "GND")
	)
	(via
		(at 87.734648 -151.134318)
		(size 0.508)
		(drill 0.254)
		(layers "F.Cu" "B.Cu")
		(net "GND")
	)
	(via
		(at 59.281314 -23.44547)
		(size 0.508)
		(drill 0.254)
		(layers "F.Cu" "B.Cu")
		(net "GND")
	)
	(via
		(at 418.76345 -157.537404)
		(size 0.508)
		(drill 0.254)
		(layers "F.Cu" "B.Cu")
		(net "GND")
	)
	(via
		(at 50.9524 -27.700986)
		(size 0.508)
		(drill 0.254)
		(layers "F.Cu" "B.Cu")
		(net "GND")
	)
	(via
		(at 176.241202 -48.19904)
		(size 0.508)
		(drill 0.254)
		(layers "F.Cu" "B.Cu")
		(net "GND")
	)
	(via
		(at 103.6574 -45.7454)
		(size 0.508)
		(drill 0.254)
		(layers "F.Cu" "B.Cu")
		(net "GND")
	)
	(via
		(at 320.88836 -91.258136)
		(size 0.508)
		(drill 0.254)
		(layers "F.Cu" "B.Cu")
		(net "GND")
	)
	(via
		(at 322.15836 -96.465136)
		(size 0.508)
		(drill 0.254)
		(layers "F.Cu" "B.Cu")
		(net "GND")
	)
	(via
		(at 407.9494 -22.606)
		(size 0.508)
		(drill 0.254)
		(layers "F.Cu" "B.Cu")
		(net "GND")
	)
	(via
		(at 406.9334 -21.717)
		(size 0.508)
		(drill 0.254)
		(layers "F.Cu" "B.Cu")
		(net "GND")
	)
	(via
		(at 475.236286 -23.853902)
		(size 0.508)
		(drill 0.254)
		(layers "F.Cu" "B.Cu")
		(net "GND")
	)
	(via
		(at 9.00557 -157.529276)
		(size 0.508)
		(drill 0.254)
		(layers "F.Cu" "B.Cu")
		(net "GND")
	)
	(via
		(at 403.46884 -0.762762)
		(size 0.508)
		(drill 0.254)
		(layers "F.Cu" "B.Cu")
		(net "GND")
	)
	(via
		(at 191.897 -58.039)
		(size 0.508)
		(drill 0.254)
		(layers "F.Cu" "B.Cu")
		(net "GND")
	)
	(via
		(at 14.08557 -157.529276)
		(size 0.508)
		(drill 0.254)
		(layers "F.Cu" "B.Cu")
		(net "GND")
	)
	(via
		(at 0.766572 -6.07822)
		(size 0.508)
		(drill 0.254)
		(layers "F.Cu" "B.Cu")
		(net "GND")
	)
	(via
		(at 52.085494 -19.05)
		(size 0.508)
		(drill 0.254)
		(layers "F.Cu" "B.Cu")
		(net "GND")
	)
	(via
		(at 428.237904 -38.989)
		(size 0.508)
		(drill 0.254)
		(layers "F.Cu" "B.Cu")
		(net "GND")
	)
	(via
		(at 52.085494 -24.638)
		(size 0.508)
		(drill 0.254)
		(layers "F.Cu" "B.Cu")
		(net "GND")
	)
	(via
		(at 0.766572 -67.03822)
		(size 0.508)
		(drill 0.254)
		(layers "F.Cu" "B.Cu")
		(net "GND")
	)
	(via
		(at 94.536768 -9.757918)
		(size 0.508)
		(drill 0.254)
		(layers "F.Cu" "B.Cu")
		(net "GND")
	)
	(via
		(at 317.73622 -96.430592)
		(size 0.508)
		(drill 0.254)
		(layers "F.Cu" "B.Cu")
		(net "GND")
	)
	(via
		(at 475.236032 -95.786448)
		(size 0.508)
		(drill 0.254)
		(layers "F.Cu" "B.Cu")
		(net "GND")
	)
	(via
		(at 367.240566 -170.885612)
		(size 0.508)
		(drill 0.254)
		(layers "F.Cu" "B.Cu")
		(net "GND")
	)
	(via
		(at 0.766572 -92.43822)
		(size 0.508)
		(drill 0.254)
		(layers "F.Cu" "B.Cu")
		(net "GND")
	)
	(via
		(at 0.766572 -117.83822)
		(size 0.508)
		(drill 0.254)
		(layers "F.Cu" "B.Cu")
		(net "GND")
	)
	(via
		(at 352.268028 -135.772906)
		(size 0.508)
		(drill 0.254)
		(layers "F.Cu" "B.Cu")
		(net "GND")
	)
	(via
		(at 255.778 -58.039)
		(size 0.508)
		(drill 0.254)
		(layers "F.Cu" "B.Cu")
		(net "GND")
	)
	(via
		(at 409.9814 -30.48)
		(size 0.508)
		(drill 0.254)
		(layers "F.Cu" "B.Cu")
		(net "GND")
	)
	(via
		(at 167.077136 -11.049)
		(size 0.508)
		(drill 0.254)
		(layers "F.Cu" "B.Cu")
		(net "GND")
	)
	(via
		(at 408.7114 -15.875)
		(size 0.508)
		(drill 0.254)
		(layers "F.Cu" "B.Cu")
		(net "GND")
	)
	(via
		(at 0.766572 -102.59822)
		(size 0.508)
		(drill 0.254)
		(layers "F.Cu" "B.Cu")
		(net "GND")
	)
	(via
		(at 378.185172 -26.612342)
		(size 0.508)
		(drill 0.254)
		(layers "F.Cu" "B.Cu")
		(net "GND")
	)
	(via
		(at 376.661172 -27.374342)
		(size 0.508)
		(drill 0.254)
		(layers "F.Cu" "B.Cu")
		(net "GND")
	)
	(via
		(at 0.766572 -127.99822)
		(size 0.508)
		(drill 0.254)
		(layers "F.Cu" "B.Cu")
		(net "GND")
	)
	(via
		(at 0.766572 -41.63822)
		(size 0.508)
		(drill 0.254)
		(layers "F.Cu" "B.Cu")
		(net "GND")
	)
	(via
		(at 455.58329 -17.535398)
		(size 0.508)
		(drill 0.254)
		(layers "F.Cu" "B.Cu")
		(net "GND")
	)
	(via
		(at 475.236032 -29.746448)
		(size 0.508)
		(drill 0.254)
		(layers "F.Cu" "B.Cu")
		(net "GND")
	)
	(via
		(at 317.22822 -90.461592)
		(size 0.508)
		(drill 0.254)
		(layers "F.Cu" "B.Cu")
		(net "GND")
	)
	(via
		(at 388.22884 -0.762762)
		(size 0.508)
		(drill 0.254)
		(layers "F.Cu" "B.Cu")
		(net "GND")
	)
	(via
		(at 0.766572 -16.23822)
		(size 0.508)
		(drill 0.254)
		(layers "F.Cu" "B.Cu")
		(net "GND")
	)
	(via
		(at 238.67872 -102.23754)
		(size 0.508)
		(drill 0.254)
		(layers "F.Cu" "B.Cu")
		(net "GND")
	)
	(via
		(at 60.281566 -25.273762)
		(size 0.508)
		(drill 0.254)
		(layers "F.Cu" "B.Cu")
		(net "GND")
	)
	(via
		(at 57.360566 -25.273762)
		(size 0.508)
		(drill 0.254)
		(layers "F.Cu" "B.Cu")
		(net "GND")
	)
	(via
		(at 189.611 -58.039)
		(size 0.508)
		(drill 0.254)
		(layers "F.Cu" "B.Cu")
		(net "GND")
	)
	(via
		(at 0.766572 -56.87822)
		(size 0.508)
		(drill 0.254)
		(layers "F.Cu" "B.Cu")
		(net "GND")
	)
	(via
		(at 443.79769 -93.285056)
		(size 0.508)
		(drill 0.254)
		(layers "F.Cu" "B.Cu")
		(net "GND")
	)
	(via
		(at 413.62884 -0.762762)
		(size 0.508)
		(drill 0.254)
		(layers "F.Cu" "B.Cu")
		(net "GND")
	)
	(via
		(at 74.873612 -170.885866)
		(size 0.508)
		(drill 0.254)
		(layers "F.Cu" "B.Cu")
		(net "GND")
	)
	(via
		(at 87.734648 -110.494318)
		(size 0.508)
		(drill 0.254)
		(layers "F.Cu" "B.Cu")
		(net "GND")
	)
	(via
		(at 444.9064 -60.452)
		(size 0.508)
		(drill 0.254)
		(layers "F.Cu" "B.Cu")
		(net "GND")
	)
	(via
		(at 167.55872 -102.23754)
		(size 0.508)
		(drill 0.254)
		(layers "F.Cu" "B.Cu")
		(net "GND")
	)
	(via
		(at 378.947172 -27.374342)
		(size 0.508)
		(drill 0.254)
		(layers "F.Cu" "B.Cu")
		(net "GND")
	)
	(via
		(at 445.885316 -130.999484)
		(size 0.508)
		(drill 0.254)
		(layers "F.Cu" "B.Cu")
		(net "GND")
	)
	(via
		(at 275.209 -25.146)
		(size 0.508)
		(drill 0.254)
		(layers "F.Cu" "B.Cu")
		(net "GND")
	)
	(via
		(at 407.060146 -169.577512)
		(size 0.508)
		(drill 0.254)
		(layers "F.Cu" "B.Cu")
		(net "GND")
	)
	(via
		(at 218.35872 -102.23754)
		(size 0.508)
		(drill 0.254)
		(layers "F.Cu" "B.Cu")
		(net "GND")
	)
	(via
		(at 443.968886 -86.29269)
		(size 0.508)
		(drill 0.254)
		(layers "F.Cu" "B.Cu")
		(net "GND")
	)
	(via
		(at 60.297314 -23.44547)
		(size 0.508)
		(drill 0.254)
		(layers "F.Cu" "B.Cu")
		(net "GND")
	)
	(via
		(at 309.79872 -102.23754)
		(size 0.508)
		(drill 0.254)
		(layers "F.Cu" "B.Cu")
		(net "GND")
	)
	(via
		(at 376.661172 -26.612342)
		(size 0.508)
		(drill 0.254)
		(layers "F.Cu" "B.Cu")
		(net "GND")
	)
	(via
		(at 443.79769 -92.377006)
		(size 0.508)
		(drill 0.254)
		(layers "F.Cu" "B.Cu")
		(net "GND")
	)
	(via
		(at 340.27872 -102.23754)
		(size 0.508)
		(drill 0.254)
		(layers "F.Cu" "B.Cu")
		(net "GND")
	)
	(via
		(at 465.74329 -17.535398)
		(size 0.508)
		(drill 0.254)
		(layers "F.Cu" "B.Cu")
		(net "GND")
	)
	(via
		(at 191.135 -58.801)
		(size 0.508)
		(drill 0.254)
		(layers "F.Cu" "B.Cu")
		(net "GND")
	)
	(via
		(at 158.061152 -59.89066)
		(size 0.508)
		(drill 0.254)
		(layers "F.Cu" "B.Cu")
		(net "GND")
	)
	(via
		(at 250.571 -58.801)
		(size 0.508)
		(drill 0.254)
		(layers "F.Cu" "B.Cu")
		(net "GND")
	)
	(via
		(at 372.320566 -170.885612)
		(size 0.508)
		(drill 0.254)
		(layers "F.Cu" "B.Cu")
		(net "GND")
	)
	(via
		(at 59.265566 -26.266648)
		(size 0.508)
		(drill 0.254)
		(layers "F.Cu" "B.Cu")
		(net "GND")
	)
	(via
		(at 294.224964 -9.901428)
		(size 0.508)
		(drill 0.254)
		(layers "F.Cu" "B.Cu")
		(net "GND")
	)
	(via
		(at 378.947172 -28.898342)
		(size 0.508)
		(drill 0.254)
		(layers "F.Cu" "B.Cu")
		(net "GND")
	)
	(via
		(at 439.23585 -153.098754)
		(size 0.508)
		(drill 0.254)
		(layers "F.Cu" "B.Cu")
		(net "GND")
	)
	(via
		(at 166.315136 -24.384)
		(size 0.508)
		(drill 0.254)
		(layers "F.Cu" "B.Cu")
		(net "GND")
	)
	(via
		(at 0.766572 -97.51822)
		(size 0.508)
		(drill 0.254)
		(layers "F.Cu" "B.Cu")
		(net "GND")
	)
	(via
		(at 157.39872 -102.23754)
		(size 0.508)
		(drill 0.254)
		(layers "F.Cu" "B.Cu")
		(net "GND")
	)
	(via
		(at 352.268028 -120.532906)
		(size 0.508)
		(drill 0.254)
		(layers "F.Cu" "B.Cu")
		(net "GND")
	)
	(via
		(at 49.473612 -170.885866)
		(size 0.508)
		(drill 0.254)
		(layers "F.Cu" "B.Cu")
		(net "GND")
	)
	(via
		(at 438.105296 -52.140104)
		(size 0.508)
		(drill 0.254)
		(layers "F.Cu" "B.Cu")
		(net "GND")
	)
	(via
		(at 407.9494 -21.717)
		(size 0.508)
		(drill 0.254)
		(layers "F.Cu" "B.Cu")
		(net "GND")
	)
	(via
		(at 87.734648 -146.054318)
		(size 0.508)
		(drill 0.254)
		(layers "F.Cu" "B.Cu")
		(net "GND")
	)
	(via
		(at 213.27872 -102.23754)
		(size 0.508)
		(drill 0.254)
		(layers "F.Cu" "B.Cu")
		(net "GND")
	)
	(via
		(at 164.029136 -24.384)
		(size 0.508)
		(drill 0.254)
		(layers "F.Cu" "B.Cu")
		(net "GND")
	)
	(via
		(at 30.837124 -0.772668)
		(size 0.508)
		(drill 0.254)
		(layers "F.Cu" "B.Cu")
		(net "GND")
	)
	(via
		(at 378.185172 -28.898342)
		(size 0.508)
		(drill 0.254)
		(layers "F.Cu" "B.Cu")
		(net "GND")
	)
	(via
		(at 468.503 -105.791)
		(size 0.508)
		(drill 0.254)
		(layers "F.Cu" "B.Cu")
		(net "GND")
	)
	(via
		(at 440.3344 -100.965)
		(size 0.508)
		(drill 0.254)
		(layers "F.Cu" "B.Cu")
		(net "GND")
	)
	(via
		(at 59.265566 -25.273762)
		(size 0.508)
		(drill 0.254)
		(layers "F.Cu" "B.Cu")
		(net "GND")
	)
	(via
		(at 0.766572 -21.31822)
		(size 0.508)
		(drill 0.254)
		(layers "F.Cu" "B.Cu")
		(net "GND")
	)
	(via
		(at 0.766572 -61.95822)
		(size 0.508)
		(drill 0.254)
		(layers "F.Cu" "B.Cu")
		(net "GND")
	)
	(via
		(at 398.38884 -0.762762)
		(size 0.508)
		(drill 0.254)
		(layers "F.Cu" "B.Cu")
		(net "GND")
	)
	(via
		(at 0.766572 -11.15822)
		(size 0.508)
		(drill 0.254)
		(layers "F.Cu" "B.Cu")
		(net "GND")
	)
	(via
		(at 377.400566 -170.885612)
		(size 0.508)
		(drill 0.254)
		(layers "F.Cu" "B.Cu")
		(net "GND")
	)
	(via
		(at 432.0794 -45.339)
		(size 0.508)
		(drill 0.254)
		(layers "F.Cu" "B.Cu")
		(net "GND")
	)
	(via
		(at 418.70884 -0.762762)
		(size 0.508)
		(drill 0.254)
		(layers "F.Cu" "B.Cu")
		(net "GND")
	)
	(via
		(at 178.8668 -52.468526)
		(size 0.508)
		(drill 0.254)
		(layers "F.Cu" "B.Cu")
		(net "GND")
	)
	(via
		(at 86.898226 -155.83154)
		(size 0.508)
		(drill 0.254)
		(layers "F.Cu" "B.Cu")
		(net "GND")
	)
	(via
		(at 294.986964 -9.901428)
		(size 0.508)
		(drill 0.254)
		(layers "F.Cu" "B.Cu")
		(net "GND")
	)
	(via
		(at 190.373 -58.801)
		(size 0.508)
		(drill 0.254)
		(layers "F.Cu" "B.Cu")
		(net "GND")
	)
	(via
		(at 326.672702 -95.329248)
		(size 0.508)
		(drill 0.254)
		(layers "F.Cu" "B.Cu")
		(net "GND")
	)
	(via
		(at 275.209 -24.384)
		(size 0.508)
		(drill 0.254)
		(layers "F.Cu" "B.Cu")
		(net "GND")
	)
	(via
		(at 164.791136 -10.287)
		(size 0.508)
		(drill 0.254)
		(layers "F.Cu" "B.Cu")
		(net "GND")
	)
	(via
		(at 321.910964 -9.774428)
		(size 0.508)
		(drill 0.254)
		(layers "F.Cu" "B.Cu")
		(net "GND")
	)
	(via
		(at 121.525284 -85.906864)
		(size 0.508)
		(drill 0.254)
		(layers "F.Cu" "B.Cu")
		(net "GND")
	)
	(via
		(at 311.38622 -91.223592)
		(size 0.508)
		(drill 0.254)
		(layers "F.Cu" "B.Cu")
		(net "GND")
	)
	(via
		(at 432.44135 -32.893)
		(size 0.508)
		(drill 0.254)
		(layers "F.Cu" "B.Cu")
		(net "GND")
	)
	(via
		(at 423.69105 -48.133)
		(size 0.508)
		(drill 0.254)
		(layers "F.Cu" "B.Cu")
		(net "GND")
	)
	(via
		(at 254.254 -58.039)
		(size 0.508)
		(drill 0.254)
		(layers "F.Cu" "B.Cu")
		(net "GND")
	)
	(via
		(at 439.166 -46.609)
		(size 0.508)
		(drill 0.254)
		(layers "F.Cu" "B.Cu")
		(net "GND")
	)
	(via
		(at 127.488442 -9.513824)
		(size 0.508)
		(drill 0.254)
		(layers "F.Cu" "B.Cu")
		(net "GND")
	)
	(via
		(at 319.95872 -102.23754)
		(size 0.508)
		(drill 0.254)
		(layers "F.Cu" "B.Cu")
		(net "GND")
	)
	(via
		(at 311.623964 -9.774428)
		(size 0.508)
		(drill 0.254)
		(layers "F.Cu" "B.Cu")
		(net "GND")
	)
	(via
		(at 119.874284 -90.682064)
		(size 0.508)
		(drill 0.254)
		(layers "F.Cu" "B.Cu")
		(net "GND")
	)
	(via
		(at 312.385964 -9.774428)
		(size 0.508)
		(drill 0.254)
		(layers "F.Cu" "B.Cu")
		(net "GND")
	)
	(via
		(at 316.97422 -96.430592)
		(size 0.508)
		(drill 0.254)
		(layers "F.Cu" "B.Cu")
		(net "GND")
	)
	(via
		(at 314.87872 -102.23754)
		(size 0.508)
		(drill 0.254)
		(layers "F.Cu" "B.Cu")
		(net "GND")
	)
	(via
		(at 269.15872 -102.23754)
		(size 0.508)
		(drill 0.254)
		(layers "F.Cu" "B.Cu")
		(net "GND")
	)
	(via
		(at 123.049284 -86.668864)
		(size 0.508)
		(drill 0.254)
		(layers "F.Cu" "B.Cu")
		(net "GND")
	)
	(via
		(at 164.860986 -79.756)
		(size 0.508)
		(drill 0.254)
		(layers "F.Cu" "B.Cu")
		(net "GND")
	)
	(via
		(at 420.8907 -26.00452)
		(size 0.508)
		(drill 0.254)
		(layers "F.Cu" "B.Cu")
		(net "GND")
	)
	(via
		(at 274.447 -10.287)
		(size 0.508)
		(drill 0.254)
		(layers "F.Cu" "B.Cu")
		(net "GND")
	)
	(via
		(at 288.29 -93.091)
		(size 0.508)
		(drill 0.254)
		(layers "F.Cu" "B.Cu")
		(net "GND")
	)
	(via
		(at 378.185172 -28.136342)
		(size 0.508)
		(drill 0.254)
		(layers "F.Cu" "B.Cu")
		(net "GND")
	)
	(via
		(at 52.085494 -20.066)
		(size 0.508)
		(drill 0.254)
		(layers "F.Cu" "B.Cu")
		(net "GND")
	)
	(via
		(at 284.099 -71.882)
		(size 0.508)
		(drill 0.254)
		(layers "F.Cu" "B.Cu")
		(net "GND")
	)
	(via
		(at 52.085494 -23.622)
		(size 0.508)
		(drill 0.254)
		(layers "F.Cu" "B.Cu")
		(net "GND")
	)
	(via
		(at 321.65036 -91.258136)
		(size 0.508)
		(drill 0.254)
		(layers "F.Cu" "B.Cu")
		(net "GND")
	)
	(via
		(at 35.917124 -0.772668)
		(size 0.508)
		(drill 0.254)
		(layers "F.Cu" "B.Cu")
		(net "GND")
	)
	(via
		(at 282.575 -92.6338)
		(size 0.508)
		(drill 0.254)
		(layers "F.Cu" "B.Cu")
		(net "GND")
	)
	(via
		(at 0.766572 -51.79822)
		(size 0.508)
		(drill 0.254)
		(layers "F.Cu" "B.Cu")
		(net "GND")
	)
	(via
		(at 475.236032 -116.106448)
		(size 0.508)
		(drill 0.254)
		(layers "F.Cu" "B.Cu")
		(net "GND")
	)
	(via
		(at 428.237904 -43.18)
		(size 0.508)
		(drill 0.254)
		(layers "F.Cu" "B.Cu")
		(net "GND")
	)
	(via
		(at 172.63872 -102.23754)
		(size 0.508)
		(drill 0.254)
		(layers "F.Cu" "B.Cu")
		(net "GND")
	)
	(via
		(at 289.9664 -77.510894)
		(size 0.508)
		(drill 0.254)
		(layers "F.Cu" "B.Cu")
		(net "GND")
	)
	(via
		(at 361.26674 -10.282174)
		(size 0.508)
		(drill 0.254)
		(layers "F.Cu" "B.Cu")
		(net "GND")
	)
	(via
		(at 60.281566 -26.266648)
		(size 0.508)
		(drill 0.254)
		(layers "F.Cu" "B.Cu")
		(net "GND")
	)
	(via
		(at 170.434 -80.20304)
		(size 0.508)
		(drill 0.254)
		(layers "F.Cu" "B.Cu")
		(net "GND")
	)
	(via
		(at 439.23077 -6.438138)
		(size 0.508)
		(drill 0.254)
		(layers "F.Cu" "B.Cu")
		(net "GND")
	)
	(via
		(at 352.268028 -115.452906)
		(size 0.508)
		(drill 0.254)
		(layers "F.Cu" "B.Cu")
		(net "GND")
	)
	(via
		(at 275.971 -24.384)
		(size 0.508)
		(drill 0.254)
		(layers "F.Cu" "B.Cu")
		(net "GND")
	)
	(via
		(at 129.774442 -9.513824)
		(size 0.508)
		(drill 0.254)
		(layers "F.Cu" "B.Cu")
		(net "GND")
	)
	(via
		(at 450.963538 -60.908692)
		(size 0.508)
		(drill 0.254)
		(layers "F.Cu" "B.Cu")
		(net "GND")
	)
	(via
		(at 377.423172 -27.374342)
		(size 0.508)
		(drill 0.254)
		(layers "F.Cu" "B.Cu")
		(net "GND")
	)
	(via
		(at 223.647 -93.853)
		(size 0.508)
		(drill 0.254)
		(layers "F.Cu" "B.Cu")
		(net "GND")
	)
	(via
		(at 248.285 -58.801)
		(size 0.508)
		(drill 0.254)
		(layers "F.Cu" "B.Cu")
		(net "GND")
	)
	(via
		(at 0.766572 -82.27822)
		(size 0.508)
		(drill 0.254)
		(layers "F.Cu" "B.Cu")
		(net "GND")
	)
	(via
		(at 407.9494 -15.875)
		(size 0.508)
		(drill 0.254)
		(layers "F.Cu" "B.Cu")
		(net "GND")
	)
	(via
		(at 126.91872 -102.23754)
		(size 0.508)
		(drill 0.254)
		(layers "F.Cu" "B.Cu")
		(net "GND")
	)
	(via
		(at 167.077136 -10.287)
		(size 0.508)
		(drill 0.254)
		(layers "F.Cu" "B.Cu")
		(net "GND")
	)
	(via
		(at 164.791136 -11.049)
		(size 0.508)
		(drill 0.254)
		(layers "F.Cu" "B.Cu")
		(net "GND")
	)
	(via
		(at 162.814 -66.421)
		(size 0.508)
		(drill 0.254)
		(layers "F.Cu" "B.Cu")
		(net "GND")
	)
	(via
		(at 428.927768 -157.528514)
		(size 0.508)
		(drill 0.254)
		(layers "F.Cu" "B.Cu")
		(net "GND")
	)
	(via
		(at 344.1954 -40.64)
		(size 0.508)
		(drill 0.254)
		(layers "F.Cu" "B.Cu")
		(net "GND")
	)
	(via
		(at 407.9494 -16.764)
		(size 0.508)
		(drill 0.254)
		(layers "F.Cu" "B.Cu")
		(net "GND")
	)
	(via
		(at 294.55872 -102.23754)
		(size 0.508)
		(drill 0.254)
		(layers "F.Cu" "B.Cu")
		(net "GND")
	)
	(via
		(at 24.24557 -157.529276)
		(size 0.508)
		(drill 0.254)
		(layers "F.Cu" "B.Cu")
		(net "GND")
	)
	(via
		(at 439.0644 -98.425)
		(size 0.508)
		(drill 0.254)
		(layers "F.Cu" "B.Cu")
		(net "GND")
	)
	(via
		(at 439.23585 -137.858754)
		(size 0.508)
		(drill 0.254)
		(layers "F.Cu" "B.Cu")
		(net "GND")
	)
	(via
		(at 0.766572 -122.91822)
		(size 0.508)
		(drill 0.254)
		(layers "F.Cu" "B.Cu")
		(net "GND")
	)
	(via
		(at 131.99872 -102.23754)
		(size 0.508)
		(drill 0.254)
		(layers "F.Cu" "B.Cu")
		(net "GND")
	)
	(via
		(at 272.923 -11.049)
		(size 0.508)
		(drill 0.254)
		(layers "F.Cu" "B.Cu")
		(net "GND")
	)
	(via
		(at 46.077124 -0.772668)
		(size 0.508)
		(drill 0.254)
		(layers "F.Cu" "B.Cu")
		(net "GND")
	)
	(via
		(at 20.677124 -0.772668)
		(size 0.508)
		(drill 0.254)
		(layers "F.Cu" "B.Cu")
		(net "GND")
	)
	(via
		(at 69.793612 -170.885866)
		(size 0.508)
		(drill 0.254)
		(layers "F.Cu" "B.Cu")
		(net "GND")
	)
	(via
		(at 320.12636 -91.258136)
		(size 0.508)
		(drill 0.254)
		(layers "F.Cu" "B.Cu")
		(net "GND")
	)
	(via
		(at 434.848 -38.862)
		(size 0.508)
		(drill 0.254)
		(layers "F.Cu" "B.Cu")
		(net "GND")
	)
	(via
		(at 187.87872 -102.23754)
		(size 0.508)
		(drill 0.254)
		(layers "F.Cu" "B.Cu")
		(net "GND")
	)
	(via
		(at 475.236032 -55.146448)
		(size 0.508)
		(drill 0.254)
		(layers "F.Cu" "B.Cu")
		(net "GND")
	)
	(via
		(at 466.205316 -130.999484)
		(size 0.508)
		(drill 0.254)
		(layers "F.Cu" "B.Cu")
		(net "GND")
	)
	(via
		(at 186.563 -78.88605)
		(size 0.508)
		(drill 0.254)
		(layers "F.Cu" "B.Cu")
		(net "GND")
	)
	(via
		(at 392.640566 -170.885612)
		(size 0.508)
		(drill 0.254)
		(layers "F.Cu" "B.Cu")
		(net "GND")
	)
	(via
		(at 275.971 -25.146)
		(size 0.508)
		(drill 0.254)
		(layers "F.Cu" "B.Cu")
		(net "GND")
	)
	(via
		(at 253.91872 -102.23754)
		(size 0.508)
		(drill 0.254)
		(layers "F.Cu" "B.Cu")
		(net "GND")
	)
	(via
		(at 257.302 -58.039)
		(size 0.508)
		(drill 0.254)
		(layers "F.Cu" "B.Cu")
		(net "GND")
	)
	(via
		(at 82.236564 -9.959594)
		(size 0.508)
		(drill 0.254)
		(layers "F.Cu" "B.Cu")
		(net "GND")
	)
	(via
		(at 184.404 -58.801)
		(size 0.508)
		(drill 0.254)
		(layers "F.Cu" "B.Cu")
		(net "GND")
	)
	(via
		(at 118.350284 -85.906864)
		(size 0.508)
		(drill 0.254)
		(layers "F.Cu" "B.Cu")
		(net "GND")
	)
	(via
		(at 257.302 -58.801)
		(size 0.508)
		(drill 0.254)
		(layers "F.Cu" "B.Cu")
		(net "GND")
	)
	(via
		(at 190.373 -58.039)
		(size 0.508)
		(drill 0.254)
		(layers "F.Cu" "B.Cu")
		(net "GND")
	)
	(via
		(at 442.495686 -87.68969)
		(size 0.508)
		(drill 0.254)
		(layers "F.Cu" "B.Cu")
		(net "GND")
	)
	(via
		(at 413.98698 -26.47696)
		(size 0.508)
		(drill 0.254)
		(layers "F.Cu" "B.Cu")
		(net "GND")
	)
	(via
		(at 103.6574 -57.023)
		(size 0.508)
		(drill 0.254)
		(layers "F.Cu" "B.Cu")
		(net "GND")
	)
	(via
		(at 256.54 -58.039)
		(size 0.508)
		(drill 0.254)
		(layers "F.Cu" "B.Cu")
		(net "GND")
	)
	(via
		(at 284.39872 -102.23754)
		(size 0.508)
		(drill 0.254)
		(layers "F.Cu" "B.Cu")
		(net "GND")
	)
	(via
		(at 58.376566 -26.266648)
		(size 0.508)
		(drill 0.254)
		(layers "F.Cu" "B.Cu")
		(net "GND")
	)
	(via
		(at 378.947172 -26.612342)
		(size 0.508)
		(drill 0.254)
		(layers "F.Cu" "B.Cu")
		(net "GND")
	)
	(via
		(at 44.393612 -170.885866)
		(size 0.508)
		(drill 0.254)
		(layers "F.Cu" "B.Cu")
		(net "GND")
	)
	(via
		(at 119.112284 -90.682064)
		(size 0.508)
		(drill 0.254)
		(layers "F.Cu" "B.Cu")
		(net "GND")
	)
	(via
		(at 475.236032 -100.866448)
		(size 0.508)
		(drill 0.254)
		(layers "F.Cu" "B.Cu")
		(net "GND")
	)
	(via
		(at 475.236032 -126.266448)
		(size 0.508)
		(drill 0.254)
		(layers "F.Cu" "B.Cu")
		(net "GND")
	)
	(via
		(at 402.800566 -170.885612)
		(size 0.508)
		(drill 0.254)
		(layers "F.Cu" "B.Cu")
		(net "GND")
	)
	(via
		(at 414.42259 -47.949358)
		(size 0.508)
		(drill 0.254)
		(layers "F.Cu" "B.Cu")
		(net "GND")
	)
	(via
		(at 328.196702 -95.329248)
		(size 0.508)
		(drill 0.254)
		(layers "F.Cu" "B.Cu")
		(net "GND")
	)
	(via
		(at 443.843664 -88.466422)
		(size 0.508)
		(drill 0.254)
		(layers "F.Cu" "B.Cu")
		(net "GND")
	)
	(via
		(at 121.83872 -102.23754)
		(size 0.508)
		(drill 0.254)
		(layers "F.Cu" "B.Cu")
		(net "GND")
	)
	(via
		(at 312.91022 -91.223592)
		(size 0.508)
		(drill 0.254)
		(layers "F.Cu" "B.Cu")
		(net "GND")
	)
	(via
		(at 0.766572 -46.71822)
		(size 0.508)
		(drill 0.254)
		(layers "F.Cu" "B.Cu")
		(net "GND")
	)
	(via
		(at 189.611 -58.801)
		(size 0.508)
		(drill 0.254)
		(layers "F.Cu" "B.Cu")
		(net "GND")
	)
	(via
		(at 449.072 -47.56404)
		(size 0.508)
		(drill 0.254)
		(layers "F.Cu" "B.Cu")
		(net "GND")
	)
	(via
		(at 279.31872 -102.23754)
		(size 0.508)
		(drill 0.254)
		(layers "F.Cu" "B.Cu")
		(net "GND")
	)
	(via
		(at 334.356964 -9.774428)
		(size 0.508)
		(drill 0.254)
		(layers "F.Cu" "B.Cu")
		(net "GND")
	)
	(via
		(at 419.35146 -30.996636)
		(size 0.508)
		(drill 0.254)
		(layers "F.Cu" "B.Cu")
		(net "GND")
	)
	(via
		(at 315.70422 -91.223592)
		(size 0.508)
		(drill 0.254)
		(layers "F.Cu" "B.Cu")
		(net "GND")
	)
	(via
		(at 322.672964 -9.774428)
		(size 0.508)
		(drill 0.254)
		(layers "F.Cu" "B.Cu")
		(net "GND")
	)
	(via
		(at 383.14884 -0.762762)
		(size 0.508)
		(drill 0.254)
		(layers "F.Cu" "B.Cu")
		(net "GND")
	)
	(via
		(at 162.47872 -102.23754)
		(size 0.508)
		(drill 0.254)
		(layers "F.Cu" "B.Cu")
		(net "GND")
	)
	(via
		(at 164.029136 -11.049)
		(size 0.508)
		(drill 0.254)
		(layers "F.Cu" "B.Cu")
		(net "GND")
	)
	(via
		(at 168.529 -79.121)
		(size 0.508)
		(drill 0.254)
		(layers "F.Cu" "B.Cu")
		(net "GND")
	)
	(via
		(at 249.047 -58.039)
		(size 0.508)
		(drill 0.254)
		(layers "F.Cu" "B.Cu")
		(net "GND")
	)
	(via
		(at 60.313062 -24.32812)
		(size 0.508)
		(drill 0.254)
		(layers "F.Cu" "B.Cu")
		(net "GND")
	)
	(via
		(at 450.469 -30.734)
		(size 0.508)
		(drill 0.254)
		(layers "F.Cu" "B.Cu")
		(net "GND")
	)
	(via
		(at 185.166 -58.801)
		(size 0.508)
		(drill 0.254)
		(layers "F.Cu" "B.Cu")
		(net "GND")
	)
	(via
		(at 118.350284 -86.668864)
		(size 0.508)
		(drill 0.254)
		(layers "F.Cu" "B.Cu")
		(net "GND")
	)
	(via
		(at 254.254 -58.801)
		(size 0.508)
		(drill 0.254)
		(layers "F.Cu" "B.Cu")
		(net "GND")
	)
	(via
		(at 273.685 -10.287)
		(size 0.508)
		(drill 0.254)
		(layers "F.Cu" "B.Cu")
		(net "GND")
	)
	(via
		(at 52.085494 -17.145)
		(size 0.508)
		(drill 0.254)
		(layers "F.Cu" "B.Cu")
		(net "GND")
	)
	(via
		(at 382.480566 -170.885612)
		(size 0.508)
		(drill 0.254)
		(layers "F.Cu" "B.Cu")
		(net "GND")
	)
	(via
		(at 169.672 -79.121)
		(size 0.508)
		(drill 0.254)
		(layers "F.Cu" "B.Cu")
		(net "GND")
	)
	(via
		(at 54.553612 -170.885866)
		(size 0.508)
		(drill 0.254)
		(layers "F.Cu" "B.Cu")
		(net "GND")
	)
	(via
		(at 360.50474 -10.282174)
		(size 0.508)
		(drill 0.254)
		(layers "F.Cu" "B.Cu")
		(net "GND")
	)
	(via
		(at 87.734648 -120.654318)
		(size 0.508)
		(drill 0.254)
		(layers "F.Cu" "B.Cu")
		(net "GND")
	)
	(via
		(at 416.231578 -33.770316)
		(size 0.508)
		(drill 0.254)
		(layers "F.Cu" "B.Cu")
		(net "GND")
	)
	(via
		(at 378.46 -21.336)
		(size 0.508)
		(drill 0.254)
		(layers "F.Cu" "B.Cu")
		(net "GND")
	)
	(via
		(at 273.685 -11.049)
		(size 0.508)
		(drill 0.254)
		(layers "F.Cu" "B.Cu")
		(net "GND")
	)
	(via
		(at 450.215 -44.196)
		(size 0.508)
		(drill 0.254)
		(layers "F.Cu" "B.Cu")
		(net "GND")
	)
	(via
		(at 185.928 -58.039)
		(size 0.508)
		(drill 0.254)
		(layers "F.Cu" "B.Cu")
		(net "GND")
	)
	(via
		(at 228.51872 -102.23754)
		(size 0.508)
		(drill 0.254)
		(layers "F.Cu" "B.Cu")
		(net "GND")
	)
	(via
		(at 88.906096 -106.25709)
		(size 0.508)
		(drill 0.254)
		(layers "F.Cu" "B.Cu")
		(net "GND")
	)
	(via
		(at 96.060768 -9.757918)
		(size 0.508)
		(drill 0.254)
		(layers "F.Cu" "B.Cu")
		(net "GND")
	)
	(via
		(at 87.734648 -140.974318)
		(size 0.508)
		(drill 0.254)
		(layers "F.Cu" "B.Cu")
		(net "GND")
	)
	(via
		(at 419.7604 -53.848)
		(size 0.508)
		(drill 0.254)
		(layers "F.Cu" "B.Cu")
		(net "GND")
	)
	(via
		(at 19.16557 -157.529276)
		(size 0.508)
		(drill 0.254)
		(layers "F.Cu" "B.Cu")
		(net "GND")
	)
	(via
		(at 322.92036 -96.465136)
		(size 0.508)
		(drill 0.254)
		(layers "F.Cu" "B.Cu")
		(net "GND")
	)
	(via
		(at 248.83872 -102.23754)
		(size 0.508)
		(drill 0.254)
		(layers "F.Cu" "B.Cu")
		(net "GND")
	)
	(via
		(at 31.724854 -162.58667)
		(size 0.508)
		(drill 0.254)
		(layers "F.Cu" "B.Cu")
		(net "GND")
	)
	(via
		(at 198.03872 -102.23754)
		(size 0.508)
		(drill 0.254)
		(layers "F.Cu" "B.Cu")
		(net "GND")
	)
	(via
		(at 233.59872 -102.23754)
		(size 0.508)
		(drill 0.254)
		(layers "F.Cu" "B.Cu")
		(net "GND")
	)
	(via
		(at 428.237904 -40.386)
		(size 0.508)
		(drill 0.254)
		(layers "F.Cu" "B.Cu")
		(net "GND")
	)
	(via
		(at 312.14822 -90.461592)
		(size 0.508)
		(drill 0.254)
		(layers "F.Cu" "B.Cu")
		(net "GND")
	)
	(via
		(at 440.309 -44.13504)
		(size 0.508)
		(drill 0.254)
		(layers "F.Cu" "B.Cu")
		(net "GND")
	)
	(via
		(at 157.598364 -62.697106)
		(size 0.508)
		(drill 0.254)
		(layers "F.Cu" "B.Cu")
		(net "GND")
	)
	(via
		(at 434.007768 -157.528514)
		(size 0.508)
		(drill 0.254)
		(layers "F.Cu" "B.Cu")
		(net "GND")
	)
	(via
		(at 52.085494 -18.161)
		(size 0.508)
		(drill 0.254)
		(layers "F.Cu" "B.Cu")
		(net "GND")
	)
	(via
		(at 423.418 -35.052)
		(size 0.508)
		(drill 0.254)
		(layers "F.Cu" "B.Cu")
		(net "GND")
	)
	(via
		(at 475.236032 -80.546448)
		(size 0.508)
		(drill 0.254)
		(layers "F.Cu" "B.Cu")
		(net "GND")
	)
	(via
		(at 165.553136 -10.287)
		(size 0.508)
		(drill 0.254)
		(layers "F.Cu" "B.Cu")
		(net "GND")
	)
	(via
		(at 321.65036 -90.496136)
		(size 0.508)
		(drill 0.254)
		(layers "F.Cu" "B.Cu")
		(net "GND")
	)
	(via
		(at 439.270394 -40.426894)
		(size 0.508)
		(drill 0.254)
		(layers "F.Cu" "B.Cu")
		(net "GND")
	)
	(via
		(at 442.1124 -60.452)
		(size 0.508)
		(drill 0.254)
		(layers "F.Cu" "B.Cu")
		(net "GND")
	)
	(via
		(at 444.827406 -87.687658)
		(size 0.508)
		(drill 0.254)
		(layers "F.Cu" "B.Cu")
		(net "GND")
	)
	(via
		(at 39.313612 -170.885866)
		(size 0.508)
		(drill 0.254)
		(layers "F.Cu" "B.Cu")
		(net "GND")
	)
	(via
		(at 451.1294 -93.599)
		(size 0.508)
		(drill 0.254)
		(layers "F.Cu" "B.Cu")
		(net "GND")
	)
	(via
		(at 0.766572 -153.39822)
		(size 0.508)
		(drill 0.254)
		(layers "F.Cu" "B.Cu")
		(net "GND")
	)
	(via
		(at 344.24874 -9.878822)
		(size 0.508)
		(drill 0.254)
		(layers "F.Cu" "B.Cu")
		(net "GND")
	)
	(via
		(at 475.236032 -105.946448)
		(size 0.508)
		(drill 0.254)
		(layers "F.Cu" "B.Cu")
		(net "GND")
	)
	(via
		(at 274.447 -25.146)
		(size 0.508)
		(drill 0.254)
		(layers "F.Cu" "B.Cu")
		(net "GND")
	)
	(via
		(at 407.9494 -20.828)
		(size 0.508)
		(drill 0.254)
		(layers "F.Cu" "B.Cu")
		(net "GND")
	)
	(via
		(at 59.633612 -170.885866)
		(size 0.508)
		(drill 0.254)
		(layers "F.Cu" "B.Cu")
		(net "GND")
	)
	(via
		(at 255.016 -58.801)
		(size 0.508)
		(drill 0.254)
		(layers "F.Cu" "B.Cu")
		(net "GND")
	)
	(via
		(at 448.677538 -60.908692)
		(size 0.508)
		(drill 0.254)
		(layers "F.Cu" "B.Cu")
		(net "GND")
	)
	(via
		(at 292.700964 -9.901428)
		(size 0.508)
		(drill 0.254)
		(layers "F.Cu" "B.Cu")
		(net "GND")
	)
	(via
		(at 439.6994 -100.965)
		(size 0.508)
		(drill 0.254)
		(layers "F.Cu" "B.Cu")
		(net "GND")
	)
	(via
		(at 290.3474 -81.915)
		(size 0.508)
		(drill 0.254)
		(layers "F.Cu" "B.Cu")
		(net "GND")
	)
	(via
		(at 116.572284 -85.906864)
		(size 0.508)
		(drill 0.254)
		(layers "F.Cu" "B.Cu")
		(net "GND")
	)
	(via
		(at 87.734648 -135.894318)
		(size 0.508)
		(drill 0.254)
		(layers "F.Cu" "B.Cu")
		(net "GND")
	)
	(via
		(at 443.206886 -86.29269)
		(size 0.508)
		(drill 0.254)
		(layers "F.Cu" "B.Cu")
		(net "GND")
	)
	(via
		(at 451.474586 -84.409788)
		(size 0.508)
		(drill 0.254)
		(layers "F.Cu" "B.Cu")
		(net "GND")
	)
	(via
		(at 330.11872 -102.23754)
		(size 0.508)
		(drill 0.254)
		(layers "F.Cu" "B.Cu")
		(net "GND")
	)
	(via
		(at 448.056 -27.178)
		(size 0.508)
		(drill 0.254)
		(layers "F.Cu" "B.Cu")
		(net "GND")
	)
	(via
		(at 0.766572 -133.07822)
		(size 0.508)
		(drill 0.254)
		(layers "F.Cu" "B.Cu")
		(net "GND")
	)
	(via
		(at 352.268028 -125.612906)
		(size 0.508)
		(drill 0.254)
		(layers "F.Cu" "B.Cu")
		(net "GND")
	)
	(via
		(at 408.54884 -0.762762)
		(size 0.508)
		(drill 0.254)
		(layers "F.Cu" "B.Cu")
		(net "GND")
	)
	(via
		(at 461.125316 -130.999484)
		(size 0.508)
		(drill 0.254)
		(layers "F.Cu" "B.Cu")
		(net "GND")
	)
	(via
		(at 475.236032 -70.386448)
		(size 0.508)
		(drill 0.254)
		(layers "F.Cu" "B.Cu")
		(net "GND")
	)
	(via
		(at 393.30884 -0.762762)
		(size 0.508)
		(drill 0.254)
		(layers "F.Cu" "B.Cu")
		(net "GND")
	)
	(via
		(at 52.085494 -22.733)
		(size 0.508)
		(drill 0.254)
		(layers "F.Cu" "B.Cu")
		(net "GND")
	)
	(via
		(at 310.861964 -9.774428)
		(size 0.508)
		(drill 0.254)
		(layers "F.Cu" "B.Cu")
		(net "GND")
	)
	(via
		(at 115.810284 -85.906864)
		(size 0.508)
		(drill 0.254)
		(layers "F.Cu" "B.Cu")
		(net "GND")
	)
	(via
		(at 439.0644 -100.965)
		(size 0.508)
		(drill 0.254)
		(layers "F.Cu" "B.Cu")
		(net "GND")
	)
	(via
		(at 296.05605 -86.487)
		(size 0.508)
		(drill 0.254)
		(layers "F.Cu" "B.Cu")
		(net "GND")
	)
	(via
		(at 451.1294 -94.361)
		(size 0.508)
		(drill 0.254)
		(layers "F.Cu" "B.Cu")
		(net "GND")
	)
	(via
		(at 7.800086 -0.765556)
		(size 0.508)
		(drill 0.254)
		(layers "F.Cu" "B.Cu")
		(net "GND")
	)
	(via
		(at 126.726442 -9.513824)
		(size 0.508)
		(drill 0.254)
		(layers "F.Cu" "B.Cu")
		(net "GND")
	)
	(via
		(at 352.268028 -140.852906)
		(size 0.508)
		(drill 0.254)
		(layers "F.Cu" "B.Cu")
		(net "GND")
	)
	(via
		(at 475.236032 -39.906448)
		(size 0.508)
		(drill 0.254)
		(layers "F.Cu" "B.Cu")
		(net "GND")
	)
	(via
		(at 439.23077 -11.518138)
		(size 0.508)
		(drill 0.254)
		(layers "F.Cu" "B.Cu")
		(net "GND")
	)
	(via
		(at 293.462964 -9.901428)
		(size 0.508)
		(drill 0.254)
		(layers "F.Cu" "B.Cu")
		(net "GND")
	)
	(via
		(at 52.0954 -31.242)
		(size 0.508)
		(drill 0.254)
		(layers "F.Cu" "B.Cu")
		(net "GND")
	)
	(via
		(at 321.148964 -9.774428)
		(size 0.508)
		(drill 0.254)
		(layers "F.Cu" "B.Cu")
		(net "GND")
	)
	(via
		(at 191.897 -58.801)
		(size 0.508)
		(drill 0.254)
		(layers "F.Cu" "B.Cu")
		(net "GND")
	)
	(via
		(at 475.236032 -65.306448)
		(size 0.508)
		(drill 0.254)
		(layers "F.Cu" "B.Cu")
		(net "GND")
	)
	(via
		(at 327.434702 -94.567248)
		(size 0.508)
		(drill 0.254)
		(layers "F.Cu" "B.Cu")
		(net "GND")
	)
	(via
		(at 275.971 -11.049)
		(size 0.508)
		(drill 0.254)
		(layers "F.Cu" "B.Cu")
		(net "GND")
	)
	(via
		(at 428.237904 -45.974)
		(size 0.508)
		(drill 0.254)
		(layers "F.Cu" "B.Cu")
		(net "GND")
	)
	(via
		(at 118.350284 -90.682064)
		(size 0.508)
		(drill 0.254)
		(layers "F.Cu" "B.Cu")
		(net "GND")
	)
	(via
		(at 360.76509 -166.468552)
		(size 0.508)
		(drill 0.254)
		(layers "F.Cu" "B.Cu")
		(net "GND")
	)
	(via
		(at 124.440442 -9.513824)
		(size 0.508)
		(drill 0.254)
		(layers "F.Cu" "B.Cu")
		(net "GND")
	)
	(via
		(at 408.7114 -17.653)
		(size 0.508)
		(drill 0.254)
		(layers "F.Cu" "B.Cu")
		(net "GND")
	)
	(via
		(at 34.88817 -30.607)
		(size 0.508)
		(drill 0.254)
		(layers "F.Cu" "B.Cu")
		(net "GND")
	)
	(via
		(at 389.0264 -24.623014)
		(size 0.508)
		(drill 0.254)
		(layers "F.Cu" "B.Cu")
		(net "GND")
	)
	(via
		(at 475.236032 -60.226448)
		(size 0.508)
		(drill 0.254)
		(layers "F.Cu" "B.Cu")
		(net "GND")
	)
	(via
		(at 167.077136 -24.384)
		(size 0.508)
		(drill 0.254)
		(layers "F.Cu" "B.Cu")
		(net "GND")
	)
	(via
		(at 249.809 -58.039)
		(size 0.508)
		(drill 0.254)
		(layers "F.Cu" "B.Cu")
		(net "GND")
	)
	(via
		(at 422.148 -26.924)
		(size 0.508)
		(drill 0.254)
		(layers "F.Cu" "B.Cu")
		(net "GND")
	)
	(via
		(at 291.338 -86.995)
		(size 0.508)
		(drill 0.254)
		(layers "F.Cu" "B.Cu")
		(net "GND")
	)
	(via
		(at 436.9054 -45.593)
		(size 0.508)
		(drill 0.254)
		(layers "F.Cu" "B.Cu")
		(net "GND")
	)
	(via
		(at 469.265 -110.998)
		(size 0.508)
		(drill 0.254)
		(layers "F.Cu" "B.Cu")
		(net "GND")
	)
	(via
		(at 475.236032 -50.066448)
		(size 0.508)
		(drill 0.254)
		(layers "F.Cu" "B.Cu")
		(net "GND")
	)
	(via
		(at 299.339 -93.65996)
		(size 0.508)
		(drill 0.254)
		(layers "F.Cu" "B.Cu")
		(net "GND")
	)
	(via
		(at 223.43872 -102.23754)
		(size 0.508)
		(drill 0.254)
		(layers "F.Cu" "B.Cu")
		(net "GND")
	)
	(via
		(at 443.968886 -84.87029)
		(size 0.508)
		(drill 0.254)
		(layers "F.Cu" "B.Cu")
		(net "GND")
	)
	(via
		(at 264.07872 -102.23754)
		(size 0.508)
		(drill 0.254)
		(layers "F.Cu" "B.Cu")
		(net "GND")
	)
	(via
		(at 274.447 -11.049)
		(size 0.508)
		(drill 0.254)
		(layers "F.Cu" "B.Cu")
		(net "GND")
	)
	(via
		(at 454.5584 -61.849)
		(size 0.508)
		(drill 0.254)
		(layers "F.Cu" "B.Cu")
		(net "GND")
	)
	(via
		(at 184.404 -58.039)
		(size 0.508)
		(drill 0.254)
		(layers "F.Cu" "B.Cu")
		(net "GND")
	)
	(via
		(at 441.63996 -48.641)
		(size 0.508)
		(drill 0.254)
		(layers "F.Cu" "B.Cu")
		(net "GND")
	)
	(via
		(at 82.296 -19.558)
		(size 0.508)
		(drill 0.254)
		(layers "F.Cu" "B.Cu")
		(net "GND")
	)
	(via
		(at 378.947172 -28.136342)
		(size 0.508)
		(drill 0.254)
		(layers "F.Cu" "B.Cu")
		(net "GND")
	)
	(via
		(at 443.206886 -85.58149)
		(size 0.508)
		(drill 0.254)
		(layers "F.Cu" "B.Cu")
		(net "GND")
	)
	(via
		(at 250.571 -58.039)
		(size 0.508)
		(drill 0.254)
		(layers "F.Cu" "B.Cu")
		(net "GND")
	)
	(via
		(at 116.75872 -102.23754)
		(size 0.508)
		(drill 0.254)
		(layers "F.Cu" "B.Cu")
		(net "GND")
	)
	(via
		(at 409.9814 -29.21)
		(size 0.508)
		(drill 0.254)
		(layers "F.Cu" "B.Cu")
		(net "GND")
	)
	(via
		(at 299.63872 -102.23754)
		(size 0.508)
		(drill 0.254)
		(layers "F.Cu" "B.Cu")
		(net "GND")
	)
	(via
		(at 284.988 -93.02496)
		(size 0.508)
		(drill 0.254)
		(layers "F.Cu" "B.Cu")
		(net "GND")
	)
	(via
		(at 410.4132 -21.0058)
		(size 0.508)
		(drill 0.254)
		(layers "F.Cu" "B.Cu")
		(net "GND")
	)
	(via
		(at 59.297062 -24.32812)
		(size 0.508)
		(drill 0.254)
		(layers "F.Cu" "B.Cu")
		(net "GND")
	)
	(via
		(at 406.9334 -15.875)
		(size 0.508)
		(drill 0.254)
		(layers "F.Cu" "B.Cu")
		(net "GND")
	)
	(via
		(at 408.7114 -20.828)
		(size 0.508)
		(drill 0.254)
		(layers "F.Cu" "B.Cu")
		(net "GND")
	)
	(via
		(at 433.94884 -0.762762)
		(size 0.508)
		(drill 0.254)
		(layers "F.Cu" "B.Cu")
		(net "GND")
	)
	(via
		(at 320.12636 -90.496136)
		(size 0.508)
		(drill 0.254)
		(layers "F.Cu" "B.Cu")
		(net "GND")
	)
	(via
		(at 356.37089 -157.525974)
		(size 0.508)
		(drill 0.254)
		(layers "F.Cu" "B.Cu")
		(net "GND")
	)
	(via
		(at 408.7114 -22.606)
		(size 0.508)
		(drill 0.254)
		(layers "F.Cu" "B.Cu")
		(net "GND")
	)
	(via
		(at 397.720566 -170.885612)
		(size 0.508)
		(drill 0.254)
		(layers "F.Cu" "B.Cu")
		(net "GND")
	)
	(via
		(at 451.493128 -83.393788)
		(size 0.508)
		(drill 0.254)
		(layers "F.Cu" "B.Cu")
		(net "GND")
	)
	(via
		(at 409.835858 -159.31388)
		(size 0.508)
		(drill 0.254)
		(layers "F.Cu" "B.Cu")
		(net "GND")
	)
	(via
		(at 443.968886 -85.58149)
		(size 0.508)
		(drill 0.254)
		(layers "F.Cu" "B.Cu")
		(net "GND")
	)
	(via
		(at 439.270394 -36.489894)
		(size 0.508)
		(drill 0.254)
		(layers "F.Cu" "B.Cu")
		(net "GND")
	)
	(via
		(at 125.202442 -9.513824)
		(size 0.508)
		(drill 0.254)
		(layers "F.Cu" "B.Cu")
		(net "GND")
	)
	(via
		(at 475.236032 -85.626448)
		(size 0.508)
		(drill 0.254)
		(layers "F.Cu" "B.Cu")
		(net "GND")
	)
	(via
		(at 0.766572 -138.15822)
		(size 0.508)
		(drill 0.254)
		(layers "F.Cu" "B.Cu")
		(net "GND")
	)
	(via
		(at 165.553136 -24.384)
		(size 0.508)
		(drill 0.254)
		(layers "F.Cu" "B.Cu")
		(net "GND")
	)
	(via
		(at 439.6994 -98.425)
		(size 0.508)
		(drill 0.254)
		(layers "F.Cu" "B.Cu")
		(net "GND")
	)
	(via
		(at 174.9806 -46.80204)
		(size 0.508)
		(drill 0.254)
		(layers "F.Cu" "B.Cu")
		(net "GND")
	)
	(via
		(at 79.950564 -9.959594)
		(size 0.508)
		(drill 0.254)
		(layers "F.Cu" "B.Cu")
		(net "GND")
	)
	(via
		(at 327.434702 -96.091248)
		(size 0.508)
		(drill 0.254)
		(layers "F.Cu" "B.Cu")
		(net "GND")
	)
	(via
		(at 58.376566 -25.273762)
		(size 0.508)
		(drill 0.254)
		(layers "F.Cu" "B.Cu")
		(net "GND")
	)
	(via
		(at 167.077136 -25.146)
		(size 0.508)
		(drill 0.254)
		(layers "F.Cu" "B.Cu")
		(net "GND")
	)
	(via
		(at 439.23585 -142.938754)
		(size 0.508)
		(drill 0.254)
		(layers "F.Cu" "B.Cu")
		(net "GND")
	)
	(via
		(at 443.968886 -87.71509)
		(size 0.508)
		(drill 0.254)
		(layers "F.Cu" "B.Cu")
		(net "GND")
	)
	(via
		(at 475.236032 -34.826448)
		(size 0.508)
		(drill 0.254)
		(layers "F.Cu" "B.Cu")
		(net "GND")
	)
	(via
		(at 352.268028 -110.372906)
		(size 0.508)
		(drill 0.254)
		(layers "F.Cu" "B.Cu")
		(net "GND")
	)
	(via
		(at 101.51872 -102.23754)
		(size 0.508)
		(drill 0.254)
		(layers "F.Cu" "B.Cu")
		(net "GND")
	)
	(via
		(at 274.23872 -102.23754)
		(size 0.508)
		(drill 0.254)
		(layers "F.Cu" "B.Cu")
		(net "GND")
	)
	(via
		(at 81.474564 -9.959594)
		(size 0.508)
		(drill 0.254)
		(layers "F.Cu" "B.Cu")
		(net "GND")
	)
	(via
		(at 335.19872 -102.23754)
		(size 0.508)
		(drill 0.254)
		(layers "F.Cu" "B.Cu")
		(net "GND")
	)
	(via
		(at 316.46622 -90.461592)
		(size 0.508)
		(drill 0.254)
		(layers "F.Cu" "B.Cu")
		(net "GND")
	)
	(via
		(at 405.11222 -29.21)
		(size 0.508)
		(drill 0.254)
		(layers "F.Cu" "B.Cu")
		(net "GND")
	)
	(via
		(at 191.135 -58.039)
		(size 0.508)
		(drill 0.254)
		(layers "F.Cu" "B.Cu")
		(net "GND")
	)
	(via
		(at 182.753 -80.137)
		(size 0.508)
		(drill 0.254)
		(layers "F.Cu" "B.Cu")
		(net "GND")
	)
	(via
		(at 411.1752 -21.0058)
		(size 0.508)
		(drill 0.254)
		(layers "F.Cu" "B.Cu")
		(net "GND")
	)
	(via
		(at 290.449 -63.881)
		(size 0.508)
		(drill 0.254)
		(layers "F.Cu" "B.Cu")
		(net "GND")
	)
	(via
		(at 274.447 -24.384)
		(size 0.508)
		(drill 0.254)
		(layers "F.Cu" "B.Cu")
		(net "GND")
	)
	(via
		(at 106.59872 -102.23754)
		(size 0.508)
		(drill 0.254)
		(layers "F.Cu" "B.Cu")
		(net "GND")
	)
	(via
		(at 0.766572 -26.39822)
		(size 0.508)
		(drill 0.254)
		(layers "F.Cu" "B.Cu")
		(net "GND")
	)
	(via
		(at 378.185172 -27.374342)
		(size 0.508)
		(drill 0.254)
		(layers "F.Cu" "B.Cu")
		(net "GND")
	)
	(segment
		(start 291.479986 -87.136986)
		(end 291.338 -86.995)
		(width 0.4572)
		(layer "B.Cu")
		(net "GND")
	)
	(segment
		(start 289.306 -92.47505)
		(end 289.306 -93.091)
		(width 0.4572)
		(layer "B.Cu")
		(net "GND")
	)
	(segment
		(start 417.931854 -32.359346)
		(end 417.900358 -32.359346)
		(width 0.3556)
		(layer "B.Cu")
		(net "GND")
	)
	(segment
		(start 157.681676 -59.89066)
		(end 158.061152 -59.89066)
		(width 0.4572)
		(layer "B.Cu")
		(net "GND")
	)
	(segment
		(start 344.1192 -40.7162)
		(end 344.1954 -40.64)
		(width 0.4572)
		(layer "B.Cu")
		(net "GND")
	)
	(segment
		(start 342.138 -40.7162)
		(end 344.1192 -40.7162)
		(width 0.4572)
		(layer "B.Cu")
		(net "GND")
	)
	(segment
		(start 418.550598 -31.740602)
		(end 417.931854 -32.359346)
		(width 0.3556)
		(layer "B.Cu")
		(net "GND")
	)
	(segment
		(start 261.3914 -52.959)
		(end 261.6454 -52.705)
		(width 0.4572)
		(layer "B.Cu")
		(net "GND")
	)
	(segment
		(start 179.68595 -52.832)
		(end 179.230274 -52.832)
		(width 0.4572)
		(layer "B.Cu")
		(net "GND")
	)
	(segment
		(start 342.138 -51.9176)
		(end 344.17 -51.9176)
		(width 0.4572)
		(layer "B.Cu")
		(net "GND")
	)
	(segment
		(start 298.718986 -93.65996)
		(end 299.339 -93.65996)
		(width 0.4572)
		(layer "B.Cu")
		(net "GND")
	)
	(segment
		(start 290.986972 -77.510894)
		(end 289.9664 -77.510894)
		(width 0.381)
		(layer "B.Cu")
		(net "GND")
	)
	(segment
		(start 281.178 -91.7956)
		(end 281.178 -92.329)
		(width 0.4572)
		(layer "B.Cu")
		(net "GND")
	)
	(segment
		(start 444.341504 -48.57496)
		(end 443.484 -48.57496)
		(width 0.4572)
		(layer "B.Cu")
		(net "GND")
	)
	(segment
		(start 427.856904 -37.973)
		(end 428.237904 -37.592)
		(width 0.4572)
		(layer "B.Cu")
		(net "GND")
	)
	(segment
		(start 293.2684 -80.7593)
		(end 293.2684 -81.5467)
		(width 0.4572)
		(layer "B.Cu")
		(net "GND")
	)
	(segment
		(start 179.230274 -52.832)
		(end 178.8668 -52.468526)
		(width 0.4572)
		(layer "B.Cu")
		(net "GND")
	)
	(segment
		(start 417.449 -44.043092)
		(end 418.973 -44.043092)
		(width 0.3556)
		(layer "B.Cu")
		(net "GND")
	)
	(segment
		(start 418.550598 -30.940248)
		(end 418.550598 -31.740602)
		(width 0.3556)
		(layer "B.Cu")
		(net "GND")
	)
	(segment
		(start 284.169104 -93.02496)
		(end 284.988 -93.02496)
		(width 0.4572)
		(layer "B.Cu")
		(net "GND")
	)
	(segment
		(start 261.6454 -52.705)
		(end 261.6454 -51.9684)
		(width 0.4572)
		(layer "B.Cu")
		(net "GND")
	)
	(segment
		(start 156.633164 -62.697106)
		(end 157.598364 -62.697106)
		(width 0.381)
		(layer "B.Cu")
		(net "GND")
	)
	(segment
		(start 261.6454 -51.9684)
		(end 261.366 -51.689)
		(width 0.4572)
		(layer "B.Cu")
		(net "GND")
	)
	(segment
		(start 426.99305 -37.973)
		(end 427.856904 -37.973)
		(width 0.4572)
		(layer "B.Cu")
		(net "GND")
	)
	(segment
		(start 422.70045 -35.052)
		(end 423.418 -35.052)
		(width 0.4572)
		(layer "B.Cu")
		(net "GND")
	)
	(segment
		(start 296.05605 -85.852)
		(end 296.05605 -86.487)
		(width 0.4572)
		(layer "B.Cu")
		(net "GND")
	)
	(segment
		(start 105.4608 -57.023)
		(end 103.6574 -57.023)
		(width 0.508)
		(layer "B.Cu")
		(net "GND")
	)
	(segment
		(start 292.16604 -87.136986)
		(end 291.479986 -87.136986)
		(width 0.4572)
		(layer "B.Cu")
		(net "GND")
	)
	(segment
		(start 281.178 -92.329)
		(end 280.924 -92.583)
		(width 0.4572)
		(layer "B.Cu")
		(net "GND")
	)
	(segment
		(start 297.307 -89.76995)
		(end 297.307 -89.1794)
		(width 0.4572)
		(layer "B.Cu")
		(net "GND")
	)
	(segment
		(start 297.307 -89.1794)
		(end 297.6118 -88.8746)
		(width 0.4572)
		(layer "B.Cu")
		(net "GND")
	)
	(segment
		(start 288.29 -92.47505)
		(end 288.29 -93.091)
		(width 0.4572)
		(layer "B.Cu")
		(net "GND")
	)
	(segment
		(start 154.351736 -59.4487)
		(end 157.239716 -59.4487)
		(width 0.4572)
		(layer "B.Cu")
		(net "GND")
	)
	(segment
		(start 261.02945 -52.959)
		(end 261.3914 -52.959)
		(width 0.4572)
		(layer "B.Cu")
		(net "GND")
	)
	(segment
		(start 449.59905 -46.736)
		(end 449.59905 -46.101)
		(width 0.4572)
		(layer "B.Cu")
		(net "GND")
	)
	(segment
		(start 282.575 -91.96705)
		(end 282.575 -92.6338)
		(width 0.4572)
		(layer "B.Cu")
		(net "GND")
	)
	(segment
		(start 178.8668 -52.468526)
		(end 178.8668 -51.562)
		(width 0.4572)
		(layer "B.Cu")
		(net "GND")
	)
	(segment
		(start 157.239716 -59.4487)
		(end 157.681676 -59.89066)
		(width 0.4572)
		(layer "B.Cu")
		(net "GND")
	)
	(segment
		(start 105.4608 -45.7454)
		(end 103.6574 -45.7454)
		(width 0.4572)
		(layer "B.Cu")
		(net "GND")
	)
	(segment
		(start 42.36339 -111.879888)
		(end 41.557956 -111.074454)
		(width 0.508)
		(layer "In1.Cu")
		(net "GND")
	)
	(segment
		(start 42.36339 -111.879888)
		(end 41.557956 -112.685322)
		(width 0.508)
		(layer "In1.Cu")
		(net "GND")
	)
	(segment
		(start 378.884434 -70.434454)
		(end 378.079 -71.239888)
		(width 0.508)
		(layer "In1.Cu")
		(net "GND")
	)
	(segment
		(start 61.92139 -50.919888)
		(end 61.115956 -51.725322)
		(width 0.508)
		(layer "In1.Cu")
		(net "GND")
	)
	(segment
		(start 42.36339 -71.239888)
		(end 41.557956 -72.045322)
		(width 0.508)
		(layer "In1.Cu")
		(net "GND")
	)
	(segment
		(start 43.168824 -70.434454)
		(end 42.36339 -71.239888)
		(width 0.508)
		(layer "In1.Cu")
		(net "GND")
	)
	(segment
		(start 398.442434 -133.005322)
		(end 397.637 -132.199888)
		(width 0.508)
		(layer "In1.Cu")
		(net "GND")
	)
	(segment
		(start 61.92139 -91.559888)
		(end 61.115956 -90.754454)
		(width 0.508)
		(layer "In1.Cu")
		(net "GND")
	)
	(segment
		(start 378.079 -50.919888)
		(end 377.273566 -51.725322)
		(width 0.508)
		(layer "In1.Cu")
		(net "GND")
	)
	(segment
		(start 43.168824 -51.725322)
		(end 42.36339 -50.919888)
		(width 0.508)
		(layer "In1.Cu")
		(net "GND")
	)
	(segment
		(start 378.884434 -111.074454)
		(end 378.079 -111.879888)
		(width 0.508)
		(layer "In1.Cu")
		(net "GND")
	)
	(segment
		(start 43.168824 -92.365322)
		(end 42.36339 -91.559888)
		(width 0.508)
		(layer "In1.Cu")
		(net "GND")
	)
	(segment
		(start 378.079 -111.879888)
		(end 377.273566 -111.074454)
		(width 0.508)
		(layer "In1.Cu")
		(net "GND")
	)
	(segment
		(start 62.726824 -72.045322)
		(end 61.92139 -71.239888)
		(width 0.508)
		(layer "In1.Cu")
		(net "GND")
	)
	(segment
		(start 398.442434 -72.045322)
		(end 397.637 -71.239888)
		(width 0.508)
		(layer "In1.Cu")
		(net "GND")
	)
	(segment
		(start 397.637 -91.559888)
		(end 396.831566 -90.754454)
		(width 0.508)
		(layer "In1.Cu")
		(net "GND")
	)
	(segment
		(start 378.884434 -92.365322)
		(end 378.079 -91.559888)
		(width 0.508)
		(layer "In1.Cu")
		(net "GND")
	)
	(segment
		(start 61.92139 -111.879888)
		(end 61.115956 -112.685322)
		(width 0.508)
		(layer "In1.Cu")
		(net "GND")
	)
	(segment
		(start 378.884434 -131.394454)
		(end 378.079 -132.199888)
		(width 0.508)
		(layer "In1.Cu")
		(net "GND")
	)
	(segment
		(start 42.36339 -50.919888)
		(end 41.557956 -51.725322)
		(width 0.508)
		(layer "In1.Cu")
		(net "GND")
	)
	(segment
		(start 61.92139 -111.879888)
		(end 61.115956 -111.074454)
		(width 0.508)
		(layer "In1.Cu")
		(net "GND")
	)
	(segment
		(start 398.442434 -112.685322)
		(end 397.637 -111.879888)
		(width 0.508)
		(layer "In1.Cu")
		(net "GND")
	)
	(segment
		(start 397.637 -71.239888)
		(end 396.831566 -70.434454)
		(width 0.508)
		(layer "In1.Cu")
		(net "GND")
	)
	(segment
		(start 42.36339 -91.559888)
		(end 41.557956 -90.754454)
		(width 0.508)
		(layer "In1.Cu")
		(net "GND")
	)
	(segment
		(start 62.726824 -131.394454)
		(end 61.92139 -132.199888)
		(width 0.508)
		(layer "In1.Cu")
		(net "GND")
	)
	(segment
		(start 378.884434 -133.005322)
		(end 378.079 -132.199888)
		(width 0.508)
		(layer "In1.Cu")
		(net "GND")
	)
	(segment
		(start 378.079 -71.239888)
		(end 377.273566 -70.434454)
		(width 0.508)
		(layer "In1.Cu")
		(net "GND")
	)
	(segment
		(start 43.168824 -90.754454)
		(end 42.36339 -91.559888)
		(width 0.508)
		(layer "In1.Cu")
		(net "GND")
	)
	(segment
		(start 42.36339 -132.199888)
		(end 41.557956 -133.005322)
		(width 0.508)
		(layer "In1.Cu")
		(net "GND")
	)
	(segment
		(start 43.168824 -111.074454)
		(end 42.36339 -111.879888)
		(width 0.508)
		(layer "In1.Cu")
		(net "GND")
	)
	(segment
		(start 42.36339 -91.559888)
		(end 41.557956 -92.365322)
		(width 0.508)
		(layer "In1.Cu")
		(net "GND")
	)
	(segment
		(start 378.079 -71.239888)
		(end 377.273566 -72.045322)
		(width 0.508)
		(layer "In1.Cu")
		(net "GND")
	)
	(segment
		(start 42.36339 -50.919888)
		(end 41.557956 -50.114454)
		(width 0.508)
		(layer "In1.Cu")
		(net "GND")
	)
	(segment
		(start 61.92139 -91.559888)
		(end 61.115956 -92.365322)
		(width 0.508)
		(layer "In1.Cu")
		(net "GND")
	)
	(segment
		(start 398.442434 -111.074454)
		(end 397.637 -111.879888)
		(width 0.508)
		(layer "In1.Cu")
		(net "GND")
	)
	(segment
		(start 378.079 -91.559888)
		(end 377.273566 -90.754454)
		(width 0.508)
		(layer "In1.Cu")
		(net "GND")
	)
	(segment
		(start 62.726824 -112.685322)
		(end 61.92139 -111.879888)
		(width 0.508)
		(layer "In1.Cu")
		(net "GND")
	)
	(segment
		(start 43.168824 -72.045322)
		(end 42.36339 -71.239888)
		(width 0.508)
		(layer "In1.Cu")
		(net "GND")
	)
	(segment
		(start 397.637 -50.919888)
		(end 396.831566 -51.725322)
		(width 0.508)
		(layer "In1.Cu")
		(net "GND")
	)
	(segment
		(start 62.726824 -92.365322)
		(end 61.92139 -91.559888)
		(width 0.508)
		(layer "In1.Cu")
		(net "GND")
	)
	(segment
		(start 397.637 -132.199888)
		(end 396.831566 -131.394454)
		(width 0.508)
		(layer "In1.Cu")
		(net "GND")
	)
	(segment
		(start 43.168824 -131.394454)
		(end 42.36339 -132.199888)
		(width 0.508)
		(layer "In1.Cu")
		(net "GND")
	)
	(segment
		(start 378.079 -132.199888)
		(end 377.273566 -133.005322)
		(width 0.508)
		(layer "In1.Cu")
		(net "GND")
	)
	(segment
		(start 378.884434 -112.685322)
		(end 378.079 -111.879888)
		(width 0.508)
		(layer "In1.Cu")
		(net "GND")
	)
	(segment
		(start 397.637 -132.199888)
		(end 396.831566 -133.005322)
		(width 0.508)
		(layer "In1.Cu")
		(net "GND")
	)
	(segment
		(start 398.442434 -50.114454)
		(end 397.637 -50.919888)
		(width 0.508)
		(layer "In1.Cu")
		(net "GND")
	)
	(segment
		(start 62.726824 -133.005322)
		(end 61.92139 -132.199888)
		(width 0.508)
		(layer "In1.Cu")
		(net "GND")
	)
	(segment
		(start 378.079 -132.199888)
		(end 377.273566 -131.394454)
		(width 0.508)
		(layer "In1.Cu")
		(net "GND")
	)
	(segment
		(start 61.92139 -71.239888)
		(end 61.115956 -70.434454)
		(width 0.508)
		(layer "In1.Cu")
		(net "GND")
	)
	(segment
		(start 43.168824 -112.685322)
		(end 42.36339 -111.879888)
		(width 0.508)
		(layer "In1.Cu")
		(net "GND")
	)
	(segment
		(start 43.168824 -50.114454)
		(end 42.36339 -50.919888)
		(width 0.508)
		(layer "In1.Cu")
		(net "GND")
	)
	(segment
		(start 398.442434 -51.725322)
		(end 397.637 -50.919888)
		(width 0.508)
		(layer "In1.Cu")
		(net "GND")
	)
	(segment
		(start 62.726824 -50.114454)
		(end 61.92139 -50.919888)
		(width 0.508)
		(layer "In1.Cu")
		(net "GND")
	)
	(segment
		(start 62.726824 -70.434454)
		(end 61.92139 -71.239888)
		(width 0.508)
		(layer "In1.Cu")
		(net "GND")
	)
	(segment
		(start 42.36339 -132.199888)
		(end 41.557956 -131.394454)
		(width 0.508)
		(layer "In1.Cu")
		(net "GND")
	)
	(segment
		(start 61.92139 -71.239888)
		(end 61.115956 -72.045322)
		(width 0.508)
		(layer "In1.Cu")
		(net "GND")
	)
	(segment
		(start 378.079 -50.919888)
		(end 377.273566 -50.114454)
		(width 0.508)
		(layer "In1.Cu")
		(net "GND")
	)
	(segment
		(start 398.442434 -90.754454)
		(end 397.637 -91.559888)
		(width 0.508)
		(layer "In1.Cu")
		(net "GND")
	)
	(segment
		(start 397.637 -71.239888)
		(end 396.831566 -72.045322)
		(width 0.508)
		(layer "In1.Cu")
		(net "GND")
	)
	(segment
		(start 62.726824 -90.754454)
		(end 61.92139 -91.559888)
		(width 0.508)
		(layer "In1.Cu")
		(net "GND")
	)
	(segment
		(start 398.442434 -92.365322)
		(end 397.637 -91.559888)
		(width 0.508)
		(layer "In1.Cu")
		(net "GND")
	)
	(segment
		(start 62.726824 -51.725322)
		(end 61.92139 -50.919888)
		(width 0.508)
		(layer "In1.Cu")
		(net "GND")
	)
	(segment
		(start 378.884434 -72.045322)
		(end 378.079 -71.239888)
		(width 0.508)
		(layer "In1.Cu")
		(net "GND")
	)
	(segment
		(start 42.36339 -71.239888)
		(end 41.557956 -70.434454)
		(width 0.508)
		(layer "In1.Cu")
		(net "GND")
	)
	(segment
		(start 43.168824 -133.005322)
		(end 42.36339 -132.199888)
		(width 0.508)
		(layer "In1.Cu")
		(net "GND")
	)
	(segment
		(start 62.726824 -111.074454)
		(end 61.92139 -111.879888)
		(width 0.508)
		(layer "In1.Cu")
		(net "GND")
	)
	(segment
		(start 398.442434 -131.394454)
		(end 397.637 -132.199888)
		(width 0.508)
		(layer "In1.Cu")
		(net "GND")
	)
	(segment
		(start 61.92139 -132.199888)
		(end 61.115956 -133.005322)
		(width 0.508)
		(layer "In1.Cu")
		(net "GND")
	)
	(segment
		(start 397.637 -91.559888)
		(end 396.831566 -92.365322)
		(width 0.508)
		(layer "In1.Cu")
		(net "GND")
	)
	(segment
		(start 61.92139 -50.919888)
		(end 61.115956 -50.114454)
		(width 0.508)
		(layer "In1.Cu")
		(net "GND")
	)
	(segment
		(start 378.079 -111.879888)
		(end 377.273566 -112.685322)
		(width 0.508)
		(layer "In1.Cu")
		(net "GND")
	)
	(segment
		(start 61.92139 -132.199888)
		(end 61.115956 -131.394454)
		(width 0.508)
		(layer "In1.Cu")
		(net "GND")
	)
	(segment
		(start 378.884434 -90.754454)
		(end 378.079 -91.559888)
		(width 0.508)
		(layer "In1.Cu")
		(net "GND")
	)
	(segment
		(start 378.884434 -50.114454)
		(end 378.079 -50.919888)
		(width 0.508)
		(layer "In1.Cu")
		(net "GND")
	)
	(segment
		(start 397.637 -111.879888)
		(end 396.831566 -111.074454)
		(width 0.508)
		(layer "In1.Cu")
		(net "GND")
	)
	(segment
		(start 378.079 -91.559888)
		(end 377.273566 -92.365322)
		(width 0.508)
		(layer "In1.Cu")
		(net "GND")
	)
	(segment
		(start 397.637 -50.919888)
		(end 396.831566 -50.114454)
		(width 0.508)
		(layer "In1.Cu")
		(net "GND")
	)
	(segment
		(start 398.442434 -70.434454)
		(end 397.637 -71.239888)
		(width 0.508)
		(layer "In1.Cu")
		(net "GND")
	)
	(segment
		(start 397.637 -111.879888)
		(end 396.831566 -112.685322)
		(width 0.508)
		(layer "In1.Cu")
		(net "GND")
	)
	(segment
		(start 378.884434 -51.725322)
		(end 378.079 -50.919888)
		(width 0.508)
		(layer "In1.Cu")
		(net "GND")
	)
	(segment
		(start 43.168824 -90.754454)
		(end 42.36339 -91.559888)
		(width 0.508)
		(layer "In3.Cu")
		(net "GND")
	)
	(segment
		(start 61.92139 -132.199888)
		(end 61.115956 -133.005322)
		(width 0.508)
		(layer "In3.Cu")
		(net "GND")
	)
	(segment
		(start 398.442434 -70.434454)
		(end 397.637 -71.239888)
		(width 0.508)
		(layer "In3.Cu")
		(net "GND")
	)
	(segment
		(start 397.637 -132.199888)
		(end 396.831566 -133.005322)
		(width 0.508)
		(layer "In3.Cu")
		(net "GND")
	)
	(segment
		(start 378.079 -91.559888)
		(end 377.273566 -90.754454)
		(width 0.508)
		(layer "In3.Cu")
		(net "GND")
	)
	(segment
		(start 62.726824 -133.005322)
		(end 61.92139 -132.199888)
		(width 0.508)
		(layer "In3.Cu")
		(net "GND")
	)
	(segment
		(start 42.36339 -50.919888)
		(end 41.557956 -51.725322)
		(width 0.508)
		(layer "In3.Cu")
		(net "GND")
	)
	(segment
		(start 42.36339 -132.199888)
		(end 41.557956 -131.394454)
		(width 0.508)
		(layer "In3.Cu")
		(net "GND")
	)
	(segment
		(start 43.168824 -92.365322)
		(end 42.36339 -91.559888)
		(width 0.508)
		(layer "In3.Cu")
		(net "GND")
	)
	(segment
		(start 378.079 -111.879888)
		(end 377.273566 -112.685322)
		(width 0.508)
		(layer "In3.Cu")
		(net "GND")
	)
	(segment
		(start 61.92139 -111.879888)
		(end 61.115956 -111.074454)
		(width 0.508)
		(layer "In3.Cu")
		(net "GND")
	)
	(segment
		(start 378.884434 -51.725322)
		(end 378.079 -50.919888)
		(width 0.508)
		(layer "In3.Cu")
		(net "GND")
	)
	(segment
		(start 62.726824 -92.365322)
		(end 61.92139 -91.559888)
		(width 0.508)
		(layer "In3.Cu")
		(net "GND")
	)
	(segment
		(start 397.637 -71.239888)
		(end 396.831566 -72.045322)
		(width 0.508)
		(layer "In3.Cu")
		(net "GND")
	)
	(segment
		(start 398.442434 -112.685322)
		(end 397.637 -111.879888)
		(width 0.508)
		(layer "In3.Cu")
		(net "GND")
	)
	(segment
		(start 43.168824 -111.074454)
		(end 42.36339 -111.879888)
		(width 0.508)
		(layer "In3.Cu")
		(net "GND")
	)
	(segment
		(start 62.726824 -111.074454)
		(end 61.92139 -111.879888)
		(width 0.508)
		(layer "In3.Cu")
		(net "GND")
	)
	(segment
		(start 62.726824 -51.725322)
		(end 61.92139 -50.919888)
		(width 0.508)
		(layer "In3.Cu")
		(net "GND")
	)
	(segment
		(start 378.079 -111.879888)
		(end 377.273566 -111.074454)
		(width 0.508)
		(layer "In3.Cu")
		(net "GND")
	)
	(segment
		(start 378.884434 -112.685322)
		(end 378.079 -111.879888)
		(width 0.508)
		(layer "In3.Cu")
		(net "GND")
	)
	(segment
		(start 42.36339 -111.879888)
		(end 41.557956 -111.074454)
		(width 0.508)
		(layer "In3.Cu")
		(net "GND")
	)
	(segment
		(start 378.079 -71.239888)
		(end 377.273566 -72.045322)
		(width 0.508)
		(layer "In3.Cu")
		(net "GND")
	)
	(segment
		(start 397.637 -111.879888)
		(end 396.831566 -112.685322)
		(width 0.508)
		(layer "In3.Cu")
		(net "GND")
	)
	(segment
		(start 62.726824 -50.114454)
		(end 61.92139 -50.919888)
		(width 0.508)
		(layer "In3.Cu")
		(net "GND")
	)
	(segment
		(start 62.726824 -90.754454)
		(end 61.92139 -91.559888)
		(width 0.508)
		(layer "In3.Cu")
		(net "GND")
	)
	(segment
		(start 61.92139 -50.919888)
		(end 61.115956 -51.725322)
		(width 0.508)
		(layer "In3.Cu")
		(net "GND")
	)
	(segment
		(start 398.442434 -111.074454)
		(end 397.637 -111.879888)
		(width 0.508)
		(layer "In3.Cu")
		(net "GND")
	)
	(segment
		(start 42.36339 -71.239888)
		(end 41.557956 -72.045322)
		(width 0.508)
		(layer "In3.Cu")
		(net "GND")
	)
	(segment
		(start 43.168824 -50.114454)
		(end 42.36339 -50.919888)
		(width 0.508)
		(layer "In3.Cu")
		(net "GND")
	)
	(segment
		(start 398.442434 -51.725322)
		(end 397.637 -50.919888)
		(width 0.508)
		(layer "In3.Cu")
		(net "GND")
	)
	(segment
		(start 378.079 -132.199888)
		(end 377.273566 -131.394454)
		(width 0.508)
		(layer "In3.Cu")
		(net "GND")
	)
	(segment
		(start 61.92139 -71.239888)
		(end 61.115956 -72.045322)
		(width 0.508)
		(layer "In3.Cu")
		(net "GND")
	)
	(segment
		(start 61.92139 -111.879888)
		(end 61.115956 -112.685322)
		(width 0.508)
		(layer "In3.Cu")
		(net "GND")
	)
	(segment
		(start 378.079 -91.559888)
		(end 377.273566 -92.365322)
		(width 0.508)
		(layer "In3.Cu")
		(net "GND")
	)
	(segment
		(start 378.884434 -131.394454)
		(end 378.079 -132.199888)
		(width 0.508)
		(layer "In3.Cu")
		(net "GND")
	)
	(segment
		(start 43.168824 -112.685322)
		(end 42.36339 -111.879888)
		(width 0.508)
		(layer "In3.Cu")
		(net "GND")
	)
	(segment
		(start 61.92139 -91.559888)
		(end 61.115956 -90.754454)
		(width 0.508)
		(layer "In3.Cu")
		(net "GND")
	)
	(segment
		(start 62.726824 -70.434454)
		(end 61.92139 -71.239888)
		(width 0.508)
		(layer "In3.Cu")
		(net "GND")
	)
	(segment
		(start 398.442434 -90.754454)
		(end 397.637 -91.559888)
		(width 0.508)
		(layer "In3.Cu")
		(net "GND")
	)
	(segment
		(start 398.442434 -131.394454)
		(end 397.637 -132.199888)
		(width 0.508)
		(layer "In3.Cu")
		(net "GND")
	)
	(segment
		(start 43.168824 -72.045322)
		(end 42.36339 -71.239888)
		(width 0.508)
		(layer "In3.Cu")
		(net "GND")
	)
	(segment
		(start 378.079 -71.239888)
		(end 377.273566 -70.434454)
		(width 0.508)
		(layer "In3.Cu")
		(net "GND")
	)
	(segment
		(start 61.92139 -71.239888)
		(end 61.115956 -70.434454)
		(width 0.508)
		(layer "In3.Cu")
		(net "GND")
	)
	(segment
		(start 61.92139 -50.919888)
		(end 61.115956 -50.114454)
		(width 0.508)
		(layer "In3.Cu")
		(net "GND")
	)
	(segment
		(start 43.168824 -131.394454)
		(end 42.36339 -132.199888)
		(width 0.508)
		(layer "In3.Cu")
		(net "GND")
	)
	(segment
		(start 378.079 -132.199888)
		(end 377.273566 -133.005322)
		(width 0.508)
		(layer "In3.Cu")
		(net "GND")
	)
	(segment
		(start 42.36339 -91.559888)
		(end 41.557956 -90.754454)
		(width 0.508)
		(layer "In3.Cu")
		(net "GND")
	)
	(segment
		(start 397.637 -91.559888)
		(end 396.831566 -90.754454)
		(width 0.508)
		(layer "In3.Cu")
		(net "GND")
	)
	(segment
		(start 43.168824 -70.434454)
		(end 42.36339 -71.239888)
		(width 0.508)
		(layer "In3.Cu")
		(net "GND")
	)
	(segment
		(start 61.92139 -132.199888)
		(end 61.115956 -131.394454)
		(width 0.508)
		(layer "In3.Cu")
		(net "GND")
	)
	(segment
		(start 62.726824 -131.394454)
		(end 61.92139 -132.199888)
		(width 0.508)
		(layer "In3.Cu")
		(net "GND")
	)
	(segment
		(start 378.884434 -72.045322)
		(end 378.079 -71.239888)
		(width 0.508)
		(layer "In3.Cu")
		(net "GND")
	)
	(segment
		(start 42.36339 -71.239888)
		(end 41.557956 -70.434454)
		(width 0.508)
		(layer "In3.Cu")
		(net "GND")
	)
	(segment
		(start 397.637 -111.879888)
		(end 396.831566 -111.074454)
		(width 0.508)
		(layer "In3.Cu")
		(net "GND")
	)
	(segment
		(start 398.442434 -133.005322)
		(end 397.637 -132.199888)
		(width 0.508)
		(layer "In3.Cu")
		(net "GND")
	)
	(segment
		(start 378.884434 -50.114454)
		(end 378.079 -50.919888)
		(width 0.508)
		(layer "In3.Cu")
		(net "GND")
	)
	(segment
		(start 397.637 -50.919888)
		(end 396.831566 -50.114454)
		(width 0.508)
		(layer "In3.Cu")
		(net "GND")
	)
	(segment
		(start 398.442434 -50.114454)
		(end 397.637 -50.919888)
		(width 0.508)
		(layer "In3.Cu")
		(net "GND")
	)
	(segment
		(start 42.36339 -91.559888)
		(end 41.557956 -92.365322)
		(width 0.508)
		(layer "In3.Cu")
		(net "GND")
	)
	(segment
		(start 62.726824 -72.045322)
		(end 61.92139 -71.239888)
		(width 0.508)
		(layer "In3.Cu")
		(net "GND")
	)
	(segment
		(start 397.637 -50.919888)
		(end 396.831566 -51.725322)
		(width 0.508)
		(layer "In3.Cu")
		(net "GND")
	)
	(segment
		(start 43.168824 -51.725322)
		(end 42.36339 -50.919888)
		(width 0.508)
		(layer "In3.Cu")
		(net "GND")
	)
	(segment
		(start 398.442434 -92.365322)
		(end 397.637 -91.559888)
		(width 0.508)
		(layer "In3.Cu")
		(net "GND")
	)
	(segment
		(start 397.637 -91.559888)
		(end 396.831566 -92.365322)
		(width 0.508)
		(layer "In3.Cu")
		(net "GND")
	)
	(segment
		(start 378.884434 -133.005322)
		(end 378.079 -132.199888)
		(width 0.508)
		(layer "In3.Cu")
		(net "GND")
	)
	(segment
		(start 398.442434 -72.045322)
		(end 397.637 -71.239888)
		(width 0.508)
		(layer "In3.Cu")
		(net "GND")
	)
	(segment
		(start 378.079 -50.919888)
		(end 377.273566 -51.725322)
		(width 0.508)
		(layer "In3.Cu")
		(net "GND")
	)
	(segment
		(start 42.36339 -111.879888)
		(end 41.557956 -112.685322)
		(width 0.508)
		(layer "In3.Cu")
		(net "GND")
	)
	(segment
		(start 43.168824 -133.005322)
		(end 42.36339 -132.199888)
		(width 0.508)
		(layer "In3.Cu")
		(net "GND")
	)
	(segment
		(start 62.726824 -112.685322)
		(end 61.92139 -111.879888)
		(width 0.508)
		(layer "In3.Cu")
		(net "GND")
	)
	(segment
		(start 42.36339 -50.919888)
		(end 41.557956 -50.114454)
		(width 0.508)
		(layer "In3.Cu")
		(net "GND")
	)
	(segment
		(start 397.637 -132.199888)
		(end 396.831566 -131.394454)
		(width 0.508)
		(layer "In3.Cu")
		(net "GND")
	)
	(segment
		(start 378.884434 -111.074454)
		(end 378.079 -111.879888)
		(width 0.508)
		(layer "In3.Cu")
		(net "GND")
	)
	(segment
		(start 397.637 -71.239888)
		(end 396.831566 -70.434454)
		(width 0.508)
		(layer "In3.Cu")
		(net "GND")
	)
	(segment
		(start 378.884434 -70.434454)
		(end 378.079 -71.239888)
		(width 0.508)
		(layer "In3.Cu")
		(net "GND")
	)
	(segment
		(start 42.36339 -132.199888)
		(end 41.557956 -133.005322)
		(width 0.508)
		(layer "In3.Cu")
		(net "GND")
	)
	(segment
		(start 61.92139 -91.559888)
		(end 61.115956 -92.365322)
		(width 0.508)
		(layer "In3.Cu")
		(net "GND")
	)
	(segment
		(start 378.884434 -90.754454)
		(end 378.079 -91.559888)
		(width 0.508)
		(layer "In3.Cu")
		(net "GND")
	)
	(segment
		(start 378.884434 -92.365322)
		(end 378.079 -91.559888)
		(width 0.508)
		(layer "In3.Cu")
		(net "GND")
	)
	(segment
		(start 378.079 -50.919888)
		(end 377.273566 -50.114454)
		(width 0.508)
		(layer "In3.Cu")
		(net "GND")
	)
	(segment
		(start 62.726824 -72.045322)
		(end 61.92139 -71.239888)
		(width 0.508)
		(layer "In6.Cu")
		(net "GND")
	)
	(segment
		(start 397.637 -91.559888)
		(end 396.831566 -90.754454)
		(width 0.508)
		(layer "In6.Cu")
		(net "GND")
	)
	(segment
		(start 398.442434 -90.754454)
		(end 397.637 -91.559888)
		(width 0.508)
		(layer "In6.Cu")
		(net "GND")
	)
	(segment
		(start 43.168824 -70.434454)
		(end 42.36339 -71.239888)
		(width 0.508)
		(layer "In6.Cu")
		(net "GND")
	)
	(segment
		(start 42.36339 -111.879888)
		(end 41.557956 -111.074454)
		(width 0.508)
		(layer "In6.Cu")
		(net "GND")
	)
	(segment
		(start 61.92139 -50.919888)
		(end 61.115956 -51.725322)
		(width 0.508)
		(layer "In6.Cu")
		(net "GND")
	)
	(segment
		(start 398.442434 -70.434454)
		(end 397.637 -71.239888)
		(width 0.508)
		(layer "In6.Cu")
		(net "GND")
	)
	(segment
		(start 378.884434 -131.394454)
		(end 378.079 -132.199888)
		(width 0.508)
		(layer "In6.Cu")
		(net "GND")
	)
	(segment
		(start 378.884434 -72.045322)
		(end 378.079 -71.239888)
		(width 0.508)
		(layer "In6.Cu")
		(net "GND")
	)
	(segment
		(start 61.92139 -132.199888)
		(end 61.115956 -133.005322)
		(width 0.508)
		(layer "In6.Cu")
		(net "GND")
	)
	(segment
		(start 397.637 -71.239888)
		(end 396.831566 -72.045322)
		(width 0.508)
		(layer "In6.Cu")
		(net "GND")
	)
	(segment
		(start 378.079 -91.559888)
		(end 377.273566 -90.754454)
		(width 0.508)
		(layer "In6.Cu")
		(net "GND")
	)
	(segment
		(start 398.442434 -111.074454)
		(end 397.637 -111.879888)
		(width 0.508)
		(layer "In6.Cu")
		(net "GND")
	)
	(segment
		(start 398.442434 -72.045322)
		(end 397.637 -71.239888)
		(width 0.508)
		(layer "In6.Cu")
		(net "GND")
	)
	(segment
		(start 398.442434 -92.365322)
		(end 397.637 -91.559888)
		(width 0.508)
		(layer "In6.Cu")
		(net "GND")
	)
	(segment
		(start 378.884434 -92.365322)
		(end 378.079 -91.559888)
		(width 0.508)
		(layer "In6.Cu")
		(net "GND")
	)
	(segment
		(start 62.726824 -133.005322)
		(end 61.92139 -132.199888)
		(width 0.508)
		(layer "In6.Cu")
		(net "GND")
	)
	(segment
		(start 42.36339 -91.559888)
		(end 41.557956 -90.754454)
		(width 0.508)
		(layer "In6.Cu")
		(net "GND")
	)
	(segment
		(start 43.168824 -72.045322)
		(end 42.36339 -71.239888)
		(width 0.508)
		(layer "In6.Cu")
		(net "GND")
	)
	(segment
		(start 43.168824 -133.005322)
		(end 42.36339 -132.199888)
		(width 0.508)
		(layer "In6.Cu")
		(net "GND")
	)
	(segment
		(start 378.079 -132.199888)
		(end 377.273566 -131.394454)
		(width 0.508)
		(layer "In6.Cu")
		(net "GND")
	)
	(segment
		(start 62.726824 -92.365322)
		(end 61.92139 -91.559888)
		(width 0.508)
		(layer "In6.Cu")
		(net "GND")
	)
	(segment
		(start 62.726824 -131.394454)
		(end 61.92139 -132.199888)
		(width 0.508)
		(layer "In6.Cu")
		(net "GND")
	)
	(segment
		(start 62.726824 -90.754454)
		(end 61.92139 -91.559888)
		(width 0.508)
		(layer "In6.Cu")
		(net "GND")
	)
	(segment
		(start 397.637 -132.199888)
		(end 396.831566 -133.005322)
		(width 0.508)
		(layer "In6.Cu")
		(net "GND")
	)
	(segment
		(start 378.079 -71.239888)
		(end 377.273566 -72.045322)
		(width 0.508)
		(layer "In6.Cu")
		(net "GND")
	)
	(segment
		(start 398.442434 -133.005322)
		(end 397.637 -132.199888)
		(width 0.508)
		(layer "In6.Cu")
		(net "GND")
	)
	(segment
		(start 378.079 -91.559888)
		(end 377.273566 -92.365322)
		(width 0.508)
		(layer "In6.Cu")
		(net "GND")
	)
	(segment
		(start 398.442434 -131.394454)
		(end 397.637 -132.199888)
		(width 0.508)
		(layer "In6.Cu")
		(net "GND")
	)
	(segment
		(start 398.442434 -51.725322)
		(end 397.637 -50.919888)
		(width 0.508)
		(layer "In6.Cu")
		(net "GND")
	)
	(segment
		(start 62.726824 -112.685322)
		(end 61.92139 -111.879888)
		(width 0.508)
		(layer "In6.Cu")
		(net "GND")
	)
	(segment
		(start 62.726824 -70.434454)
		(end 61.92139 -71.239888)
		(width 0.508)
		(layer "In6.Cu")
		(net "GND")
	)
	(segment
		(start 43.168824 -51.725322)
		(end 42.36339 -50.919888)
		(width 0.508)
		(layer "In6.Cu")
		(net "GND")
	)
	(segment
		(start 61.92139 -71.239888)
		(end 61.115956 -70.434454)
		(width 0.508)
		(layer "In6.Cu")
		(net "GND")
	)
	(segment
		(start 42.36339 -91.559888)
		(end 41.557956 -92.365322)
		(width 0.508)
		(layer "In6.Cu")
		(net "GND")
	)
	(segment
		(start 378.884434 -70.434454)
		(end 378.079 -71.239888)
		(width 0.508)
		(layer "In6.Cu")
		(net "GND")
	)
	(segment
		(start 378.884434 -50.114454)
		(end 378.079 -50.919888)
		(width 0.508)
		(layer "In6.Cu")
		(net "GND")
	)
	(segment
		(start 378.884434 -90.754454)
		(end 378.079 -91.559888)
		(width 0.508)
		(layer "In6.Cu")
		(net "GND")
	)
	(segment
		(start 43.168824 -131.394454)
		(end 42.36339 -132.199888)
		(width 0.508)
		(layer "In6.Cu")
		(net "GND")
	)
	(segment
		(start 378.079 -50.919888)
		(end 377.273566 -50.114454)
		(width 0.508)
		(layer "In6.Cu")
		(net "GND")
	)
	(segment
		(start 42.36339 -111.879888)
		(end 41.557956 -112.685322)
		(width 0.508)
		(layer "In6.Cu")
		(net "GND")
	)
	(segment
		(start 62.726824 -111.074454)
		(end 61.92139 -111.879888)
		(width 0.508)
		(layer "In6.Cu")
		(net "GND")
	)
	(segment
		(start 378.884434 -51.725322)
		(end 378.079 -50.919888)
		(width 0.508)
		(layer "In6.Cu")
		(net "GND")
	)
	(segment
		(start 62.726824 -51.725322)
		(end 61.92139 -50.919888)
		(width 0.508)
		(layer "In6.Cu")
		(net "GND")
	)
	(segment
		(start 378.079 -132.199888)
		(end 377.273566 -133.005322)
		(width 0.508)
		(layer "In6.Cu")
		(net "GND")
	)
	(segment
		(start 378.884434 -112.685322)
		(end 378.079 -111.879888)
		(width 0.508)
		(layer "In6.Cu")
		(net "GND")
	)
	(segment
		(start 61.92139 -132.199888)
		(end 61.115956 -131.394454)
		(width 0.508)
		(layer "In6.Cu")
		(net "GND")
	)
	(segment
		(start 61.92139 -111.879888)
		(end 61.115956 -111.074454)
		(width 0.508)
		(layer "In6.Cu")
		(net "GND")
	)
	(segment
		(start 61.92139 -71.239888)
		(end 61.115956 -72.045322)
		(width 0.508)
		(layer "In6.Cu")
		(net "GND")
	)
	(segment
		(start 42.36339 -71.239888)
		(end 41.557956 -70.434454)
		(width 0.508)
		(layer "In6.Cu")
		(net "GND")
	)
	(segment
		(start 42.36339 -50.919888)
		(end 41.557956 -50.114454)
		(width 0.508)
		(layer "In6.Cu")
		(net "GND")
	)
	(segment
		(start 378.079 -111.879888)
		(end 377.273566 -112.685322)
		(width 0.508)
		(layer "In6.Cu")
		(net "GND")
	)
	(segment
		(start 43.168824 -92.365322)
		(end 42.36339 -91.559888)
		(width 0.508)
		(layer "In6.Cu")
		(net "GND")
	)
	(segment
		(start 61.92139 -91.559888)
		(end 61.115956 -90.754454)
		(width 0.508)
		(layer "In6.Cu")
		(net "GND")
	)
	(segment
		(start 397.637 -132.199888)
		(end 396.831566 -131.394454)
		(width 0.508)
		(layer "In6.Cu")
		(net "GND")
	)
	(segment
		(start 42.36339 -132.199888)
		(end 41.557956 -131.394454)
		(width 0.508)
		(layer "In6.Cu")
		(net "GND")
	)
	(segment
		(start 378.079 -111.879888)
		(end 377.273566 -111.074454)
		(width 0.508)
		(layer "In6.Cu")
		(net "GND")
	)
	(segment
		(start 378.079 -71.239888)
		(end 377.273566 -70.434454)
		(width 0.508)
		(layer "In6.Cu")
		(net "GND")
	)
	(segment
		(start 378.884434 -133.005322)
		(end 378.079 -132.199888)
		(width 0.508)
		(layer "In6.Cu")
		(net "GND")
	)
	(segment
		(start 397.637 -50.919888)
		(end 396.831566 -50.114454)
		(width 0.508)
		(layer "In6.Cu")
		(net "GND")
	)
	(segment
		(start 42.36339 -50.919888)
		(end 41.557956 -51.725322)
		(width 0.508)
		(layer "In6.Cu")
		(net "GND")
	)
	(segment
		(start 61.92139 -91.559888)
		(end 61.115956 -92.365322)
		(width 0.508)
		(layer "In6.Cu")
		(net "GND")
	)
	(segment
		(start 398.442434 -50.114454)
		(end 397.637 -50.919888)
		(width 0.508)
		(layer "In6.Cu")
		(net "GND")
	)
	(segment
		(start 397.637 -111.879888)
		(end 396.831566 -111.074454)
		(width 0.508)
		(layer "In6.Cu")
		(net "GND")
	)
	(segment
		(start 62.726824 -50.114454)
		(end 61.92139 -50.919888)
		(width 0.508)
		(layer "In6.Cu")
		(net "GND")
	)
	(segment
		(start 397.637 -50.919888)
		(end 396.831566 -51.725322)
		(width 0.508)
		(layer "In6.Cu")
		(net "GND")
	)
	(segment
		(start 61.92139 -111.879888)
		(end 61.115956 -112.685322)
		(width 0.508)
		(layer "In6.Cu")
		(net "GND")
	)
	(segment
		(start 378.884434 -111.074454)
		(end 378.079 -111.879888)
		(width 0.508)
		(layer "In6.Cu")
		(net "GND")
	)
	(segment
		(start 42.36339 -132.199888)
		(end 41.557956 -133.005322)
		(width 0.508)
		(layer "In6.Cu")
		(net "GND")
	)
	(segment
		(start 397.637 -91.559888)
		(end 396.831566 -92.365322)
		(width 0.508)
		(layer "In6.Cu")
		(net "GND")
	)
	(segment
		(start 43.168824 -50.114454)
		(end 42.36339 -50.919888)
		(width 0.508)
		(layer "In6.Cu")
		(net "GND")
	)
	(segment
		(start 398.442434 -112.685322)
		(end 397.637 -111.879888)
		(width 0.508)
		(layer "In6.Cu")
		(net "GND")
	)
	(segment
		(start 43.168824 -111.074454)
		(end 42.36339 -111.879888)
		(width 0.508)
		(layer "In6.Cu")
		(net "GND")
	)
	(segment
		(start 61.92139 -50.919888)
		(end 61.115956 -50.114454)
		(width 0.508)
		(layer "In6.Cu")
		(net "GND")
	)
	(segment
		(start 43.168824 -90.754454)
		(end 42.36339 -91.559888)
		(width 0.508)
		(layer "In6.Cu")
		(net "GND")
	)
	(segment
		(start 397.637 -111.879888)
		(end 396.831566 -112.685322)
		(width 0.508)
		(layer "In6.Cu")
		(net "GND")
	)
	(segment
		(start 42.36339 -71.239888)
		(end 41.557956 -72.045322)
		(width 0.508)
		(layer "In6.Cu")
		(net "GND")
	)
	(segment
		(start 43.168824 -112.685322)
		(end 42.36339 -111.879888)
		(width 0.508)
		(layer "In6.Cu")
		(net "GND")
	)
	(segment
		(start 378.079 -50.919888)
		(end 377.273566 -51.725322)
		(width 0.508)
		(layer "In6.Cu")
		(net "GND")
	)
	(segment
		(start 397.637 -71.239888)
		(end 396.831566 -70.434454)
		(width 0.508)
		(layer "In6.Cu")
		(net "GND")
	)
	(segment
		(start 397.637 -71.239888)
		(end 396.831566 -72.045322)
		(width 0.508)
		(layer "In8.Cu")
		(net "GND")
	)
	(segment
		(start 42.36339 -50.919888)
		(end 41.557956 -50.114454)
		(width 0.508)
		(layer "In8.Cu")
		(net "GND")
	)
	(segment
		(start 378.884434 -131.394454)
		(end 378.079 -132.199888)
		(width 0.508)
		(layer "In8.Cu")
		(net "GND")
	)
	(segment
		(start 61.92139 -71.239888)
		(end 61.115956 -72.045322)
		(width 0.508)
		(layer "In8.Cu")
		(net "GND")
	)
	(segment
		(start 378.884434 -70.434454)
		(end 378.079 -71.239888)
		(width 0.508)
		(layer "In8.Cu")
		(net "GND")
	)
	(segment
		(start 42.36339 -50.919888)
		(end 41.557956 -51.725322)
		(width 0.508)
		(layer "In8.Cu")
		(net "GND")
	)
	(segment
		(start 61.92139 -132.199888)
		(end 61.115956 -133.005322)
		(width 0.508)
		(layer "In8.Cu")
		(net "GND")
	)
	(segment
		(start 378.079 -50.919888)
		(end 377.273566 -50.114454)
		(width 0.508)
		(layer "In8.Cu")
		(net "GND")
	)
	(segment
		(start 61.92139 -71.239888)
		(end 61.115956 -70.434454)
		(width 0.508)
		(layer "In8.Cu")
		(net "GND")
	)
	(segment
		(start 378.079 -111.879888)
		(end 377.273566 -111.074454)
		(width 0.508)
		(layer "In8.Cu")
		(net "GND")
	)
	(segment
		(start 62.726824 -92.365322)
		(end 61.92139 -91.559888)
		(width 0.508)
		(layer "In8.Cu")
		(net "GND")
	)
	(segment
		(start 42.36339 -91.559888)
		(end 41.557956 -90.754454)
		(width 0.508)
		(layer "In8.Cu")
		(net "GND")
	)
	(segment
		(start 378.079 -111.879888)
		(end 377.273566 -112.685322)
		(width 0.508)
		(layer "In8.Cu")
		(net "GND")
	)
	(segment
		(start 42.36339 -91.559888)
		(end 41.557956 -92.365322)
		(width 0.508)
		(layer "In8.Cu")
		(net "GND")
	)
	(segment
		(start 62.726824 -111.074454)
		(end 61.92139 -111.879888)
		(width 0.508)
		(layer "In8.Cu")
		(net "GND")
	)
	(segment
		(start 42.36339 -132.199888)
		(end 41.557956 -133.005322)
		(width 0.508)
		(layer "In8.Cu")
		(net "GND")
	)
	(segment
		(start 397.637 -71.239888)
		(end 396.831566 -70.434454)
		(width 0.508)
		(layer "In8.Cu")
		(net "GND")
	)
	(segment
		(start 378.079 -71.239888)
		(end 377.273566 -72.045322)
		(width 0.508)
		(layer "In8.Cu")
		(net "GND")
	)
	(segment
		(start 43.168824 -133.005322)
		(end 42.36339 -132.199888)
		(width 0.508)
		(layer "In8.Cu")
		(net "GND")
	)
	(segment
		(start 397.637 -111.879888)
		(end 396.831566 -111.074454)
		(width 0.508)
		(layer "In8.Cu")
		(net "GND")
	)
	(segment
		(start 397.637 -132.199888)
		(end 396.831566 -133.005322)
		(width 0.508)
		(layer "In8.Cu")
		(net "GND")
	)
	(segment
		(start 61.92139 -111.879888)
		(end 61.115956 -112.685322)
		(width 0.508)
		(layer "In8.Cu")
		(net "GND")
	)
	(segment
		(start 398.442434 -112.685322)
		(end 397.637 -111.879888)
		(width 0.508)
		(layer "In8.Cu")
		(net "GND")
	)
	(segment
		(start 42.36339 -71.239888)
		(end 41.557956 -70.434454)
		(width 0.508)
		(layer "In8.Cu")
		(net "GND")
	)
	(segment
		(start 62.726824 -70.434454)
		(end 61.92139 -71.239888)
		(width 0.508)
		(layer "In8.Cu")
		(net "GND")
	)
	(segment
		(start 378.079 -91.559888)
		(end 377.273566 -92.365322)
		(width 0.508)
		(layer "In8.Cu")
		(net "GND")
	)
	(segment
		(start 61.92139 -91.559888)
		(end 61.115956 -90.754454)
		(width 0.508)
		(layer "In8.Cu")
		(net "GND")
	)
	(segment
		(start 378.079 -50.919888)
		(end 377.273566 -51.725322)
		(width 0.508)
		(layer "In8.Cu")
		(net "GND")
	)
	(segment
		(start 42.36339 -71.239888)
		(end 41.557956 -72.045322)
		(width 0.508)
		(layer "In8.Cu")
		(net "GND")
	)
	(segment
		(start 61.92139 -50.919888)
		(end 61.115956 -51.725322)
		(width 0.508)
		(layer "In8.Cu")
		(net "GND")
	)
	(segment
		(start 43.168824 -50.114454)
		(end 42.36339 -50.919888)
		(width 0.508)
		(layer "In8.Cu")
		(net "GND")
	)
	(segment
		(start 42.36339 -111.879888)
		(end 41.557956 -111.074454)
		(width 0.508)
		(layer "In8.Cu")
		(net "GND")
	)
	(segment
		(start 398.442434 -133.005322)
		(end 397.637 -132.199888)
		(width 0.508)
		(layer "In8.Cu")
		(net "GND")
	)
	(segment
		(start 43.168824 -90.754454)
		(end 42.36339 -91.559888)
		(width 0.508)
		(layer "In8.Cu")
		(net "GND")
	)
	(segment
		(start 378.079 -91.559888)
		(end 377.273566 -90.754454)
		(width 0.508)
		(layer "In8.Cu")
		(net "GND")
	)
	(segment
		(start 378.884434 -111.074454)
		(end 378.079 -111.879888)
		(width 0.508)
		(layer "In8.Cu")
		(net "GND")
	)
	(segment
		(start 397.637 -50.919888)
		(end 396.831566 -51.725322)
		(width 0.508)
		(layer "In8.Cu")
		(net "GND")
	)
	(segment
		(start 62.726824 -131.394454)
		(end 61.92139 -132.199888)
		(width 0.508)
		(layer "In8.Cu")
		(net "GND")
	)
	(segment
		(start 42.36339 -132.199888)
		(end 41.557956 -131.394454)
		(width 0.508)
		(layer "In8.Cu")
		(net "GND")
	)
	(segment
		(start 398.442434 -50.114454)
		(end 397.637 -50.919888)
		(width 0.508)
		(layer "In8.Cu")
		(net "GND")
	)
	(segment
		(start 378.079 -132.199888)
		(end 377.273566 -133.005322)
		(width 0.508)
		(layer "In8.Cu")
		(net "GND")
	)
	(segment
		(start 61.92139 -132.199888)
		(end 61.115956 -131.394454)
		(width 0.508)
		(layer "In8.Cu")
		(net "GND")
	)
	(segment
		(start 61.92139 -91.559888)
		(end 61.115956 -92.365322)
		(width 0.508)
		(layer "In8.Cu")
		(net "GND")
	)
	(segment
		(start 398.442434 -72.045322)
		(end 397.637 -71.239888)
		(width 0.508)
		(layer "In8.Cu")
		(net "GND")
	)
	(segment
		(start 43.168824 -111.074454)
		(end 42.36339 -111.879888)
		(width 0.508)
		(layer "In8.Cu")
		(net "GND")
	)
	(segment
		(start 378.884434 -112.685322)
		(end 378.079 -111.879888)
		(width 0.508)
		(layer "In8.Cu")
		(net "GND")
	)
	(segment
		(start 62.726824 -133.005322)
		(end 61.92139 -132.199888)
		(width 0.508)
		(layer "In8.Cu")
		(net "GND")
	)
	(segment
		(start 62.726824 -112.685322)
		(end 61.92139 -111.879888)
		(width 0.508)
		(layer "In8.Cu")
		(net "GND")
	)
	(segment
		(start 398.442434 -111.074454)
		(end 397.637 -111.879888)
		(width 0.508)
		(layer "In8.Cu")
		(net "GND")
	)
	(segment
		(start 43.168824 -131.394454)
		(end 42.36339 -132.199888)
		(width 0.508)
		(layer "In8.Cu")
		(net "GND")
	)
	(segment
		(start 397.637 -91.559888)
		(end 396.831566 -90.754454)
		(width 0.508)
		(layer "In8.Cu")
		(net "GND")
	)
	(segment
		(start 397.637 -50.919888)
		(end 396.831566 -50.114454)
		(width 0.508)
		(layer "In8.Cu")
		(net "GND")
	)
	(segment
		(start 397.637 -91.559888)
		(end 396.831566 -92.365322)
		(width 0.508)
		(layer "In8.Cu")
		(net "GND")
	)
	(segment
		(start 62.726824 -50.114454)
		(end 61.92139 -50.919888)
		(width 0.508)
		(layer "In8.Cu")
		(net "GND")
	)
	(segment
		(start 398.442434 -51.725322)
		(end 397.637 -50.919888)
		(width 0.508)
		(layer "In8.Cu")
		(net "GND")
	)
	(segment
		(start 378.884434 -133.005322)
		(end 378.079 -132.199888)
		(width 0.508)
		(layer "In8.Cu")
		(net "GND")
	)
	(segment
		(start 43.168824 -92.365322)
		(end 42.36339 -91.559888)
		(width 0.508)
		(layer "In8.Cu")
		(net "GND")
	)
	(segment
		(start 378.884434 -72.045322)
		(end 378.079 -71.239888)
		(width 0.508)
		(layer "In8.Cu")
		(net "GND")
	)
	(segment
		(start 398.442434 -90.754454)
		(end 397.637 -91.559888)
		(width 0.508)
		(layer "In8.Cu")
		(net "GND")
	)
	(segment
		(start 378.884434 -51.725322)
		(end 378.079 -50.919888)
		(width 0.508)
		(layer "In8.Cu")
		(net "GND")
	)
	(segment
		(start 62.726824 -72.045322)
		(end 61.92139 -71.239888)
		(width 0.508)
		(layer "In8.Cu")
		(net "GND")
	)
	(segment
		(start 398.442434 -70.434454)
		(end 397.637 -71.239888)
		(width 0.508)
		(layer "In8.Cu")
		(net "GND")
	)
	(segment
		(start 61.92139 -111.879888)
		(end 61.115956 -111.074454)
		(width 0.508)
		(layer "In8.Cu")
		(net "GND")
	)
	(segment
		(start 42.36339 -111.879888)
		(end 41.557956 -112.685322)
		(width 0.508)
		(layer "In8.Cu")
		(net "GND")
	)
	(segment
		(start 398.442434 -92.365322)
		(end 397.637 -91.559888)
		(width 0.508)
		(layer "In8.Cu")
		(net "GND")
	)
	(segment
		(start 378.884434 -92.365322)
		(end 378.079 -91.559888)
		(width 0.508)
		(layer "In8.Cu")
		(net "GND")
	)
	(segment
		(start 43.168824 -70.434454)
		(end 42.36339 -71.239888)
		(width 0.508)
		(layer "In8.Cu")
		(net "GND")
	)
	(segment
		(start 43.168824 -112.685322)
		(end 42.36339 -111.879888)
		(width 0.508)
		(layer "In8.Cu")
		(net "GND")
	)
	(segment
		(start 378.079 -71.239888)
		(end 377.273566 -70.434454)
		(width 0.508)
		(layer "In8.Cu")
		(net "GND")
	)
	(segment
		(start 43.168824 -51.725322)
		(end 42.36339 -50.919888)
		(width 0.508)
		(layer "In8.Cu")
		(net "GND")
	)
	(segment
		(start 378.079 -132.199888)
		(end 377.273566 -131.394454)
		(width 0.508)
		(layer "In8.Cu")
		(net "GND")
	)
	(segment
		(start 378.884434 -50.114454)
		(end 378.079 -50.919888)
		(width 0.508)
		(layer "In8.Cu")
		(net "GND")
	)
	(segment
		(start 62.726824 -90.754454)
		(end 61.92139 -91.559888)
		(width 0.508)
		(layer "In8.Cu")
		(net "GND")
	)
	(segment
		(start 43.168824 -72.045322)
		(end 42.36339 -71.239888)
		(width 0.508)
		(layer "In8.Cu")
		(net "GND")
	)
	(segment
		(start 397.637 -132.199888)
		(end 396.831566 -131.394454)
		(width 0.508)
		(layer "In8.Cu")
		(net "GND")
	)
	(segment
		(start 378.884434 -90.754454)
		(end 378.079 -91.559888)
		(width 0.508)
		(layer "In8.Cu")
		(net "GND")
	)
	(segment
		(start 62.726824 -51.725322)
		(end 61.92139 -50.919888)
		(width 0.508)
		(layer "In8.Cu")
		(net "GND")
	)
	(segment
		(start 61.92139 -50.919888)
		(end 61.115956 -50.114454)
		(width 0.508)
		(layer "In8.Cu")
		(net "GND")
	)
	(segment
		(start 398.442434 -131.394454)
		(end 397.637 -132.199888)
		(width 0.508)
		(layer "In8.Cu")
		(net "GND")
	)
	(segment
		(start 397.637 -111.879888)
		(end 396.831566 -112.685322)
		(width 0.508)
		(layer "In8.Cu")
		(net "GND")
	)
	(segment
		(start 430.8094 -23.241)
		(end 430.8094 -21.971)
		(width 0.17272)
		(layer "F.Cu")
		(net "FRU_ADDR1")
	)
	(segment
		(start 437.30799 -24.36876)
		(end 435.75351 -24.36876)
		(width 0.17272)
		(layer "F.Cu")
		(net "FRU_ADDR1")
	)
	(segment
		(start 431.8254 -24.257)
		(end 430.8094 -23.241)
		(width 0.17272)
		(layer "F.Cu")
		(net "FRU_ADDR1")
	)
	(segment
		(start 435.13375 -23.749)
		(end 434.62575 -24.257)
		(width 0.17272)
		(layer "F.Cu")
		(net "FRU_ADDR1")
	)
	(segment
		(start 434.62575 -24.257)
		(end 431.8254 -24.257)
		(width 0.17272)
		(layer "F.Cu")
		(net "FRU_ADDR1")
	)
	(segment
		(start 435.75351 -24.36876)
		(end 435.13375 -23.749)
		(width 0.17272)
		(layer "F.Cu")
		(net "FRU_ADDR1")
	)
	(segment
		(start 437.92775 -23.749)
		(end 437.30799 -24.36876)
		(width 0.17272)
		(layer "F.Cu")
		(net "FRU_ADDR1")
	)
	(via
		(at 437.30799 -24.36876)
		(size 0.508)
		(drill 0.254)
		(layers "F.Cu" "B.Cu")
		(net "FRU_ADDR1")
	)
	(segment
		(start 435.3814 -26.543)
		(end 437.1594 -26.543)
		(width 0.17272)
		(layer "F.Cu")
		(net "FRU_ADDR0")
	)
	(segment
		(start 429.5394 -23.368)
		(end 429.5394 -21.971)
		(width 0.17272)
		(layer "F.Cu")
		(net "FRU_ADDR0")
	)
	(segment
		(start 435.13375 -25.146)
		(end 435.13375 -26.29535)
		(width 0.17272)
		(layer "F.Cu")
		(net "FRU_ADDR0")
	)
	(segment
		(start 435.13375 -26.29535)
		(end 435.3814 -26.543)
		(width 0.17272)
		(layer "F.Cu")
		(net "FRU_ADDR0")
	)
	(segment
		(start 431.3174 -25.146)
		(end 429.5394 -23.368)
		(width 0.17272)
		(layer "F.Cu")
		(net "FRU_ADDR0")
	)
	(segment
		(start 435.13375 -25.146)
		(end 431.3174 -25.146)
		(width 0.17272)
		(layer "F.Cu")
		(net "FRU_ADDR0")
	)
	(segment
		(start 437.92775 -25.77465)
		(end 437.92775 -25.146)
		(width 0.17272)
		(layer "F.Cu")
		(net "FRU_ADDR0")
	)
	(segment
		(start 437.1594 -26.543)
		(end 437.92775 -25.77465)
		(width 0.17272)
		(layer "F.Cu")
		(net "FRU_ADDR0")
	)
	(via
		(at 435.3814 -26.543)
		(size 0.762)
		(drill 0.381)
		(layers "F.Cu" "B.Cu")
		(net "FRU_ADDR0")
	)
	(segment
		(start 173.127416 -150.669498)
		(end 248.027952 -150.669498)
		(width 0.12954)
		(layer "In7.Cu")
		(net "TDR_SE_50_OHM_IN2")
	)
	(segment
		(start 248.027952 -150.669498)
		(end 248.157492 -150.799038)
		(width 0.12954)
		(layer "In7.Cu")
		(net "TDR_SE_50_OHM_IN2")
	)
	(segment
		(start 248.157492 -153.079958)
		(end 248.027952 -153.209498)
		(width 0.12954)
		(layer "In7.Cu")
		(net "TDR_SE_50_OHM_IN2")
	)
	(segment
		(start 248.157492 -150.799038)
		(end 248.157492 -153.079958)
		(width 0.12954)
		(layer "In7.Cu")
		(net "TDR_SE_50_OHM_IN2")
	)
	(segment
		(start 248.027952 -153.209498)
		(end 173.127416 -153.209498)
		(width 0.12954)
		(layer "In7.Cu")
		(net "TDR_SE_50_OHM_IN2")
	)
	(segment
		(start 178.569366 -143.520668)
		(end 178.396646 -143.693388)
		(width 0.17272)
		(layer "B.Cu")
		(net "TDR_SE_50_OHM_BOT")
	)
	(segment
		(start 178.396646 -143.693388)
		(end 178.396646 -145.887948)
		(width 0.17272)
		(layer "B.Cu")
		(net "TDR_SE_50_OHM_BOT")
	)
	(segment
		(start 178.396646 -145.887948)
		(end 178.569366 -146.060668)
		(width 0.17272)
		(layer "B.Cu")
		(net "TDR_SE_50_OHM_BOT")
	)
	(segment
		(start 178.569366 -146.060668)
		(end 253.449582 -146.060668)
		(width 0.17272)
		(layer "B.Cu")
		(net "TDR_SE_50_OHM_BOT")
	)
	(segment
		(start 253.449582 -143.520668)
		(end 178.569366 -143.520668)
		(width 0.17272)
		(layer "B.Cu")
		(net "TDR_SE_50_OHM_BOT")
	)
	(segment
		(start 178.569366 -150.669498)
		(end 178.396646 -150.842218)
		(width 0.17272)
		(layer "F.Cu")
		(net "TDR_SE_50_OHM_TOP")
	)
	(segment
		(start 178.569366 -153.209498)
		(end 253.449582 -153.209498)
		(width 0.17272)
		(layer "F.Cu")
		(net "TDR_SE_50_OHM_TOP")
	)
	(segment
		(start 178.396646 -150.842218)
		(end 178.396646 -153.036778)
		(width 0.17272)
		(layer "F.Cu")
		(net "TDR_SE_50_OHM_TOP")
	)
	(segment
		(start 253.449582 -150.669498)
		(end 178.569366 -150.669498)
		(width 0.17272)
		(layer "F.Cu")
		(net "TDR_SE_50_OHM_TOP")
	)
	(segment
		(start 178.396646 -153.036778)
		(end 178.569366 -153.209498)
		(width 0.17272)
		(layer "F.Cu")
		(net "TDR_SE_50_OHM_TOP")
	)
	(segment
		(start 248.130568 -145.931128)
		(end 248.001028 -146.060668)
		(width 0.12954)
		(layer "In2.Cu")
		(net "TDR_SE_50_OHM_IN1")
	)
	(segment
		(start 248.130568 -143.650208)
		(end 248.130568 -145.931128)
		(width 0.12954)
		(layer "In2.Cu")
		(net "TDR_SE_50_OHM_IN1")
	)
	(segment
		(start 248.001028 -143.520668)
		(end 248.130568 -143.650208)
		(width 0.12954)
		(layer "In2.Cu")
		(net "TDR_SE_50_OHM_IN1")
	)
	(segment
		(start 248.001028 -146.060668)
		(end 173.100492 -146.060668)
		(width 0.12954)
		(layer "In2.Cu")
		(net "TDR_SE_50_OHM_IN1")
	)
	(segment
		(start 173.100492 -143.520668)
		(end 248.001028 -143.520668)
		(width 0.12954)
		(layer "In2.Cu")
		(net "TDR_SE_50_OHM_IN1")
	)
	(segment
		(start 435.23535 -34.80435)
		(end 435.23535 -34.163)
		(width 0.4572)
		(layer "F.Cu")
		(net "P3V3_AUX")
	)
	(segment
		(start 449.43395 -50.927)
		(end 449.43395 -51.562)
		(width 0.4572)
		(layer "F.Cu")
		(net "P3V3_AUX")
	)
	(segment
		(start 435.84495 -32.893)
		(end 435.23535 -32.893)
		(width 0.4572)
		(layer "F.Cu")
		(net "P3V3_AUX")
	)
	(segment
		(start 446.370456 -46.03496)
		(end 446.436496 -46.101)
		(width 0.4572)
		(layer "F.Cu")
		(net "P3V3_AUX")
	)
	(segment
		(start 414.28797 -47.08779)
		(end 413.489648 -47.08779)
		(width 0.4572)
		(layer "F.Cu")
		(net "P3V3_AUX")
	)
	(segment
		(start 297.9928 -88.1888)
		(end 298.704 -88.9)
		(width 0.4572)
		(layer "F.Cu")
		(net "P3V3_AUX")
	)
	(segment
		(start 439.90895 -51.181)
		(end 439.90895 -50.546)
		(width 0.4572)
		(layer "F.Cu")
		(net "P3V3_AUX")
	)
	(segment
		(start 186.563 -78.08595)
		(end 185.928 -78.08595)
		(width 0.4572)
		(layer "F.Cu")
		(net "P3V3_AUX")
	)
	(segment
		(start 452.073264 -85.470746)
		(end 451.057264 -85.470746)
		(width 0.4572)
		(layer "F.Cu")
		(net "P3V3_AUX")
	)
	(segment
		(start 409.55595 -43.053)
		(end 409.55595 -42.037)
		(width 0.4572)
		(layer "F.Cu")
		(net "P3V3_AUX")
	)
	(segment
		(start 165.989 -83.83905)
		(end 167.005 -83.83905)
		(width 0.4572)
		(layer "F.Cu")
		(net "P3V3_AUX")
	)
	(segment
		(start 455.4474 -64.28105)
		(end 455.4474 -82.676746)
		(width 0.4572)
		(layer "F.Cu")
		(net "P3V3_AUX")
	)
	(segment
		(start 448.03695 -38.862)
		(end 446.44056 -38.862)
		(width 0.4572)
		(layer "F.Cu")
		(net "P3V3_AUX")
	)
	(segment
		(start 435.84495 -29.083)
		(end 435.235096 -29.083)
		(width 0.4572)
		(layer "F.Cu")
		(net "P3V3_AUX")
	)
	(segment
		(start 279.4254 -61.849)
		(end 277.79345 -61.849)
		(width 0.4572)
		(layer "F.Cu")
		(net "P3V3_AUX")
	)
	(segment
		(start 452.6534 -85.470746)
		(end 452.073264 -85.470746)
		(width 0.4572)
		(layer "F.Cu")
		(net "P3V3_AUX")
	)
	(segment
		(start 432.9684 -51.181)
		(end 432.7144 -50.927)
		(width 0.4572)
		(layer "F.Cu")
		(net "P3V3_AUX")
	)
	(segment
		(start 428.2694 -48.895)
		(end 428.2694 -51.17592)
		(width 0.4572)
		(layer "F.Cu")
		(net "P3V3_AUX")
	)
	(segment
		(start 422.89095 -47.371)
		(end 422.89095 -48.59655)
		(width 0.4572)
		(layer "F.Cu")
		(net "P3V3_AUX")
	)
	(segment
		(start 416.033712 -46.717966)
		(end 414.657794 -46.717966)
		(width 0.4572)
		(layer "F.Cu")
		(net "P3V3_AUX")
	)
	(segment
		(start 435.84495 -34.163)
		(end 435.23535 -34.163)
		(width 0.4572)
		(layer "F.Cu")
		(net "P3V3_AUX")
	)
	(segment
		(start 443.820042 -46.03496)
		(end 446.370456 -46.03496)
		(width 0.4572)
		(layer "F.Cu")
		(net "P3V3_AUX")
	)
	(segment
		(start 430.67605 -41.783)
		(end 431.285904 -41.783)
		(width 0.4572)
		(layer "F.Cu")
		(net "P3V3_AUX")
	)
	(segment
		(start 186.563 -78.08595)
		(end 186.563 -77.396086)
		(width 0.4572)
		(layer "F.Cu")
		(net "P3V3_AUX")
	)
	(segment
		(start 435.93385 -23.749)
		(end 436.54345 -23.749)
		(width 0.4572)
		(layer "F.Cu")
		(net "P3V3_AUX")
	)
	(segment
		(start 432.7144 -50.927)
		(end 430.59096 -50.927)
		(width 0.4572)
		(layer "F.Cu")
		(net "P3V3_AUX")
	)
	(segment
		(start 435.84495 -27.813)
		(end 435.235096 -27.813)
		(width 0.4572)
		(layer "F.Cu")
		(net "P3V3_AUX")
	)
	(segment
		(start 171.4754 -77.343)
		(end 171.9834 -76.835)
		(width 0.4572)
		(layer "F.Cu")
		(net "P3V3_AUX")
	)
	(segment
		(start 410.737304 -47.13605)
		(end 411.099 -47.13605)
		(width 0.4572)
		(layer "F.Cu")
		(net "P3V3_AUX")
	)
	(segment
		(start 449.72605 -27.813)
		(end 450.33565 -27.813)
		(width 0.4572)
		(layer "F.Cu")
		(net "P3V3_AUX")
	)
	(segment
		(start 164.916104 -83.83905)
		(end 165.989 -83.83905)
		(width 0.4572)
		(layer "F.Cu")
		(net "P3V3_AUX")
	)
	(segment
		(start 298.704 -88.9)
		(end 297.434 -90.17)
		(width 0.4572)
		(layer "F.Cu")
		(net "P3V3_AUX")
	)
	(segment
		(start 430.59096 -50.927)
		(end 430.149 -51.36896)
		(width 0.4572)
		(layer "F.Cu")
		(net "P3V3_AUX")
	)
	(segment
		(start 185.928 -78.08595)
		(end 184.841896 -78.08595)
		(width 0.4572)
		(layer "F.Cu")
		(net "P3V3_AUX")
	)
	(segment
		(start 168.16705 -81.915)
		(end 168.16705 -81.28)
		(width 0.4572)
		(layer "F.Cu")
		(net "P3V3_AUX")
	)
	(segment
		(start 449.72605 -26.543)
		(end 450.33565 -26.543)
		(width 0.4572)
		(layer "F.Cu")
		(net "P3V3_AUX")
	)
	(segment
		(start 430.67605 -40.386)
		(end 431.285904 -40.386)
		(width 0.4572)
		(layer "F.Cu")
		(net "P3V3_AUX")
	)
	(segment
		(start 444.827406 -42.377106)
		(end 445.602106 -42.377106)
		(width 0.3556)
		(layer "F.Cu")
		(net "P3V3_AUX")
	)
	(segment
		(start 297.3578 -88.1888)
		(end 297.9928 -88.1888)
		(width 0.4572)
		(layer "F.Cu")
		(net "P3V3_AUX")
	)
	(segment
		(start 409.55595 -45.954696)
		(end 410.737304 -47.13605)
		(width 0.4572)
		(layer "F.Cu")
		(net "P3V3_AUX")
	)
	(segment
		(start 414.657794 -46.717966)
		(end 414.28797 -47.08779)
		(width 0.4572)
		(layer "F.Cu")
		(net "P3V3_AUX")
	)
	(segment
		(start 454.6854 -62.865)
		(end 455.0664 -62.865)
		(width 0.4572)
		(layer "F.Cu")
		(net "P3V3_AUX")
	)
	(segment
		(start 186.563 -77.396086)
		(end 185.518044 -76.35113)
		(width 0.4572)
		(layer "F.Cu")
		(net "P3V3_AUX")
	)
	(segment
		(start 413.489648 -47.08779)
		(end 413.11195 -46.710092)
		(width 0.4572)
		(layer "F.Cu")
		(net "P3V3_AUX")
	)
	(segment
		(start 450.107304 -29.591)
		(end 449.75145 -29.591)
		(width 0.4572)
		(layer "F.Cu")
		(net "P3V3_AUX")
	)
	(segment
		(start 450.84365 -90.5002)
		(end 451.45325 -90.5002)
		(width 0.4572)
		(layer "F.Cu")
		(net "P3V3_AUX")
	)
	(segment
		(start 422.394126 -47.047658)
		(end 422.717468 -47.371)
		(width 0.4572)
		(layer "F.Cu")
		(net "P3V3_AUX")
	)
	(segment
		(start 436.1434 -36.81095)
		(end 436.1434 -35.7124)
		(width 0.4572)
		(layer "F.Cu")
		(net "P3V3_AUX")
	)
	(segment
		(start 449.199 -36.81095)
		(end 449.199 -36.20135)
		(width 0.4572)
		(layer "F.Cu")
		(net "P3V3_AUX")
	)
	(segment
		(start 280.162 -66.294)
		(end 280.162 -62.3062)
		(width 0.4572)
		(layer "F.Cu")
		(net "P3V3_AUX")
	)
	(segment
		(start 416.464496 -47.14875)
		(end 416.033712 -46.717966)
		(width 0.4572)
		(layer "F.Cu")
		(net "P3V3_AUX")
	)
	(segment
		(start 446.44056 -38.862)
		(end 446.018666 -38.440106)
		(width 0.4572)
		(layer "F.Cu")
		(net "P3V3_AUX")
	)
	(segment
		(start 454.6854 -62.865)
		(end 454.5584 -62.738)
		(width 0.4572)
		(layer "F.Cu")
		(net "P3V3_AUX")
	)
	(segment
		(start 448.03695 -42.799)
		(end 448.03695 -43.429936)
		(width 0.4572)
		(layer "F.Cu")
		(net "P3V3_AUX")
	)
	(segment
		(start 297.434 -90.17)
		(end 296.6212 -90.17)
		(width 0.4572)
		(layer "F.Cu")
		(net "P3V3_AUX")
	)
	(segment
		(start 428.2694 -51.17592)
		(end 428.46244 -51.36896)
		(width 0.4572)
		(layer "F.Cu")
		(net "P3V3_AUX")
	)
	(segment
		(start 163.561014 -82.48396)
		(end 164.916104 -83.83905)
		(width 0.4572)
		(layer "F.Cu")
		(net "P3V3_AUX")
	)
	(segment
		(start 279.7048 -61.849)
		(end 279.4254 -61.849)
		(width 0.4572)
		(layer "F.Cu")
		(net "P3V3_AUX")
	)
	(segment
		(start 409.55595 -43.942)
		(end 409.55595 -45.954696)
		(width 0.4572)
		(layer "F.Cu")
		(net "P3V3_AUX")
	)
	(segment
		(start 429.2854 -31.74365)
		(end 429.2854 -32.35325)
		(width 0.4572)
		(layer "F.Cu")
		(net "P3V3_AUX")
	)
	(segment
		(start 430.67605 -44.577)
		(end 431.285904 -44.577)
		(width 0.4572)
		(layer "F.Cu")
		(net "P3V3_AUX")
	)
	(segment
		(start 425.2214 -48.514)
		(end 427.8884 -48.514)
		(width 0.4572)
		(layer "F.Cu")
		(net "P3V3_AUX")
	)
	(segment
		(start 279.527 -66.929)
		(end 280.162 -66.294)
		(width 0.4572)
		(layer "F.Cu")
		(net "P3V3_AUX")
	)
	(segment
		(start 412.495746 -46.482)
		(end 413.11195 -46.482)
		(width 0.4572)
		(layer "F.Cu")
		(net "P3V3_AUX")
	)
	(segment
		(start 423.214546 -48.920146)
		(end 424.815254 -48.920146)
		(width 0.4572)
		(layer "F.Cu")
		(net "P3V3_AUX")
	)
	(segment
		(start 446.018666 -38.440106)
		(end 444.827406 -38.440106)
		(width 0.3556)
		(layer "F.Cu")
		(net "P3V3_AUX")
	)
	(segment
		(start 437.62295 -44.45)
		(end 437.013096 -44.45)
		(width 0.4572)
		(layer "F.Cu")
		(net "P3V3_AUX")
	)
	(segment
		(start 295.25595 -87.35695)
		(end 295.25595 -86.487)
		(width 0.4572)
		(layer "F.Cu")
		(net "P3V3_AUX")
	)
	(segment
		(start 446.436496 -46.101)
		(end 447.02095 -46.101)
		(width 0.4572)
		(layer "F.Cu")
		(net "P3V3_AUX")
	)
	(segment
		(start 296.7228 -88.8238)
		(end 295.25595 -87.35695)
		(width 0.4572)
		(layer "F.Cu")
		(net "P3V3_AUX")
	)
	(segment
		(start 449.199 -40.74795)
		(end 449.199 -40.13835)
		(width 0.4572)
		(layer "F.Cu")
		(net "P3V3_AUX")
	)
	(segment
		(start 413.11195 -46.710092)
		(end 413.11195 -46.482)
		(width 0.4572)
		(layer "F.Cu")
		(net "P3V3_AUX")
	)
	(segment
		(start 411.099 -47.13605)
		(end 411.841696 -47.13605)
		(width 0.4572)
		(layer "F.Cu")
		(net "P3V3_AUX")
	)
	(segment
		(start 445.2366 -34.163)
		(end 448.92595 -34.163)
		(width 0.4572)
		(layer "F.Cu")
		(net "P3V3_AUX")
	)
	(segment
		(start 428.46244 -51.36896)
		(end 428.2694 -51.562)
		(width 0.4572)
		(layer "F.Cu")
		(net "P3V3_AUX")
	)
	(segment
		(start 455.4474 -63.246)
		(end 455.4474 -64.28105)
		(width 0.4572)
		(layer "F.Cu")
		(net "P3V3_AUX")
	)
	(segment
		(start 422.394126 -46.297342)
		(end 422.394126 -47.047658)
		(width 0.4572)
		(layer "F.Cu")
		(net "P3V3_AUX")
	)
	(segment
		(start 435.705504 -49.46904)
		(end 435.705504 -48.438054)
		(width 0.4572)
		(layer "F.Cu")
		(net "P3V3_AUX")
	)
	(segment
		(start 277.79345 -61.849)
		(end 275.76145 -63.881)
		(width 0.4572)
		(layer "F.Cu")
		(net "P3V3_AUX")
	)
	(segment
		(start 427.355 -30.94355)
		(end 428.0154 -30.94355)
		(width 0.4572)
		(layer "F.Cu")
		(net "P3V3_AUX")
	)
	(segment
		(start 429.5394 -27.8384)
		(end 429.5394 -27.2542)
		(width 0.4572)
		(layer "F.Cu")
		(net "P3V3_AUX")
	)
	(segment
		(start 430.67605 -43.18)
		(end 431.285904 -43.18)
		(width 0.4572)
		(layer "F.Cu")
		(net "P3V3_AUX")
	)
	(segment
		(start 430.149 -51.36896)
		(end 428.46244 -51.36896)
		(width 0.4572)
		(layer "F.Cu")
		(net "P3V3_AUX")
	)
	(segment
		(start 428.0154 -29.3624)
		(end 429.5394 -27.8384)
		(width 0.4572)
		(layer "F.Cu")
		(net "P3V3_AUX")
	)
	(segment
		(start 436.1434 -35.7124)
		(end 435.23535 -34.80435)
		(width 0.4572)
		(layer "F.Cu")
		(net "P3V3_AUX")
	)
	(segment
		(start 184.841896 -78.08595)
		(end 184.291986 -77.53604)
		(width 0.4572)
		(layer "F.Cu")
		(net "P3V3_AUX")
	)
	(segment
		(start 430.67605 -45.974)
		(end 431.28565 -45.974)
		(width 0.4572)
		(layer "F.Cu")
		(net "P3V3_AUX")
	)
	(segment
		(start 448.92595 -34.163)
		(end 448.92595 -34.798)
		(width 0.4572)
		(layer "F.Cu")
		(net "P3V3_AUX")
	)
	(segment
		(start 430.67605 -38.989)
		(end 431.285904 -38.989)
		(width 0.4572)
		(layer "F.Cu")
		(net "P3V3_AUX")
	)
	(segment
		(start 450.361304 -29.845)
		(end 450.107304 -29.591)
		(width 0.4572)
		(layer "F.Cu")
		(net "P3V3_AUX")
	)
	(segment
		(start 171.9834 -76.835)
		(end 172.09135 -76.835)
		(width 0.4572)
		(layer "F.Cu")
		(net "P3V3_AUX")
	)
	(segment
		(start 280.162 -62.3062)
		(end 279.7048 -61.849)
		(width 0.4572)
		(layer "F.Cu")
		(net "P3V3_AUX")
	)
	(segment
		(start 435.93385 -22.352)
		(end 436.54345 -22.352)
		(width 0.4572)
		(layer "F.Cu")
		(net "P3V3_AUX")
	)
	(segment
		(start 422.698418 -45.99305)
		(end 422.394126 -46.297342)
		(width 0.3556)
		(layer "F.Cu")
		(net "P3V3_AUX")
	)
	(segment
		(start 455.0664 -62.865)
		(end 455.4474 -63.246)
		(width 0.4572)
		(layer "F.Cu")
		(net "P3V3_AUX")
	)
	(segment
		(start 447.02095 -46.101)
		(end 447.02095 -45.4406)
		(width 0.4572)
		(layer "F.Cu")
		(net "P3V3_AUX")
	)
	(segment
		(start 430.67605 -37.592)
		(end 431.285904 -37.592)
		(width 0.4572)
		(layer "F.Cu")
		(net "P3V3_AUX")
	)
	(segment
		(start 428.2694 -52.451)
		(end 427.86935 -52.85105)
		(width 0.4572)
		(layer "F.Cu")
		(net "P3V3_AUX")
	)
	(segment
		(start 427.8884 -48.514)
		(end 428.2694 -48.895)
		(width 0.4572)
		(layer "F.Cu")
		(net "P3V3_AUX")
	)
	(segment
		(start 435.93385 -25.146)
		(end 436.54345 -25.146)
		(width 0.4572)
		(layer "F.Cu")
		(net "P3V3_AUX")
	)
	(segment
		(start 455.4474 -82.676746)
		(end 452.6534 -85.470746)
		(width 0.4572)
		(layer "F.Cu")
		(net "P3V3_AUX")
	)
	(segment
		(start 424.815254 -48.920146)
		(end 425.2214 -48.514)
		(width 0.4572)
		(layer "F.Cu")
		(net "P3V3_AUX")
	)
	(segment
		(start 423.291 -45.99305)
		(end 422.698418 -45.99305)
		(width 0.3556)
		(layer "F.Cu")
		(net "P3V3_AUX")
	)
	(segment
		(start 428.2694 -51.562)
		(end 428.2694 -52.451)
		(width 0.4572)
		(layer "F.Cu")
		(net "P3V3_AUX")
	)
	(segment
		(start 448.03695 -38.862)
		(end 448.03695 -39.492936)
		(width 0.4572)
		(layer "F.Cu")
		(net "P3V3_AUX")
	)
	(segment
		(start 422.89095 -48.59655)
		(end 423.214546 -48.920146)
		(width 0.4572)
		(layer "F.Cu")
		(net "P3V3_AUX")
	)
	(segment
		(start 435.84495 -30.353)
		(end 435.235096 -30.353)
		(width 0.4572)
		(layer "F.Cu")
		(net "P3V3_AUX")
	)
	(segment
		(start 445.75095 -50.927)
		(end 445.75095 -51.562)
		(width 0.4572)
		(layer "F.Cu")
		(net "P3V3_AUX")
	)
	(segment
		(start 435.40045 -48.133)
		(end 435.40045 -47.498)
		(width 0.4572)
		(layer "F.Cu")
		(net "P3V3_AUX")
	)
	(segment
		(start 427.86935 -52.85105)
		(end 419.88105 -52.85105)
		(width 0.4572)
		(layer "F.Cu")
		(net "P3V3_AUX")
	)
	(segment
		(start 445.602106 -42.377106)
		(end 446.024 -42.799)
		(width 0.3556)
		(layer "F.Cu")
		(net "P3V3_AUX")
	)
	(segment
		(start 435.705504 -48.438054)
		(end 435.40045 -48.133)
		(width 0.4572)
		(layer "F.Cu")
		(net "P3V3_AUX")
	)
	(segment
		(start 428.0154 -30.94355)
		(end 428.0154 -29.3624)
		(width 0.4572)
		(layer "F.Cu")
		(net "P3V3_AUX")
	)
	(segment
		(start 435.991 -40.4114)
		(end 436.2704 -40.132)
		(width 0.4572)
		(layer "F.Cu")
		(net "P3V3_AUX")
	)
	(segment
		(start 409.55595 -43.942)
		(end 409.55595 -43.053)
		(width 0.4572)
		(layer "F.Cu")
		(net "P3V3_AUX")
	)
	(segment
		(start 435.991 -40.74795)
		(end 435.991 -40.4114)
		(width 0.4572)
		(layer "F.Cu")
		(net "P3V3_AUX")
	)
	(segment
		(start 446.024 -42.799)
		(end 448.03695 -42.799)
		(width 0.4572)
		(layer "F.Cu")
		(net "P3V3_AUX")
	)
	(segment
		(start 411.841696 -47.13605)
		(end 412.495746 -46.482)
		(width 0.4572)
		(layer "F.Cu")
		(net "P3V3_AUX")
	)
	(segment
		(start 419.88105 -52.85105)
		(end 416.464496 -49.434496)
		(width 0.4572)
		(layer "F.Cu")
		(net "P3V3_AUX")
	)
	(segment
		(start 422.717468 -47.371)
		(end 422.89095 -47.371)
		(width 0.4572)
		(layer "F.Cu")
		(net "P3V3_AUX")
	)
	(segment
		(start 296.7228 -88.8238)
		(end 297.3578 -88.1888)
		(width 0.4572)
		(layer "F.Cu")
		(net "P3V3_AUX")
	)
	(segment
		(start 416.464496 -49.434496)
		(end 416.464496 -47.14875)
		(width 0.4572)
		(layer "F.Cu")
		(net "P3V3_AUX")
	)
	(via
		(at 444.9064 -63.627)
		(size 0.508)
		(drill 0.254)
		(layers "F.Cu" "B.Cu")
		(net "P3V3_AUX")
	)
	(via
		(at 431.285904 -37.592)
		(size 0.508)
		(drill 0.254)
		(layers "F.Cu" "B.Cu")
		(net "P3V3_AUX")
	)
	(via
		(at 448.03695 -39.492936)
		(size 0.508)
		(drill 0.254)
		(layers "F.Cu" "B.Cu")
		(net "P3V3_AUX")
	)
	(via
		(at 168.194736 -73.279)
		(size 0.508)
		(drill 0.254)
		(layers "F.Cu" "B.Cu")
		(net "P3V3_AUX")
	)
	(via
		(at 435.23535 -32.893)
		(size 0.508)
		(drill 0.254)
		(layers "F.Cu" "B.Cu")
		(net "P3V3_AUX")
	)
	(via
		(at 248.5644 -78.98257)
		(size 0.508)
		(drill 0.254)
		(layers "F.Cu" "B.Cu")
		(net "P3V3_AUX")
	)
	(via
		(at 450.959728 -62.828678)
		(size 0.508)
		(drill 0.254)
		(layers "F.Cu" "B.Cu")
		(net "P3V3_AUX")
	)
	(via
		(at 436.54345 -25.146)
		(size 0.508)
		(drill 0.254)
		(layers "F.Cu" "B.Cu")
		(net "P3V3_AUX")
	)
	(via
		(at 295.25595 -86.487)
		(size 0.508)
		(drill 0.254)
		(layers "F.Cu" "B.Cu")
		(net "P3V3_AUX")
	)
	(via
		(at 450.959728 -63.590678)
		(size 0.508)
		(drill 0.254)
		(layers "F.Cu" "B.Cu")
		(net "P3V3_AUX")
	)
	(via
		(at 168.17975 -78.359)
		(size 0.508)
		(drill 0.254)
		(layers "F.Cu" "B.Cu")
		(net "P3V3_AUX")
	)
	(via
		(at 444.9064 -62.992)
		(size 0.508)
		(drill 0.254)
		(layers "F.Cu" "B.Cu")
		(net "P3V3_AUX")
	)
	(via
		(at 442.1124 -64.897)
		(size 0.508)
		(drill 0.254)
		(layers "F.Cu" "B.Cu")
		(net "P3V3_AUX")
	)
	(via
		(at 168.16705 -81.28)
		(size 0.508)
		(drill 0.254)
		(layers "F.Cu" "B.Cu")
		(net "P3V3_AUX")
	)
	(via
		(at 435.235096 -27.813)
		(size 0.508)
		(drill 0.254)
		(layers "F.Cu" "B.Cu")
		(net "P3V3_AUX")
	)
	(via
		(at 445.75095 -51.562)
		(size 0.508)
		(drill 0.254)
		(layers "F.Cu" "B.Cu")
		(net "P3V3_AUX")
	)
	(via
		(at 429.2854 -32.35325)
		(size 0.508)
		(drill 0.254)
		(layers "F.Cu" "B.Cu")
		(net "P3V3_AUX")
	)
	(via
		(at 435.40045 -47.498)
		(size 0.508)
		(drill 0.254)
		(layers "F.Cu" "B.Cu")
		(net "P3V3_AUX")
	)
	(via
		(at 450.33565 -27.813)
		(size 0.508)
		(drill 0.254)
		(layers "F.Cu" "B.Cu")
		(net "P3V3_AUX")
	)
	(via
		(at 448.03695 -43.429936)
		(size 0.508)
		(drill 0.254)
		(layers "F.Cu" "B.Cu")
		(net "P3V3_AUX")
	)
	(via
		(at 436.54345 -23.749)
		(size 0.508)
		(drill 0.254)
		(layers "F.Cu" "B.Cu")
		(net "P3V3_AUX")
	)
	(via
		(at 412.06293 -29.19476)
		(size 0.508)
		(drill 0.254)
		(layers "F.Cu" "B.Cu")
		(net "P3V3_AUX")
	)
	(via
		(at 296.6212 -90.17)
		(size 0.508)
		(drill 0.254)
		(layers "F.Cu" "B.Cu")
		(net "P3V3_AUX")
	)
	(via
		(at 279.527 -66.929)
		(size 0.508)
		(drill 0.254)
		(layers "F.Cu" "B.Cu")
		(net "P3V3_AUX")
	)
	(via
		(at 437.013096 -44.45)
		(size 0.508)
		(drill 0.254)
		(layers "F.Cu" "B.Cu")
		(net "P3V3_AUX")
	)
	(via
		(at 168.194736 -72.263)
		(size 0.508)
		(drill 0.254)
		(layers "F.Cu" "B.Cu")
		(net "P3V3_AUX")
	)
	(via
		(at 427.355 -30.94355)
		(size 0.508)
		(drill 0.254)
		(layers "F.Cu" "B.Cu")
		(net "P3V3_AUX")
	)
	(via
		(at 412.623 -37.084)
		(size 0.508)
		(drill 0.254)
		(layers "F.Cu" "B.Cu")
		(net "P3V3_AUX")
	)
	(via
		(at 167.005 -83.83905)
		(size 0.508)
		(drill 0.254)
		(layers "F.Cu" "B.Cu")
		(net "P3V3_AUX")
	)
	(via
		(at 449.43395 -51.562)
		(size 0.508)
		(drill 0.254)
		(layers "F.Cu" "B.Cu")
		(net "P3V3_AUX")
	)
	(via
		(at 431.28565 -45.974)
		(size 0.508)
		(drill 0.254)
		(layers "F.Cu" "B.Cu")
		(net "P3V3_AUX")
	)
	(via
		(at 447.02095 -45.4406)
		(size 0.508)
		(drill 0.254)
		(layers "F.Cu" "B.Cu")
		(net "P3V3_AUX")
	)
	(via
		(at 442.1124 -62.992)
		(size 0.508)
		(drill 0.254)
		(layers "F.Cu" "B.Cu")
		(net "P3V3_AUX")
	)
	(via
		(at 442.1124 -63.627)
		(size 0.508)
		(drill 0.254)
		(layers "F.Cu" "B.Cu")
		(net "P3V3_AUX")
	)
	(via
		(at 444.9064 -65.532)
		(size 0.508)
		(drill 0.254)
		(layers "F.Cu" "B.Cu")
		(net "P3V3_AUX")
	)
	(via
		(at 171.4754 -77.343)
		(size 0.508)
		(drill 0.254)
		(layers "F.Cu" "B.Cu")
		(net "P3V3_AUX")
	)
	(via
		(at 436.2704 -40.132)
		(size 0.508)
		(drill 0.254)
		(layers "F.Cu" "B.Cu")
		(net "P3V3_AUX")
	)
	(via
		(at 442.1124 -65.532)
		(size 0.508)
		(drill 0.254)
		(layers "F.Cu" "B.Cu")
		(net "P3V3_AUX")
	)
	(via
		(at 186.563 -78.08595)
		(size 0.508)
		(drill 0.254)
		(layers "F.Cu" "B.Cu")
		(net "P3V3_AUX")
	)
	(via
		(at 432.9684 -51.181)
		(size 0.508)
		(drill 0.254)
		(layers "F.Cu" "B.Cu")
		(net "P3V3_AUX")
	)
	(via
		(at 449.199 -36.20135)
		(size 0.508)
		(drill 0.254)
		(layers "F.Cu" "B.Cu")
		(net "P3V3_AUX")
	)
	(via
		(at 431.285904 -40.386)
		(size 0.508)
		(drill 0.254)
		(layers "F.Cu" "B.Cu")
		(net "P3V3_AUX")
	)
	(via
		(at 409.9814 -31.75)
		(size 0.508)
		(drill 0.254)
		(layers "F.Cu" "B.Cu")
		(net "P3V3_AUX")
	)
	(via
		(at 431.285904 -41.783)
		(size 0.508)
		(drill 0.254)
		(layers "F.Cu" "B.Cu")
		(net "P3V3_AUX")
	)
	(via
		(at 421.259 -35.052)
		(size 0.508)
		(drill 0.254)
		(layers "F.Cu" "B.Cu")
		(net "P3V3_AUX")
	)
	(via
		(at 451.45325 -90.5002)
		(size 0.508)
		(drill 0.254)
		(layers "F.Cu" "B.Cu")
		(net "P3V3_AUX")
	)
	(via
		(at 448.673728 -63.576454)
		(size 0.508)
		(drill 0.254)
		(layers "F.Cu" "B.Cu")
		(net "P3V3_AUX")
	)
	(via
		(at 435.235096 -30.353)
		(size 0.508)
		(drill 0.254)
		(layers "F.Cu" "B.Cu")
		(net "P3V3_AUX")
	)
	(via
		(at 448.79895 -46.101)
		(size 0.508)
		(drill 0.254)
		(layers "F.Cu" "B.Cu")
		(net "P3V3_AUX")
	)
	(via
		(at 442.1124 -64.262)
		(size 0.508)
		(drill 0.254)
		(layers "F.Cu" "B.Cu")
		(net "P3V3_AUX")
	)
	(via
		(at 426.72 -39.751)
		(size 0.508)
		(drill 0.254)
		(layers "F.Cu" "B.Cu")
		(net "P3V3_AUX")
	)
	(via
		(at 439.90895 -50.546)
		(size 0.508)
		(drill 0.254)
		(layers "F.Cu" "B.Cu")
		(net "P3V3_AUX")
	)
	(via
		(at 279.4254 -61.849)
		(size 0.508)
		(drill 0.254)
		(layers "F.Cu" "B.Cu")
		(net "P3V3_AUX")
	)
	(via
		(at 454.5584 -62.738)
		(size 0.508)
		(drill 0.254)
		(layers "F.Cu" "B.Cu")
		(net "P3V3_AUX")
	)
	(via
		(at 435.23535 -34.163)
		(size 0.508)
		(drill 0.254)
		(layers "F.Cu" "B.Cu")
		(net "P3V3_AUX")
	)
	(via
		(at 431.285904 -44.577)
		(size 0.508)
		(drill 0.254)
		(layers "F.Cu" "B.Cu")
		(net "P3V3_AUX")
	)
	(via
		(at 453.118728 -62.828678)
		(size 0.508)
		(drill 0.254)
		(layers "F.Cu" "B.Cu")
		(net "P3V3_AUX")
	)
	(via
		(at 412.06293 -30.21076)
		(size 0.508)
		(drill 0.254)
		(layers "F.Cu" "B.Cu")
		(net "P3V3_AUX")
	)
	(via
		(at 412.623 -36.195)
		(size 0.508)
		(drill 0.254)
		(layers "F.Cu" "B.Cu")
		(net "P3V3_AUX")
	)
	(via
		(at 444.9064 -64.262)
		(size 0.508)
		(drill 0.254)
		(layers "F.Cu" "B.Cu")
		(net "P3V3_AUX")
	)
	(via
		(at 435.235096 -29.083)
		(size 0.508)
		(drill 0.254)
		(layers "F.Cu" "B.Cu")
		(net "P3V3_AUX")
	)
	(via
		(at 448.673728 -62.814454)
		(size 0.508)
		(drill 0.254)
		(layers "F.Cu" "B.Cu")
		(net "P3V3_AUX")
	)
	(via
		(at 431.285904 -43.18)
		(size 0.508)
		(drill 0.254)
		(layers "F.Cu" "B.Cu")
		(net "P3V3_AUX")
	)
	(via
		(at 453.118728 -63.590678)
		(size 0.508)
		(drill 0.254)
		(layers "F.Cu" "B.Cu")
		(net "P3V3_AUX")
	)
	(via
		(at 448.92595 -34.798)
		(size 0.508)
		(drill 0.254)
		(layers "F.Cu" "B.Cu")
		(net "P3V3_AUX")
	)
	(via
		(at 431.285904 -38.989)
		(size 0.508)
		(drill 0.254)
		(layers "F.Cu" "B.Cu")
		(net "P3V3_AUX")
	)
	(via
		(at 450.361304 -29.845)
		(size 0.508)
		(drill 0.254)
		(layers "F.Cu" "B.Cu")
		(net "P3V3_AUX")
	)
	(via
		(at 449.199 -40.13835)
		(size 0.508)
		(drill 0.254)
		(layers "F.Cu" "B.Cu")
		(net "P3V3_AUX")
	)
	(via
		(at 436.54345 -22.352)
		(size 0.508)
		(drill 0.254)
		(layers "F.Cu" "B.Cu")
		(net "P3V3_AUX")
	)
	(via
		(at 298.704 -88.9)
		(size 0.508)
		(drill 0.254)
		(layers "F.Cu" "B.Cu")
		(net "P3V3_AUX")
	)
	(via
		(at 450.33565 -26.543)
		(size 0.508)
		(drill 0.254)
		(layers "F.Cu" "B.Cu")
		(net "P3V3_AUX")
	)
	(via
		(at 296.7228 -88.8238)
		(size 0.508)
		(drill 0.254)
		(layers "F.Cu" "B.Cu")
		(net "P3V3_AUX")
	)
	(via
		(at 444.9064 -64.897)
		(size 0.508)
		(drill 0.254)
		(layers "F.Cu" "B.Cu")
		(net "P3V3_AUX")
	)
	(segment
		(start 297.419014 -91.76004)
		(end 297.419014 -90.682064)
		(width 0.4572)
		(layer "B.Cu")
		(net "P3V3_AUX")
	)
	(segment
		(start 448.79895 -46.736)
		(end 448.79895 -46.101)
		(width 0.4572)
		(layer "B.Cu")
		(net "P3V3_AUX")
	)
	(segment
		(start 448.03695 -46.736)
		(end 448.79895 -46.736)
		(width 0.4572)
		(layer "B.Cu")
		(net "P3V3_AUX")
	)
	(segment
		(start 298.704 -89.76995)
		(end 298.704 -88.9)
		(width 0.4572)
		(layer "B.Cu")
		(net "P3V3_AUX")
	)
	(segment
		(start 278.80945 -67.945)
		(end 278.80945 -66.929)
		(width 0.4572)
		(layer "B.Cu")
		(net "P3V3_AUX")
	)
	(segment
		(start 422.2369 -36.5379)
		(end 422.591992 -36.892992)
		(width 0.3556)
		(layer "B.Cu")
		(net "P3V3_AUX")
	)
	(segment
		(start 426.99305 -38.989)
		(end 426.99305 -39.47795)
		(width 0.4572)
		(layer "B.Cu")
		(net "P3V3_AUX")
	)
	(segment
		(start 297.419014 -90.682064)
		(end 297.307 -90.57005)
		(width 0.4572)
		(layer "B.Cu")
		(net "P3V3_AUX")
	)
	(segment
		(start 420.51605 -35.052)
		(end 421.259 -35.052)
		(width 0.4572)
		(layer "B.Cu")
		(net "P3V3_AUX")
	)
	(segment
		(start 447.97599 -46.67504)
		(end 448.03695 -46.736)
		(width 0.4572)
		(layer "B.Cu")
		(net "P3V3_AUX")
	)
	(segment
		(start 295.402 -88.28405)
		(end 296.18305 -88.28405)
		(width 0.4572)
		(layer "B.Cu")
		(net "P3V3_AUX")
	)
	(segment
		(start 297.02125 -90.57005)
		(end 296.6212 -90.17)
		(width 0.4572)
		(layer "B.Cu")
		(net "P3V3_AUX")
	)
	(segment
		(start 296.18305 -88.28405)
		(end 296.7228 -88.8238)
		(width 0.4572)
		(layer "B.Cu")
		(net "P3V3_AUX")
	)
	(segment
		(start 453.7964 -89.535)
		(end 452.8312 -90.5002)
		(width 0.4572)
		(layer "B.Cu")
		(net "P3V3_AUX")
	)
	(segment
		(start 452.8312 -90.5002)
		(end 451.45325 -90.5002)
		(width 0.4572)
		(layer "B.Cu")
		(net "P3V3_AUX")
	)
	(segment
		(start 294.06596 -85.837014)
		(end 295.240964 -85.837014)
		(width 0.4572)
		(layer "B.Cu")
		(net "P3V3_AUX")
	)
	(segment
		(start 453.7964 -64.643)
		(end 453.7964 -89.535)
		(width 0.4572)
		(layer "B.Cu")
		(net "P3V3_AUX")
	)
	(segment
		(start 413.23895 -37.084)
		(end 412.623 -37.084)
		(width 0.4572)
		(layer "B.Cu")
		(net "P3V3_AUX")
	)
	(segment
		(start 295.25595 -85.852)
		(end 295.25595 -86.487)
		(width 0.4572)
		(layer "B.Cu")
		(net "P3V3_AUX")
	)
	(segment
		(start 297.307 -90.57005)
		(end 297.02125 -90.57005)
		(width 0.4572)
		(layer "B.Cu")
		(net "P3V3_AUX")
	)
	(segment
		(start 421.90035 -35.052)
		(end 421.90035 -36.20135)
		(width 0.4572)
		(layer "B.Cu")
		(net "P3V3_AUX")
	)
	(segment
		(start 168.78935 -78.359)
		(end 168.17975 -78.359)
		(width 0.4572)
		(layer "B.Cu")
		(net "P3V3_AUX")
	)
	(segment
		(start 446.741296 -46.67504)
		(end 447.97599 -46.67504)
		(width 0.4572)
		(layer "B.Cu")
		(net "P3V3_AUX")
	)
	(segment
		(start 168.810686 -72.263)
		(end 168.194736 -72.263)
		(width 0.4572)
		(layer "B.Cu")
		(net "P3V3_AUX")
	)
	(segment
		(start 278.80945 -61.849)
		(end 279.4254 -61.849)
		(width 0.4572)
		(layer "B.Cu")
		(net "P3V3_AUX")
	)
	(segment
		(start 426.99305 -39.47795)
		(end 426.72 -39.751)
		(width 0.4572)
		(layer "B.Cu")
		(net "P3V3_AUX")
	)
	(segment
		(start 421.90035 -36.20135)
		(end 422.2369 -36.5379)
		(width 0.4572)
		(layer "B.Cu")
		(net "P3V3_AUX")
	)
	(segment
		(start 422.591992 -36.892992)
		(end 423.291 -36.892992)
		(width 0.3556)
		(layer "B.Cu")
		(net "P3V3_AUX")
	)
	(segment
		(start 413.23895 -36.195)
		(end 412.623 -36.195)
		(width 0.4572)
		(layer "B.Cu")
		(net "P3V3_AUX")
	)
	(segment
		(start 421.90035 -35.052)
		(end 421.259 -35.052)
		(width 0.4572)
		(layer "B.Cu")
		(net "P3V3_AUX")
	)
	(segment
		(start 278.80945 -66.929)
		(end 279.527 -66.929)
		(width 0.4572)
		(layer "B.Cu")
		(net "P3V3_AUX")
	)
	(segment
		(start 295.240964 -85.837014)
		(end 295.25595 -85.852)
		(width 0.4572)
		(layer "B.Cu")
		(net "P3V3_AUX")
	)
	(segment
		(start 168.810686 -73.279)
		(end 168.194736 -73.279)
		(width 0.4572)
		(layer "B.Cu")
		(net "P3V3_AUX")
	)
	(segment
		(start 257.76555 -78.98257)
		(end 264.060178 -72.687942)
		(width 0.4572)
		(layer "In2.Cu")
		(net "P3V3_AUX")
	)
	(segment
		(start 264.060178 -72.687942)
		(end 264.060178 -70.925182)
		(width 0.4572)
		(layer "In2.Cu")
		(net "P3V3_AUX")
	)
	(segment
		(start 263.725152 -66.894456)
		(end 266.113514 -64.506094)
		(width 0.4572)
		(layer "In2.Cu")
		(net "P3V3_AUX")
	)
	(segment
		(start 264.060178 -70.925182)
		(end 263.725152 -70.590156)
		(width 0.4572)
		(layer "In2.Cu")
		(net "P3V3_AUX")
	)
	(segment
		(start 279.527 -64.963294)
		(end 279.527 -66.929)
		(width 0.4572)
		(layer "In2.Cu")
		(net "P3V3_AUX")
	)
	(segment
		(start 248.5644 -78.98257)
		(end 257.76555 -78.98257)
		(width 0.4572)
		(layer "In2.Cu")
		(net "P3V3_AUX")
	)
	(segment
		(start 263.725152 -70.590156)
		(end 263.725152 -66.894456)
		(width 0.4572)
		(layer "In2.Cu")
		(net "P3V3_AUX")
	)
	(segment
		(start 266.113514 -64.506094)
		(end 279.0698 -64.506094)
		(width 0.4572)
		(layer "In2.Cu")
		(net "P3V3_AUX")
	)
	(segment
		(start 279.0698 -64.506094)
		(end 279.527 -64.963294)
		(width 0.4572)
		(layer "In2.Cu")
		(net "P3V3_AUX")
	)
	(segment
		(start 296.6212 -91.8718)
		(end 296.6212 -90.17)
		(width 0.4572)
		(layer "In7.Cu")
		(net "P3V3_AUX")
	)
	(segment
		(start 290.576 -94.615)
		(end 291.592 -93.599)
		(width 0.4572)
		(layer "In7.Cu")
		(net "P3V3_AUX")
	)
	(segment
		(start 294.894 -93.599)
		(end 296.6212 -91.8718)
		(width 0.4572)
		(layer "In7.Cu")
		(net "P3V3_AUX")
	)
	(segment
		(start 291.592 -93.599)
		(end 294.894 -93.599)
		(width 0.4572)
		(layer "In7.Cu")
		(net "P3V3_AUX")
	)
	(segment
		(start 396.569692 -118.312692)
		(end 397.637 -119.38)
		(width 0.635)
		(layer "F.Cu")
		(net "P52V_HS1")
	)
	(segment
		(start 396.569692 -97.992692)
		(end 397.637 -99.06)
		(width 0.635)
		(layer "F.Cu")
		(net "P52V_HS1")
	)
	(segment
		(start 396.569692 -120.447308)
		(end 397.637 -119.38)
		(width 0.635)
		(layer "F.Cu")
		(net "P52V_HS1")
	)
	(segment
		(start 396.569692 -140.767308)
		(end 397.637 -139.7)
		(width 0.635)
		(layer "F.Cu")
		(net "P52V_HS1")
	)
	(segment
		(start 396.569692 -77.672692)
		(end 397.637 -78.74)
		(width 0.635)
		(layer "F.Cu")
		(net "P52V_HS1")
	)
	(segment
		(start 397.637 -119.38)
		(end 398.704308 -118.312692)
		(width 0.635)
		(layer "F.Cu")
		(net "P52V_HS1")
	)
	(segment
		(start 378.079 -78.74)
		(end 379.146308 -77.672692)
		(width 0.635)
		(layer "F.Cu")
		(net "P52V_HS1")
	)
	(segment
		(start 378.079 -119.38)
		(end 379.146308 -120.447308)
		(width 0.635)
		(layer "F.Cu")
		(net "P52V_HS1")
	)
	(segment
		(start 397.637 -119.38)
		(end 398.704308 -120.447308)
		(width 0.635)
		(layer "F.Cu")
		(net "P52V_HS1")
	)
	(segment
		(start 377.011692 -97.992692)
		(end 378.079 -99.06)
		(width 0.635)
		(layer "F.Cu")
		(net "P52V_HS1")
	)
	(segment
		(start 377.011692 -120.447308)
		(end 378.079 -119.38)
		(width 0.635)
		(layer "F.Cu")
		(net "P52V_HS1")
	)
	(segment
		(start 397.637 -78.74)
		(end 398.704308 -79.807308)
		(width 0.635)
		(layer "F.Cu")
		(net "P52V_HS1")
	)
	(segment
		(start 397.637 -78.74)
		(end 398.704308 -77.672692)
		(width 0.635)
		(layer "F.Cu")
		(net "P52V_HS1")
	)
	(segment
		(start 378.079 -99.06)
		(end 379.146308 -97.992692)
		(width 0.635)
		(layer "F.Cu")
		(net "P52V_HS1")
	)
	(segment
		(start 378.079 -58.42)
		(end 379.146308 -57.352692)
		(width 0.635)
		(layer "F.Cu")
		(net "P52V_HS1")
	)
	(segment
		(start 397.637 -58.42)
		(end 398.704308 -59.487308)
		(width 0.635)
		(layer "F.Cu")
		(net "P52V_HS1")
	)
	(segment
		(start 378.079 -58.42)
		(end 379.146308 -59.487308)
		(width 0.635)
		(layer "F.Cu")
		(net "P52V_HS1")
	)
	(segment
		(start 378.079 -78.74)
		(end 379.146308 -79.807308)
		(width 0.635)
		(layer "F.Cu")
		(net "P52V_HS1")
	)
	(segment
		(start 396.569692 -79.807308)
		(end 397.637 -78.74)
		(width 0.635)
		(layer "F.Cu")
		(net "P52V_HS1")
	)
	(segment
		(start 396.569692 -100.127308)
		(end 397.637 -99.06)
		(width 0.635)
		(layer "F.Cu")
		(net "P52V_HS1")
	)
	(segment
		(start 377.011692 -118.312692)
		(end 378.079 -119.38)
		(width 0.635)
		(layer "F.Cu")
		(net "P52V_HS1")
	)
	(segment
		(start 377.011692 -138.632692)
		(end 378.079 -139.7)
		(width 0.635)
		(layer "F.Cu")
		(net "P52V_HS1")
	)
	(segment
		(start 396.569692 -138.632692)
		(end 397.637 -139.7)
		(width 0.635)
		(layer "F.Cu")
		(net "P52V_HS1")
	)
	(segment
		(start 378.079 -119.38)
		(end 379.146308 -118.312692)
		(width 0.635)
		(layer "F.Cu")
		(net "P52V_HS1")
	)
	(segment
		(start 378.079 -139.7)
		(end 379.146308 -140.767308)
		(width 0.635)
		(layer "F.Cu")
		(net "P52V_HS1")
	)
	(segment
		(start 397.637 -99.06)
		(end 398.704308 -97.992692)
		(width 0.635)
		(layer "F.Cu")
		(net "P52V_HS1")
	)
	(segment
		(start 396.569692 -57.352692)
		(end 397.637 -58.42)
		(width 0.635)
		(layer "F.Cu")
		(net "P52V_HS1")
	)
	(segment
		(start 377.011692 -100.127308)
		(end 378.079 -99.06)
		(width 0.635)
		(layer "F.Cu")
		(net "P52V_HS1")
	)
	(segment
		(start 397.637 -99.06)
		(end 398.704308 -100.127308)
		(width 0.635)
		(layer "F.Cu")
		(net "P52V_HS1")
	)
	(segment
		(start 377.011692 -79.807308)
		(end 378.079 -78.74)
		(width 0.635)
		(layer "F.Cu")
		(net "P52V_HS1")
	)
	(segment
		(start 377.011692 -57.352692)
		(end 378.079 -58.42)
		(width 0.635)
		(layer "F.Cu")
		(net "P52V_HS1")
	)
	(segment
		(start 397.637 -58.42)
		(end 398.704308 -57.352692)
		(width 0.635)
		(layer "F.Cu")
		(net "P52V_HS1")
	)
	(segment
		(start 396.569692 -59.487308)
		(end 397.637 -58.42)
		(width 0.635)
		(layer "F.Cu")
		(net "P52V_HS1")
	)
	(segment
		(start 377.011692 -140.767308)
		(end 378.079 -139.7)
		(width 0.635)
		(layer "F.Cu")
		(net "P52V_HS1")
	)
	(segment
		(start 397.637 -139.7)
		(end 398.704308 -138.632692)
		(width 0.635)
		(layer "F.Cu")
		(net "P52V_HS1")
	)
	(segment
		(start 377.011692 -77.672692)
		(end 378.079 -78.74)
		(width 0.635)
		(layer "F.Cu")
		(net "P52V_HS1")
	)
	(segment
		(start 397.637 -139.7)
		(end 398.704308 -140.767308)
		(width 0.635)
		(layer "F.Cu")
		(net "P52V_HS1")
	)
	(segment
		(start 378.079 -99.06)
		(end 379.146308 -100.127308)
		(width 0.635)
		(layer "F.Cu")
		(net "P52V_HS1")
	)
	(segment
		(start 378.079 -139.7)
		(end 379.146308 -138.632692)
		(width 0.635)
		(layer "F.Cu")
		(net "P52V_HS1")
	)
	(segment
		(start 377.011692 -59.487308)
		(end 378.079 -58.42)
		(width 0.635)
		(layer "F.Cu")
		(net "P52V_HS1")
	)
	(via
		(at 334.4418 -66.675)
		(size 0.508)
		(drill 0.254)
		(layers "F.Cu" "B.Cu")
		(net "P52V_HS1")
	)
	(via
		(at 333.6798 -44.1198)
		(size 0.508)
		(drill 0.254)
		(layers "F.Cu" "B.Cu")
		(net "P52V_HS1")
	)
	(via
		(at 332.1558 -53.8734)
		(size 0.508)
		(drill 0.254)
		(layers "F.Cu" "B.Cu")
		(net "P52V_HS1")
	)
	(via
		(at 334.4418 -20.8026)
		(size 0.508)
		(drill 0.254)
		(layers "F.Cu" "B.Cu")
		(net "P52V_HS1")
	)
	(via
		(at 332.9178 -31.3182)
		(size 0.508)
		(drill 0.254)
		(layers "F.Cu" "B.Cu")
		(net "P52V_HS1")
	)
	(via
		(at 334.4418 -32.8422)
		(size 0.508)
		(drill 0.254)
		(layers "F.Cu" "B.Cu")
		(net "P52V_HS1")
	)
	(via
		(at 332.1558 -54.6354)
		(size 0.508)
		(drill 0.254)
		(layers "F.Cu" "B.Cu")
		(net "P52V_HS1")
	)
	(via
		(at 332.9178 -77.1906)
		(size 0.508)
		(drill 0.254)
		(layers "F.Cu" "B.Cu")
		(net "P52V_HS1")
	)
	(via
		(at 334.4418 -23.0886)
		(size 0.508)
		(drill 0.254)
		(layers "F.Cu" "B.Cu")
		(net "P52V_HS1")
	)
	(via
		(at 332.1558 -67.437)
		(size 0.508)
		(drill 0.254)
		(layers "F.Cu" "B.Cu")
		(net "P52V_HS1")
	)
	(via
		(at 332.9178 -55.3974)
		(size 0.508)
		(drill 0.254)
		(layers "F.Cu" "B.Cu")
		(net "P52V_HS1")
	)
	(via
		(at 333.6798 -20.0406)
		(size 0.508)
		(drill 0.254)
		(layers "F.Cu" "B.Cu")
		(net "P52V_HS1")
	)
	(via
		(at 335.2038 -56.9214)
		(size 0.508)
		(drill 0.254)
		(layers "F.Cu" "B.Cu")
		(net "P52V_HS1")
	)
	(via
		(at 332.1558 -20.8026)
		(size 0.508)
		(drill 0.254)
		(layers "F.Cu" "B.Cu")
		(net "P52V_HS1")
	)
	(via
		(at 333.6798 -34.3662)
		(size 0.508)
		(drill 0.254)
		(layers "F.Cu" "B.Cu")
		(net "P52V_HS1")
	)
	(via
		(at 335.2038 -20.8026)
		(size 0.508)
		(drill 0.254)
		(layers "F.Cu" "B.Cu")
		(net "P52V_HS1")
	)
	(via
		(at 333.6798 -44.8818)
		(size 0.508)
		(drill 0.254)
		(layers "F.Cu" "B.Cu")
		(net "P52V_HS1")
	)
	(via
		(at 334.4418 -22.3266)
		(size 0.508)
		(drill 0.254)
		(layers "F.Cu" "B.Cu")
		(net "P52V_HS1")
	)
	(via
		(at 334.4418 -21.5646)
		(size 0.508)
		(drill 0.254)
		(layers "F.Cu" "B.Cu")
		(net "P52V_HS1")
	)
	(via
		(at 332.9178 -44.1198)
		(size 0.508)
		(drill 0.254)
		(layers "F.Cu" "B.Cu")
		(net "P52V_HS1")
	)
	(via
		(at 332.9178 -67.437)
		(size 0.508)
		(drill 0.254)
		(layers "F.Cu" "B.Cu")
		(net "P52V_HS1")
	)
	(via
		(at 333.6798 -68.199)
		(size 0.508)
		(drill 0.254)
		(layers "F.Cu" "B.Cu")
		(net "P52V_HS1")
	)
	(via
		(at 332.9178 -20.0406)
		(size 0.508)
		(drill 0.254)
		(layers "F.Cu" "B.Cu")
		(net "P52V_HS1")
	)
	(via
		(at 332.9178 -68.199)
		(size 0.508)
		(drill 0.254)
		(layers "F.Cu" "B.Cu")
		(net "P52V_HS1")
	)
	(via
		(at 335.2038 -34.3662)
		(size 0.508)
		(drill 0.254)
		(layers "F.Cu" "B.Cu")
		(net "P52V_HS1")
	)
	(via
		(at 270.4084 -57.912)
		(size 0.508)
		(drill 0.254)
		(layers "F.Cu" "B.Cu")
		(net "P52V_HS1")
	)
	(via
		(at 333.6798 -77.9526)
		(size 0.508)
		(drill 0.254)
		(layers "F.Cu" "B.Cu")
		(net "P52V_HS1")
	)
	(via
		(at 332.1558 -32.8422)
		(size 0.508)
		(drill 0.254)
		(layers "F.Cu" "B.Cu")
		(net "P52V_HS1")
	)
	(via
		(at 332.1558 -32.0802)
		(size 0.508)
		(drill 0.254)
		(layers "F.Cu" "B.Cu")
		(net "P52V_HS1")
	)
	(via
		(at 334.4418 -67.437)
		(size 0.508)
		(drill 0.254)
		(layers "F.Cu" "B.Cu")
		(net "P52V_HS1")
	)
	(via
		(at 333.6798 -43.3578)
		(size 0.508)
		(drill 0.254)
		(layers "F.Cu" "B.Cu")
		(net "P52V_HS1")
	)
	(via
		(at 334.4418 -65.151)
		(size 0.508)
		(drill 0.254)
		(layers "F.Cu" "B.Cu")
		(net "P52V_HS1")
	)
	(via
		(at 332.9178 -53.8734)
		(size 0.508)
		(drill 0.254)
		(layers "F.Cu" "B.Cu")
		(net "P52V_HS1")
	)
	(via
		(at 332.9178 -21.5646)
		(size 0.508)
		(drill 0.254)
		(layers "F.Cu" "B.Cu")
		(net "P52V_HS1")
	)
	(via
		(at 332.9178 -56.9214)
		(size 0.508)
		(drill 0.254)
		(layers "F.Cu" "B.Cu")
		(net "P52V_HS1")
	)
	(via
		(at 332.9178 -43.3578)
		(size 0.508)
		(drill 0.254)
		(layers "F.Cu" "B.Cu")
		(net "P52V_HS1")
	)
	(via
		(at 335.2038 -33.6042)
		(size 0.508)
		(drill 0.254)
		(layers "F.Cu" "B.Cu")
		(net "P52V_HS1")
	)
	(via
		(at 335.2038 -31.3182)
		(size 0.508)
		(drill 0.254)
		(layers "F.Cu" "B.Cu")
		(net "P52V_HS1")
	)
	(via
		(at 332.1558 -45.6438)
		(size 0.508)
		(drill 0.254)
		(layers "F.Cu" "B.Cu")
		(net "P52V_HS1")
	)
	(via
		(at 335.2038 -76.4286)
		(size 0.508)
		(drill 0.254)
		(layers "F.Cu" "B.Cu")
		(net "P52V_HS1")
	)
	(via
		(at 332.9178 -42.5958)
		(size 0.508)
		(drill 0.254)
		(layers "F.Cu" "B.Cu")
		(net "P52V_HS1")
	)
	(via
		(at 333.6798 -76.4286)
		(size 0.508)
		(drill 0.254)
		(layers "F.Cu" "B.Cu")
		(net "P52V_HS1")
	)
	(via
		(at 335.2038 -54.6354)
		(size 0.508)
		(drill 0.254)
		(layers "F.Cu" "B.Cu")
		(net "P52V_HS1")
	)
	(via
		(at 333.6798 -66.675)
		(size 0.508)
		(drill 0.254)
		(layers "F.Cu" "B.Cu")
		(net "P52V_HS1")
	)
	(via
		(at 332.1558 -31.3182)
		(size 0.508)
		(drill 0.254)
		(layers "F.Cu" "B.Cu")
		(net "P52V_HS1")
	)
	(via
		(at 334.4418 -42.5958)
		(size 0.508)
		(drill 0.254)
		(layers "F.Cu" "B.Cu")
		(net "P52V_HS1")
	)
	(via
		(at 332.9178 -44.8818)
		(size 0.508)
		(drill 0.254)
		(layers "F.Cu" "B.Cu")
		(net "P52V_HS1")
	)
	(via
		(at 332.1558 -55.3974)
		(size 0.508)
		(drill 0.254)
		(layers "F.Cu" "B.Cu")
		(net "P52V_HS1")
	)
	(via
		(at 332.1558 -76.4286)
		(size 0.508)
		(drill 0.254)
		(layers "F.Cu" "B.Cu")
		(net "P52V_HS1")
	)
	(via
		(at 332.1558 -65.151)
		(size 0.508)
		(drill 0.254)
		(layers "F.Cu" "B.Cu")
		(net "P52V_HS1")
	)
	(via
		(at 262.255 -71.5772)
		(size 0.508)
		(drill 0.254)
		(layers "F.Cu" "B.Cu")
		(net "P52V_HS1")
	)
	(via
		(at 332.1558 -21.5646)
		(size 0.508)
		(drill 0.254)
		(layers "F.Cu" "B.Cu")
		(net "P52V_HS1")
	)
	(via
		(at 332.9178 -23.0886)
		(size 0.508)
		(drill 0.254)
		(layers "F.Cu" "B.Cu")
		(net "P52V_HS1")
	)
	(via
		(at 335.2038 -44.8818)
		(size 0.508)
		(drill 0.254)
		(layers "F.Cu" "B.Cu")
		(net "P52V_HS1")
	)
	(via
		(at 333.6798 -56.9214)
		(size 0.508)
		(drill 0.254)
		(layers "F.Cu" "B.Cu")
		(net "P52V_HS1")
	)
	(via
		(at 271.9324 -57.912)
		(size 0.508)
		(drill 0.254)
		(layers "F.Cu" "B.Cu")
		(net "P52V_HS1")
	)
	(via
		(at 335.2038 -66.675)
		(size 0.508)
		(drill 0.254)
		(layers "F.Cu" "B.Cu")
		(net "P52V_HS1")
	)
	(via
		(at 333.6798 -23.0886)
		(size 0.508)
		(drill 0.254)
		(layers "F.Cu" "B.Cu")
		(net "P52V_HS1")
	)
	(via
		(at 334.4418 -56.1594)
		(size 0.508)
		(drill 0.254)
		(layers "F.Cu" "B.Cu")
		(net "P52V_HS1")
	)
	(via
		(at 332.9178 -76.4286)
		(size 0.508)
		(drill 0.254)
		(layers "F.Cu" "B.Cu")
		(net "P52V_HS1")
	)
	(via
		(at 334.4418 -44.1198)
		(size 0.508)
		(drill 0.254)
		(layers "F.Cu" "B.Cu")
		(net "P52V_HS1")
	)
	(via
		(at 334.4418 -20.0406)
		(size 0.508)
		(drill 0.254)
		(layers "F.Cu" "B.Cu")
		(net "P52V_HS1")
	)
	(via
		(at 334.4418 -76.4286)
		(size 0.508)
		(drill 0.254)
		(layers "F.Cu" "B.Cu")
		(net "P52V_HS1")
	)
	(via
		(at 333.6798 -53.8734)
		(size 0.508)
		(drill 0.254)
		(layers "F.Cu" "B.Cu")
		(net "P52V_HS1")
	)
	(via
		(at 333.6798 -65.913)
		(size 0.508)
		(drill 0.254)
		(layers "F.Cu" "B.Cu")
		(net "P52V_HS1")
	)
	(via
		(at 334.4418 -77.9526)
		(size 0.508)
		(drill 0.254)
		(layers "F.Cu" "B.Cu")
		(net "P52V_HS1")
	)
	(via
		(at 335.2038 -77.1906)
		(size 0.508)
		(drill 0.254)
		(layers "F.Cu" "B.Cu")
		(net "P52V_HS1")
	)
	(via
		(at 335.2038 -23.0886)
		(size 0.508)
		(drill 0.254)
		(layers "F.Cu" "B.Cu")
		(net "P52V_HS1")
	)
	(via
		(at 333.6798 -22.3266)
		(size 0.508)
		(drill 0.254)
		(layers "F.Cu" "B.Cu")
		(net "P52V_HS1")
	)
	(via
		(at 332.1558 -77.1906)
		(size 0.508)
		(drill 0.254)
		(layers "F.Cu" "B.Cu")
		(net "P52V_HS1")
	)
	(via
		(at 335.2038 -20.0406)
		(size 0.508)
		(drill 0.254)
		(layers "F.Cu" "B.Cu")
		(net "P52V_HS1")
	)
	(via
		(at 333.6798 -42.5958)
		(size 0.508)
		(drill 0.254)
		(layers "F.Cu" "B.Cu")
		(net "P52V_HS1")
	)
	(via
		(at 332.9178 -56.1594)
		(size 0.508)
		(drill 0.254)
		(layers "F.Cu" "B.Cu")
		(net "P52V_HS1")
	)
	(via
		(at 332.1558 -33.6042)
		(size 0.508)
		(drill 0.254)
		(layers "F.Cu" "B.Cu")
		(net "P52V_HS1")
	)
	(via
		(at 333.6798 -77.1906)
		(size 0.508)
		(drill 0.254)
		(layers "F.Cu" "B.Cu")
		(net "P52V_HS1")
	)
	(via
		(at 332.1558 -42.5958)
		(size 0.508)
		(drill 0.254)
		(layers "F.Cu" "B.Cu")
		(net "P52V_HS1")
	)
	(via
		(at 333.6798 -54.6354)
		(size 0.508)
		(drill 0.254)
		(layers "F.Cu" "B.Cu")
		(net "P52V_HS1")
	)
	(via
		(at 332.1558 -43.3578)
		(size 0.508)
		(drill 0.254)
		(layers "F.Cu" "B.Cu")
		(net "P52V_HS1")
	)
	(via
		(at 332.9178 -32.0802)
		(size 0.508)
		(drill 0.254)
		(layers "F.Cu" "B.Cu")
		(net "P52V_HS1")
	)
	(via
		(at 297.9928 -80.391)
		(size 0.508)
		(drill 0.254)
		(layers "F.Cu" "B.Cu")
		(net "P52V_HS1")
	)
	(via
		(at 332.9178 -78.7146)
		(size 0.508)
		(drill 0.254)
		(layers "F.Cu" "B.Cu")
		(net "P52V_HS1")
	)
	(via
		(at 335.2038 -56.1594)
		(size 0.508)
		(drill 0.254)
		(layers "F.Cu" "B.Cu")
		(net "P52V_HS1")
	)
	(via
		(at 333.6798 -56.1594)
		(size 0.508)
		(drill 0.254)
		(layers "F.Cu" "B.Cu")
		(net "P52V_HS1")
	)
	(via
		(at 335.2038 -43.3578)
		(size 0.508)
		(drill 0.254)
		(layers "F.Cu" "B.Cu")
		(net "P52V_HS1")
	)
	(via
		(at 333.6798 -55.3974)
		(size 0.508)
		(drill 0.254)
		(layers "F.Cu" "B.Cu")
		(net "P52V_HS1")
	)
	(via
		(at 335.2038 -44.1198)
		(size 0.508)
		(drill 0.254)
		(layers "F.Cu" "B.Cu")
		(net "P52V_HS1")
	)
	(via
		(at 333.6798 -45.6438)
		(size 0.508)
		(drill 0.254)
		(layers "F.Cu" "B.Cu")
		(net "P52V_HS1")
	)
	(via
		(at 335.2038 -65.913)
		(size 0.508)
		(drill 0.254)
		(layers "F.Cu" "B.Cu")
		(net "P52V_HS1")
	)
	(via
		(at 334.4418 -34.3662)
		(size 0.508)
		(drill 0.254)
		(layers "F.Cu" "B.Cu")
		(net "P52V_HS1")
	)
	(via
		(at 281.091894 -78.1558)
		(size 0.508)
		(drill 0.254)
		(layers "F.Cu" "B.Cu")
		(net "P52V_HS1")
	)
	(via
		(at 334.4418 -55.3974)
		(size 0.508)
		(drill 0.254)
		(layers "F.Cu" "B.Cu")
		(net "P52V_HS1")
	)
	(via
		(at 335.2038 -32.0802)
		(size 0.508)
		(drill 0.254)
		(layers "F.Cu" "B.Cu")
		(net "P52V_HS1")
	)
	(via
		(at 332.1558 -77.9526)
		(size 0.508)
		(drill 0.254)
		(layers "F.Cu" "B.Cu")
		(net "P52V_HS1")
	)
	(via
		(at 335.2038 -68.199)
		(size 0.508)
		(drill 0.254)
		(layers "F.Cu" "B.Cu")
		(net "P52V_HS1")
	)
	(via
		(at 332.9178 -77.9526)
		(size 0.508)
		(drill 0.254)
		(layers "F.Cu" "B.Cu")
		(net "P52V_HS1")
	)
	(via
		(at 332.9178 -20.8026)
		(size 0.508)
		(drill 0.254)
		(layers "F.Cu" "B.Cu")
		(net "P52V_HS1")
	)
	(via
		(at 332.1558 -23.0886)
		(size 0.508)
		(drill 0.254)
		(layers "F.Cu" "B.Cu")
		(net "P52V_HS1")
	)
	(via
		(at 332.9178 -33.6042)
		(size 0.508)
		(drill 0.254)
		(layers "F.Cu" "B.Cu")
		(net "P52V_HS1")
	)
	(via
		(at 333.6798 -21.5646)
		(size 0.508)
		(drill 0.254)
		(layers "F.Cu" "B.Cu")
		(net "P52V_HS1")
	)
	(via
		(at 334.4418 -31.3182)
		(size 0.508)
		(drill 0.254)
		(layers "F.Cu" "B.Cu")
		(net "P52V_HS1")
	)
	(via
		(at 333.6798 -78.7146)
		(size 0.508)
		(drill 0.254)
		(layers "F.Cu" "B.Cu")
		(net "P52V_HS1")
	)
	(via
		(at 332.9178 -65.913)
		(size 0.508)
		(drill 0.254)
		(layers "F.Cu" "B.Cu")
		(net "P52V_HS1")
	)
	(via
		(at 334.4418 -44.8818)
		(size 0.508)
		(drill 0.254)
		(layers "F.Cu" "B.Cu")
		(net "P52V_HS1")
	)
	(via
		(at 333.6798 -20.8026)
		(size 0.508)
		(drill 0.254)
		(layers "F.Cu" "B.Cu")
		(net "P52V_HS1")
	)
	(via
		(at 334.4418 -33.6042)
		(size 0.508)
		(drill 0.254)
		(layers "F.Cu" "B.Cu")
		(net "P52V_HS1")
	)
	(via
		(at 332.9178 -66.675)
		(size 0.508)
		(drill 0.254)
		(layers "F.Cu" "B.Cu")
		(net "P52V_HS1")
	)
	(via
		(at 335.2038 -65.151)
		(size 0.508)
		(drill 0.254)
		(layers "F.Cu" "B.Cu")
		(net "P52V_HS1")
	)
	(via
		(at 334.4418 -43.3578)
		(size 0.508)
		(drill 0.254)
		(layers "F.Cu" "B.Cu")
		(net "P52V_HS1")
	)
	(via
		(at 335.2038 -53.8734)
		(size 0.508)
		(drill 0.254)
		(layers "F.Cu" "B.Cu")
		(net "P52V_HS1")
	)
	(via
		(at 334.4418 -68.199)
		(size 0.508)
		(drill 0.254)
		(layers "F.Cu" "B.Cu")
		(net "P52V_HS1")
	)
	(via
		(at 333.6798 -32.0802)
		(size 0.508)
		(drill 0.254)
		(layers "F.Cu" "B.Cu")
		(net "P52V_HS1")
	)
	(via
		(at 269.6464 -57.912)
		(size 0.508)
		(drill 0.254)
		(layers "F.Cu" "B.Cu")
		(net "P52V_HS1")
	)
	(via
		(at 332.1558 -56.1594)
		(size 0.508)
		(drill 0.254)
		(layers "F.Cu" "B.Cu")
		(net "P52V_HS1")
	)
	(via
		(at 332.1558 -34.3662)
		(size 0.508)
		(drill 0.254)
		(layers "F.Cu" "B.Cu")
		(net "P52V_HS1")
	)
	(via
		(at 335.2038 -42.5958)
		(size 0.508)
		(drill 0.254)
		(layers "F.Cu" "B.Cu")
		(net "P52V_HS1")
	)
	(via
		(at 333.6798 -31.3182)
		(size 0.508)
		(drill 0.254)
		(layers "F.Cu" "B.Cu")
		(net "P52V_HS1")
	)
	(via
		(at 332.9178 -79.4766)
		(size 0.508)
		(drill 0.254)
		(layers "F.Cu" "B.Cu")
		(net "P52V_HS1")
	)
	(via
		(at 332.1558 -22.3266)
		(size 0.508)
		(drill 0.254)
		(layers "F.Cu" "B.Cu")
		(net "P52V_HS1")
	)
	(via
		(at 334.4418 -65.913)
		(size 0.508)
		(drill 0.254)
		(layers "F.Cu" "B.Cu")
		(net "P52V_HS1")
	)
	(via
		(at 335.2038 -67.437)
		(size 0.508)
		(drill 0.254)
		(layers "F.Cu" "B.Cu")
		(net "P52V_HS1")
	)
	(via
		(at 332.1558 -44.8818)
		(size 0.508)
		(drill 0.254)
		(layers "F.Cu" "B.Cu")
		(net "P52V_HS1")
	)
	(via
		(at 334.4418 -77.1906)
		(size 0.508)
		(drill 0.254)
		(layers "F.Cu" "B.Cu")
		(net "P52V_HS1")
	)
	(via
		(at 332.1558 -20.0406)
		(size 0.508)
		(drill 0.254)
		(layers "F.Cu" "B.Cu")
		(net "P52V_HS1")
	)
	(via
		(at 333.6798 -33.6042)
		(size 0.508)
		(drill 0.254)
		(layers "F.Cu" "B.Cu")
		(net "P52V_HS1")
	)
	(via
		(at 332.9178 -22.3266)
		(size 0.508)
		(drill 0.254)
		(layers "F.Cu" "B.Cu")
		(net "P52V_HS1")
	)
	(via
		(at 332.1558 -44.1198)
		(size 0.508)
		(drill 0.254)
		(layers "F.Cu" "B.Cu")
		(net "P52V_HS1")
	)
	(via
		(at 261.493 -71.5772)
		(size 0.508)
		(drill 0.254)
		(layers "F.Cu" "B.Cu")
		(net "P52V_HS1")
	)
	(via
		(at 332.1558 -78.7146)
		(size 0.508)
		(drill 0.254)
		(layers "F.Cu" "B.Cu")
		(net "P52V_HS1")
	)
	(via
		(at 332.9178 -34.3662)
		(size 0.508)
		(drill 0.254)
		(layers "F.Cu" "B.Cu")
		(net "P52V_HS1")
	)
	(via
		(at 334.4418 -32.0802)
		(size 0.508)
		(drill 0.254)
		(layers "F.Cu" "B.Cu")
		(net "P52V_HS1")
	)
	(via
		(at 332.1558 -79.4766)
		(size 0.508)
		(drill 0.254)
		(layers "F.Cu" "B.Cu")
		(net "P52V_HS1")
	)
	(via
		(at 333.6798 -67.437)
		(size 0.508)
		(drill 0.254)
		(layers "F.Cu" "B.Cu")
		(net "P52V_HS1")
	)
	(via
		(at 332.1558 -66.675)
		(size 0.508)
		(drill 0.254)
		(layers "F.Cu" "B.Cu")
		(net "P52V_HS1")
	)
	(via
		(at 332.9178 -32.8422)
		(size 0.508)
		(drill 0.254)
		(layers "F.Cu" "B.Cu")
		(net "P52V_HS1")
	)
	(via
		(at 335.2038 -22.3266)
		(size 0.508)
		(drill 0.254)
		(layers "F.Cu" "B.Cu")
		(net "P52V_HS1")
	)
	(via
		(at 332.9178 -45.6438)
		(size 0.508)
		(drill 0.254)
		(layers "F.Cu" "B.Cu")
		(net "P52V_HS1")
	)
	(via
		(at 272.6944 -57.912)
		(size 0.508)
		(drill 0.254)
		(layers "F.Cu" "B.Cu")
		(net "P52V_HS1")
	)
	(via
		(at 280.329894 -78.1558)
		(size 0.508)
		(drill 0.254)
		(layers "F.Cu" "B.Cu")
		(net "P52V_HS1")
	)
	(via
		(at 335.2038 -55.3974)
		(size 0.508)
		(drill 0.254)
		(layers "F.Cu" "B.Cu")
		(net "P52V_HS1")
	)
	(via
		(at 332.1558 -65.913)
		(size 0.508)
		(drill 0.254)
		(layers "F.Cu" "B.Cu")
		(net "P52V_HS1")
	)
	(via
		(at 333.6798 -65.151)
		(size 0.508)
		(drill 0.254)
		(layers "F.Cu" "B.Cu")
		(net "P52V_HS1")
	)
	(via
		(at 335.2038 -21.5646)
		(size 0.508)
		(drill 0.254)
		(layers "F.Cu" "B.Cu")
		(net "P52V_HS1")
	)
	(via
		(at 332.1558 -56.9214)
		(size 0.508)
		(drill 0.254)
		(layers "F.Cu" "B.Cu")
		(net "P52V_HS1")
	)
	(via
		(at 298.7548 -80.391)
		(size 0.508)
		(drill 0.254)
		(layers "F.Cu" "B.Cu")
		(net "P52V_HS1")
	)
	(via
		(at 335.2038 -32.8422)
		(size 0.508)
		(drill 0.254)
		(layers "F.Cu" "B.Cu")
		(net "P52V_HS1")
	)
	(via
		(at 334.4418 -54.6354)
		(size 0.508)
		(drill 0.254)
		(layers "F.Cu" "B.Cu")
		(net "P52V_HS1")
	)
	(via
		(at 334.4418 -56.9214)
		(size 0.508)
		(drill 0.254)
		(layers "F.Cu" "B.Cu")
		(net "P52V_HS1")
	)
	(via
		(at 333.6798 -32.8422)
		(size 0.508)
		(drill 0.254)
		(layers "F.Cu" "B.Cu")
		(net "P52V_HS1")
	)
	(via
		(at 332.9178 -54.6354)
		(size 0.508)
		(drill 0.254)
		(layers "F.Cu" "B.Cu")
		(net "P52V_HS1")
	)
	(via
		(at 332.1558 -68.199)
		(size 0.508)
		(drill 0.254)
		(layers "F.Cu" "B.Cu")
		(net "P52V_HS1")
	)
	(via
		(at 332.9178 -65.151)
		(size 0.508)
		(drill 0.254)
		(layers "F.Cu" "B.Cu")
		(net "P52V_HS1")
	)
	(via
		(at 298.069 -75.819)
		(size 0.508)
		(drill 0.254)
		(layers "F.Cu" "B.Cu")
		(net "P52V_HS1")
	)
	(via
		(at 334.4418 -53.8734)
		(size 0.508)
		(drill 0.254)
		(layers "F.Cu" "B.Cu")
		(net "P52V_HS1")
	)
	(segment
		(start 377.011692 -138.632692)
		(end 378.079 -139.7)
		(width 0.635)
		(layer "B.Cu")
		(net "P52V_HS1")
	)
	(segment
		(start 397.637 -58.42)
		(end 398.704308 -57.352692)
		(width 0.635)
		(layer "B.Cu")
		(net "P52V_HS1")
	)
	(segment
		(start 377.011692 -57.352692)
		(end 378.079 -58.42)
		(width 0.635)
		(layer "B.Cu")
		(net "P52V_HS1")
	)
	(segment
		(start 396.569692 -100.127308)
		(end 397.637 -99.06)
		(width 0.635)
		(layer "B.Cu")
		(net "P52V_HS1")
	)
	(segment
		(start 396.569692 -77.672692)
		(end 397.637 -78.74)
		(width 0.635)
		(layer "B.Cu")
		(net "P52V_HS1")
	)
	(segment
		(start 396.569692 -97.992692)
		(end 397.637 -99.06)
		(width 0.635)
		(layer "B.Cu")
		(net "P52V_HS1")
	)
	(segment
		(start 396.569692 -59.487308)
		(end 397.637 -58.42)
		(width 0.635)
		(layer "B.Cu")
		(net "P52V_HS1")
	)
	(segment
		(start 378.079 -119.38)
		(end 379.146308 -118.312692)
		(width 0.635)
		(layer "B.Cu")
		(net "P52V_HS1")
	)
	(segment
		(start 377.011692 -118.312692)
		(end 378.079 -119.38)
		(width 0.635)
		(layer "B.Cu")
		(net "P52V_HS1")
	)
	(segment
		(start 377.011692 -100.127308)
		(end 378.079 -99.06)
		(width 0.635)
		(layer "B.Cu")
		(net "P52V_HS1")
	)
	(segment
		(start 396.569692 -57.352692)
		(end 397.637 -58.42)
		(width 0.635)
		(layer "B.Cu")
		(net "P52V_HS1")
	)
	(segment
		(start 397.637 -139.7)
		(end 398.704308 -140.767308)
		(width 0.635)
		(layer "B.Cu")
		(net "P52V_HS1")
	)
	(segment
		(start 397.637 -99.06)
		(end 398.704308 -97.992692)
		(width 0.635)
		(layer "B.Cu")
		(net "P52V_HS1")
	)
	(segment
		(start 396.569692 -138.632692)
		(end 397.637 -139.7)
		(width 0.635)
		(layer "B.Cu")
		(net "P52V_HS1")
	)
	(segment
		(start 397.637 -119.38)
		(end 398.704308 -118.312692)
		(width 0.635)
		(layer "B.Cu")
		(net "P52V_HS1")
	)
	(segment
		(start 397.637 -119.38)
		(end 398.704308 -120.447308)
		(width 0.635)
		(layer "B.Cu")
		(net "P52V_HS1")
	)
	(segment
		(start 378.079 -58.42)
		(end 379.146308 -57.352692)
		(width 0.635)
		(layer "B.Cu")
		(net "P52V_HS1")
	)
	(segment
		(start 397.637 -139.7)
		(end 398.704308 -138.632692)
		(width 0.635)
		(layer "B.Cu")
		(net "P52V_HS1")
	)
	(segment
		(start 377.011692 -120.447308)
		(end 378.079 -119.38)
		(width 0.635)
		(layer "B.Cu")
		(net "P52V_HS1")
	)
	(segment
		(start 397.637 -99.06)
		(end 398.704308 -100.127308)
		(width 0.635)
		(layer "B.Cu")
		(net "P52V_HS1")
	)
	(segment
		(start 378.079 -139.7)
		(end 379.146308 -138.632692)
		(width 0.635)
		(layer "B.Cu")
		(net "P52V_HS1")
	)
	(segment
		(start 378.079 -119.38)
		(end 379.146308 -120.447308)
		(width 0.635)
		(layer "B.Cu")
		(net "P52V_HS1")
	)
	(segment
		(start 397.637 -78.74)
		(end 398.704308 -79.807308)
		(width 0.635)
		(layer "B.Cu")
		(net "P52V_HS1")
	)
	(segment
		(start 396.569692 -118.312692)
		(end 397.637 -119.38)
		(width 0.635)
		(layer "B.Cu")
		(net "P52V_HS1")
	)
	(segment
		(start 396.569692 -79.807308)
		(end 397.637 -78.74)
		(width 0.635)
		(layer "B.Cu")
		(net "P52V_HS1")
	)
	(segment
		(start 397.637 -58.42)
		(end 398.704308 -59.487308)
		(width 0.635)
		(layer "B.Cu")
		(net "P52V_HS1")
	)
	(segment
		(start 397.637 -78.74)
		(end 398.704308 -77.672692)
		(width 0.635)
		(layer "B.Cu")
		(net "P52V_HS1")
	)
	(segment
		(start 396.569692 -140.767308)
		(end 397.637 -139.7)
		(width 0.635)
		(layer "B.Cu")
		(net "P52V_HS1")
	)
	(segment
		(start 378.079 -99.06)
		(end 379.146308 -100.127308)
		(width 0.635)
		(layer "B.Cu")
		(net "P52V_HS1")
	)
	(segment
		(start 377.011692 -140.767308)
		(end 378.079 -139.7)
		(width 0.635)
		(layer "B.Cu")
		(net "P52V_HS1")
	)
	(segment
		(start 378.079 -139.7)
		(end 379.146308 -140.767308)
		(width 0.635)
		(layer "B.Cu")
		(net "P52V_HS1")
	)
	(segment
		(start 378.079 -78.74)
		(end 379.146308 -77.672692)
		(width 0.635)
		(layer "B.Cu")
		(net "P52V_HS1")
	)
	(segment
		(start 396.569692 -120.447308)
		(end 397.637 -119.38)
		(width 0.635)
		(layer "B.Cu")
		(net "P52V_HS1")
	)
	(segment
		(start 377.011692 -97.992692)
		(end 378.079 -99.06)
		(width 0.635)
		(layer "B.Cu")
		(net "P52V_HS1")
	)
	(segment
		(start 378.079 -78.74)
		(end 379.146308 -79.807308)
		(width 0.635)
		(layer "B.Cu")
		(net "P52V_HS1")
	)
	(segment
		(start 378.079 -99.06)
		(end 379.146308 -97.992692)
		(width 0.635)
		(layer "B.Cu")
		(net "P52V_HS1")
	)
	(segment
		(start 377.011692 -77.672692)
		(end 378.079 -78.74)
		(width 0.635)
		(layer "B.Cu")
		(net "P52V_HS1")
	)
	(segment
		(start 377.011692 -59.487308)
		(end 378.079 -58.42)
		(width 0.635)
		(layer "B.Cu")
		(net "P52V_HS1")
	)
	(segment
		(start 378.079 -58.42)
		(end 379.146308 -59.487308)
		(width 0.635)
		(layer "B.Cu")
		(net "P52V_HS1")
	)
	(segment
		(start 377.011692 -79.807308)
		(end 378.079 -78.74)
		(width 0.635)
		(layer "B.Cu")
		(net "P52V_HS1")
	)
	(segment
		(start 378.079 -78.74)
		(end 378.884434 -79.545434)
		(width 0.635)
		(layer "In2.Cu")
		(net "P52V_HS1")
	)
	(segment
		(start 396.831566 -140.505434)
		(end 397.637 -139.7)
		(width 0.635)
		(layer "In2.Cu")
		(net "P52V_HS1")
	)
	(segment
		(start 396.831566 -57.614566)
		(end 397.637 -58.42)
		(width 0.508)
		(layer "In2.Cu")
		(net "P52V_HS1")
	)
	(segment
		(start 396.831566 -98.254566)
		(end 397.637 -99.06)
		(width 0.635)
		(layer "In2.Cu")
		(net "P52V_HS1")
	)
	(segment
		(start 378.079 -58.42)
		(end 378.884434 -59.225434)
		(width 0.508)
		(layer "In2.Cu")
		(net "P52V_HS1")
	)
	(segment
		(start 396.831566 -138.894566)
		(end 397.637 -139.7)
		(width 0.635)
		(layer "In2.Cu")
		(net "P52V_HS1")
	)
	(segment
		(start 377.273566 -138.894566)
		(end 378.079 -139.7)
		(width 0.635)
		(layer "In2.Cu")
		(net "P52V_HS1")
	)
	(segment
		(start 397.637 -58.42)
		(end 398.442434 -57.614566)
		(width 0.508)
		(layer "In2.Cu")
		(net "P52V_HS1")
	)
	(segment
		(start 377.273566 -98.254566)
		(end 378.079 -99.06)
		(width 0.635)
		(layer "In2.Cu")
		(net "P52V_HS1")
	)
	(segment
		(start 397.637 -78.74)
		(end 398.442434 -77.934566)
		(width 0.635)
		(layer "In2.Cu")
		(net "P52V_HS1")
	)
	(segment
		(start 396.831566 -79.545434)
		(end 397.637 -78.74)
		(width 0.635)
		(layer "In2.Cu")
		(net "P52V_HS1")
	)
	(segment
		(start 378.079 -139.7)
		(end 378.884434 -140.505434)
		(width 0.635)
		(layer "In2.Cu")
		(net "P52V_HS1")
	)
	(segment
		(start 377.273566 -99.865434)
		(end 378.079 -99.06)
		(width 0.635)
		(layer "In2.Cu")
		(net "P52V_HS1")
	)
	(segment
		(start 377.273566 -120.185434)
		(end 378.079 -119.38)
		(width 0.635)
		(layer "In2.Cu")
		(net "P52V_HS1")
	)
	(segment
		(start 378.079 -58.42)
		(end 378.884434 -57.614566)
		(width 0.508)
		(layer "In2.Cu")
		(net "P52V_HS1")
	)
	(segment
		(start 396.831566 -77.934566)
		(end 397.637 -78.74)
		(width 0.635)
		(layer "In2.Cu")
		(net "P52V_HS1")
	)
	(segment
		(start 377.273566 -118.574566)
		(end 378.079 -119.38)
		(width 0.635)
		(layer "In2.Cu")
		(net "P52V_HS1")
	)
	(segment
		(start 378.079 -139.7)
		(end 378.884434 -138.894566)
		(width 0.635)
		(layer "In2.Cu")
		(net "P52V_HS1")
	)
	(segment
		(start 397.637 -78.74)
		(end 398.442434 -79.545434)
		(width 0.635)
		(layer "In2.Cu")
		(net "P52V_HS1")
	)
	(segment
		(start 396.831566 -99.865434)
		(end 397.637 -99.06)
		(width 0.635)
		(layer "In2.Cu")
		(net "P52V_HS1")
	)
	(segment
		(start 397.637 -119.38)
		(end 398.442434 -118.574566)
		(width 0.635)
		(layer "In2.Cu")
		(net "P52V_HS1")
	)
	(segment
		(start 396.831566 -118.574566)
		(end 397.637 -119.38)
		(width 0.635)
		(layer "In2.Cu")
		(net "P52V_HS1")
	)
	(segment
		(start 378.079 -119.38)
		(end 378.884434 -118.574566)
		(width 0.635)
		(layer "In2.Cu")
		(net "P52V_HS1")
	)
	(segment
		(start 378.079 -99.06)
		(end 378.884434 -99.865434)
		(width 0.635)
		(layer "In2.Cu")
		(net "P52V_HS1")
	)
	(segment
		(start 377.273566 -77.934566)
		(end 378.079 -78.74)
		(width 0.635)
		(layer "In2.Cu")
		(net "P52V_HS1")
	)
	(segment
		(start 378.079 -78.74)
		(end 378.884434 -77.934566)
		(width 0.635)
		(layer "In2.Cu")
		(net "P52V_HS1")
	)
	(segment
		(start 397.637 -139.7)
		(end 398.442434 -140.505434)
		(width 0.635)
		(layer "In2.Cu")
		(net "P52V_HS1")
	)
	(segment
		(start 397.637 -139.7)
		(end 398.442434 -138.894566)
		(width 0.635)
		(layer "In2.Cu")
		(net "P52V_HS1")
	)
	(segment
		(start 397.637 -99.06)
		(end 398.442434 -99.865434)
		(width 0.635)
		(layer "In2.Cu")
		(net "P52V_HS1")
	)
	(segment
		(start 397.637 -99.06)
		(end 398.442434 -98.254566)
		(width 0.635)
		(layer "In2.Cu")
		(net "P52V_HS1")
	)
	(segment
		(start 396.831566 -120.185434)
		(end 397.637 -119.38)
		(width 0.635)
		(layer "In2.Cu")
		(net "P52V_HS1")
	)
	(segment
		(start 377.273566 -57.614566)
		(end 378.079 -58.42)
		(width 0.508)
		(layer "In2.Cu")
		(net "P52V_HS1")
	)
	(segment
		(start 377.273566 -140.505434)
		(end 378.079 -139.7)
		(width 0.635)
		(layer "In2.Cu")
		(net "P52V_HS1")
	)
	(segment
		(start 377.273566 -79.545434)
		(end 378.079 -78.74)
		(width 0.635)
		(layer "In2.Cu")
		(net "P52V_HS1")
	)
	(segment
		(start 396.831566 -59.225434)
		(end 397.637 -58.42)
		(width 0.508)
		(layer "In2.Cu")
		(net "P52V_HS1")
	)
	(segment
		(start 378.079 -119.38)
		(end 378.884434 -120.185434)
		(width 0.635)
		(layer "In2.Cu")
		(net "P52V_HS1")
	)
	(segment
		(start 397.637 -119.38)
		(end 398.442434 -120.185434)
		(width 0.635)
		(layer "In2.Cu")
		(net "P52V_HS1")
	)
	(segment
		(start 377.273566 -59.225434)
		(end 378.079 -58.42)
		(width 0.508)
		(layer "In2.Cu")
		(net "P52V_HS1")
	)
	(segment
		(start 378.079 -99.06)
		(end 378.884434 -98.254566)
		(width 0.635)
		(layer "In2.Cu")
		(net "P52V_HS1")
	)
	(segment
		(start 397.637 -99.06)
		(end 398.442434 -98.254566)
		(width 0.508)
		(layer "In4.Cu")
		(net "P52V_HS1")
	)
	(segment
		(start 396.831566 -59.225434)
		(end 397.637 -58.42)
		(width 0.508)
		(layer "In4.Cu")
		(net "P52V_HS1")
	)
	(segment
		(start 396.831566 -99.865434)
		(end 397.637 -99.06)
		(width 0.508)
		(layer "In4.Cu")
		(net "P52V_HS1")
	)
	(segment
		(start 377.273566 -57.614566)
		(end 378.079 -58.42)
		(width 0.508)
		(layer "In4.Cu")
		(net "P52V_HS1")
	)
	(segment
		(start 396.831566 -120.185434)
		(end 397.637 -119.38)
		(width 0.508)
		(layer "In4.Cu")
		(net "P52V_HS1")
	)
	(segment
		(start 397.637 -78.74)
		(end 398.442434 -79.545434)
		(width 0.508)
		(layer "In4.Cu")
		(net "P52V_HS1")
	)
	(segment
		(start 378.079 -99.06)
		(end 378.884434 -99.865434)
		(width 0.508)
		(layer "In4.Cu")
		(net "P52V_HS1")
	)
	(segment
		(start 378.079 -99.06)
		(end 378.884434 -98.254566)
		(width 0.508)
		(layer "In4.Cu")
		(net "P52V_HS1")
	)
	(segment
		(start 397.637 -58.42)
		(end 398.442434 -57.614566)
		(width 0.508)
		(layer "In4.Cu")
		(net "P52V_HS1")
	)
	(segment
		(start 378.079 -139.7)
		(end 378.884434 -140.505434)
		(width 0.508)
		(layer "In4.Cu")
		(net "P52V_HS1")
	)
	(segment
		(start 397.637 -78.74)
		(end 398.442434 -77.934566)
		(width 0.508)
		(layer "In4.Cu")
		(net "P52V_HS1")
	)
	(segment
		(start 378.079 -78.74)
		(end 378.884434 -79.545434)
		(width 0.508)
		(layer "In4.Cu")
		(net "P52V_HS1")
	)
	(segment
		(start 396.831566 -138.894566)
		(end 397.637 -139.7)
		(width 0.508)
		(layer "In4.Cu")
		(net "P52V_HS1")
	)
	(segment
		(start 378.079 -119.38)
		(end 378.884434 -118.574566)
		(width 0.508)
		(layer "In4.Cu")
		(net "P52V_HS1")
	)
	(segment
		(start 377.273566 -140.505434)
		(end 378.079 -139.7)
		(width 0.508)
		(layer "In4.Cu")
		(net "P52V_HS1")
	)
	(segment
		(start 397.637 -139.7)
		(end 398.442434 -140.505434)
		(width 0.508)
		(layer "In4.Cu")
		(net "P52V_HS1")
	)
	(segment
		(start 396.831566 -140.505434)
		(end 397.637 -139.7)
		(width 0.508)
		(layer "In4.Cu")
		(net "P52V_HS1")
	)
	(segment
		(start 378.079 -119.38)
		(end 378.884434 -120.185434)
		(width 0.508)
		(layer "In4.Cu")
		(net "P52V_HS1")
	)
	(segment
		(start 396.831566 -79.545434)
		(end 397.637 -78.74)
		(width 0.508)
		(layer "In4.Cu")
		(net "P52V_HS1")
	)
	(segment
		(start 378.079 -58.42)
		(end 378.884434 -57.614566)
		(width 0.508)
		(layer "In4.Cu")
		(net "P52V_HS1")
	)
	(segment
		(start 396.831566 -77.934566)
		(end 397.637 -78.74)
		(width 0.508)
		(layer "In4.Cu")
		(net "P52V_HS1")
	)
	(segment
		(start 377.273566 -118.574566)
		(end 378.079 -119.38)
		(width 0.508)
		(layer "In4.Cu")
		(net "P52V_HS1")
	)
	(segment
		(start 397.637 -58.42)
		(end 398.442434 -59.225434)
		(width 0.508)
		(layer "In4.Cu")
		(net "P52V_HS1")
	)
	(segment
		(start 397.637 -99.06)
		(end 398.442434 -99.865434)
		(width 0.508)
		(layer "In4.Cu")
		(net "P52V_HS1")
	)
	(segment
		(start 377.273566 -79.545434)
		(end 378.079 -78.74)
		(width 0.508)
		(layer "In4.Cu")
		(net "P52V_HS1")
	)
	(segment
		(start 377.273566 -59.225434)
		(end 378.079 -58.42)
		(width 0.508)
		(layer "In4.Cu")
		(net "P52V_HS1")
	)
	(segment
		(start 377.273566 -120.185434)
		(end 378.079 -119.38)
		(width 0.508)
		(layer "In4.Cu")
		(net "P52V_HS1")
	)
	(segment
		(start 397.637 -139.7)
		(end 398.442434 -138.894566)
		(width 0.508)
		(layer "In4.Cu")
		(net "P52V_HS1")
	)
	(segment
		(start 397.637 -119.38)
		(end 398.442434 -118.574566)
		(width 0.508)
		(layer "In4.Cu")
		(net "P52V_HS1")
	)
	(segment
		(start 378.079 -78.74)
		(end 378.884434 -77.934566)
		(width 0.508)
		(layer "In4.Cu")
		(net "P52V_HS1")
	)
	(segment
		(start 396.831566 -57.614566)
		(end 397.637 -58.42)
		(width 0.508)
		(layer "In4.Cu")
		(net "P52V_HS1")
	)
	(segment
		(start 377.273566 -138.894566)
		(end 378.079 -139.7)
		(width 0.508)
		(layer "In4.Cu")
		(net "P52V_HS1")
	)
	(segment
		(start 377.273566 -77.934566)
		(end 378.079 -78.74)
		(width 0.508)
		(layer "In4.Cu")
		(net "P52V_HS1")
	)
	(segment
		(start 396.831566 -118.574566)
		(end 397.637 -119.38)
		(width 0.508)
		(layer "In4.Cu")
		(net "P52V_HS1")
	)
	(segment
		(start 378.079 -139.7)
		(end 378.884434 -138.894566)
		(width 0.508)
		(layer "In4.Cu")
		(net "P52V_HS1")
	)
	(segment
		(start 377.273566 -98.254566)
		(end 378.079 -99.06)
		(width 0.508)
		(layer "In4.Cu")
		(net "P52V_HS1")
	)
	(segment
		(start 378.079 -58.42)
		(end 378.884434 -59.225434)
		(width 0.508)
		(layer "In4.Cu")
		(net "P52V_HS1")
	)
	(segment
		(start 397.637 -119.38)
		(end 398.442434 -120.185434)
		(width 0.508)
		(layer "In4.Cu")
		(net "P52V_HS1")
	)
	(segment
		(start 396.831566 -98.254566)
		(end 397.637 -99.06)
		(width 0.508)
		(layer "In4.Cu")
		(net "P52V_HS1")
	)
	(segment
		(start 377.273566 -99.865434)
		(end 378.079 -99.06)
		(width 0.508)
		(layer "In4.Cu")
		(net "P52V_HS1")
	)
	(segment
		(start 378.079 -78.74)
		(end 378.884434 -77.934566)
		(width 0.508)
		(layer "In5.Cu")
		(net "P52V_HS1")
	)
	(segment
		(start 378.079 -58.42)
		(end 378.884434 -57.614566)
		(width 0.508)
		(layer "In5.Cu")
		(net "P52V_HS1")
	)
	(segment
		(start 397.637 -78.74)
		(end 398.442434 -79.545434)
		(width 0.508)
		(layer "In5.Cu")
		(net "P52V_HS1")
	)
	(segment
		(start 377.273566 -57.614566)
		(end 378.079 -58.42)
		(width 0.508)
		(layer "In5.Cu")
		(net "P52V_HS1")
	)
	(segment
		(start 397.637 -139.7)
		(end 398.442434 -140.505434)
		(width 0.508)
		(layer "In5.Cu")
		(net "P52V_HS1")
	)
	(segment
		(start 377.273566 -138.894566)
		(end 378.079 -139.7)
		(width 0.508)
		(layer "In5.Cu")
		(net "P52V_HS1")
	)
	(segment
		(start 378.079 -78.74)
		(end 378.884434 -79.545434)
		(width 0.508)
		(layer "In5.Cu")
		(net "P52V_HS1")
	)
	(segment
		(start 396.831566 -138.894566)
		(end 397.637 -139.7)
		(width 0.508)
		(layer "In5.Cu")
		(net "P52V_HS1")
	)
	(segment
		(start 396.831566 -99.865434)
		(end 397.637 -99.06)
		(width 0.508)
		(layer "In5.Cu")
		(net "P52V_HS1")
	)
	(segment
		(start 378.079 -119.38)
		(end 378.884434 -118.574566)
		(width 0.508)
		(layer "In5.Cu")
		(net "P52V_HS1")
	)
	(segment
		(start 397.637 -58.42)
		(end 398.442434 -59.225434)
		(width 0.508)
		(layer "In5.Cu")
		(net "P52V_HS1")
	)
	(segment
		(start 377.273566 -79.545434)
		(end 378.079 -78.74)
		(width 0.508)
		(layer "In5.Cu")
		(net "P52V_HS1")
	)
	(segment
		(start 396.831566 -57.614566)
		(end 397.637 -58.42)
		(width 0.508)
		(layer "In5.Cu")
		(net "P52V_HS1")
	)
	(segment
		(start 396.831566 -79.545434)
		(end 397.637 -78.74)
		(width 0.508)
		(layer "In5.Cu")
		(net "P52V_HS1")
	)
	(segment
		(start 396.831566 -120.185434)
		(end 397.637 -119.38)
		(width 0.508)
		(layer "In5.Cu")
		(net "P52V_HS1")
	)
	(segment
		(start 377.273566 -98.254566)
		(end 378.079 -99.06)
		(width 0.508)
		(layer "In5.Cu")
		(net "P52V_HS1")
	)
	(segment
		(start 378.079 -139.7)
		(end 378.884434 -138.894566)
		(width 0.508)
		(layer "In5.Cu")
		(net "P52V_HS1")
	)
	(segment
		(start 377.273566 -140.505434)
		(end 378.079 -139.7)
		(width 0.508)
		(layer "In5.Cu")
		(net "P52V_HS1")
	)
	(segment
		(start 397.637 -119.38)
		(end 398.442434 -118.574566)
		(width 0.508)
		(layer "In5.Cu")
		(net "P52V_HS1")
	)
	(segment
		(start 397.637 -99.06)
		(end 398.442434 -99.865434)
		(width 0.508)
		(layer "In5.Cu")
		(net "P52V_HS1")
	)
	(segment
		(start 377.273566 -120.185434)
		(end 378.079 -119.38)
		(width 0.508)
		(layer "In5.Cu")
		(net "P52V_HS1")
	)
	(segment
		(start 378.079 -99.06)
		(end 378.884434 -98.254566)
		(width 0.508)
		(layer "In5.Cu")
		(net "P52V_HS1")
	)
	(segment
		(start 397.637 -139.7)
		(end 398.442434 -138.894566)
		(width 0.508)
		(layer "In5.Cu")
		(net "P52V_HS1")
	)
	(segment
		(start 396.831566 -59.225434)
		(end 397.637 -58.42)
		(width 0.508)
		(layer "In5.Cu")
		(net "P52V_HS1")
	)
	(segment
		(start 397.637 -78.74)
		(end 398.442434 -77.934566)
		(width 0.508)
		(layer "In5.Cu")
		(net "P52V_HS1")
	)
	(segment
		(start 396.831566 -118.574566)
		(end 397.637 -119.38)
		(width 0.508)
		(layer "In5.Cu")
		(net "P52V_HS1")
	)
	(segment
		(start 378.079 -58.42)
		(end 378.884434 -59.225434)
		(width 0.508)
		(layer "In5.Cu")
		(net "P52V_HS1")
	)
	(segment
		(start 377.273566 -77.934566)
		(end 378.079 -78.74)
		(width 0.508)
		(layer "In5.Cu")
		(net "P52V_HS1")
	)
	(segment
		(start 378.079 -119.38)
		(end 378.884434 -120.185434)
		(width 0.508)
		(layer "In5.Cu")
		(net "P52V_HS1")
	)
	(segment
		(start 378.079 -99.06)
		(end 378.884434 -99.865434)
		(width 0.508)
		(layer "In5.Cu")
		(net "P52V_HS1")
	)
	(segment
		(start 397.637 -119.38)
		(end 398.442434 -120.185434)
		(width 0.508)
		(layer "In5.Cu")
		(net "P52V_HS1")
	)
	(segment
		(start 397.637 -58.42)
		(end 398.442434 -57.614566)
		(width 0.508)
		(layer "In5.Cu")
		(net "P52V_HS1")
	)
	(segment
		(start 396.831566 -140.505434)
		(end 397.637 -139.7)
		(width 0.508)
		(layer "In5.Cu")
		(net "P52V_HS1")
	)
	(segment
		(start 377.273566 -59.225434)
		(end 378.079 -58.42)
		(width 0.508)
		(layer "In5.Cu")
		(net "P52V_HS1")
	)
	(segment
		(start 396.831566 -77.934566)
		(end 397.637 -78.74)
		(width 0.508)
		(layer "In5.Cu")
		(net "P52V_HS1")
	)
	(segment
		(start 378.079 -139.7)
		(end 378.884434 -140.505434)
		(width 0.508)
		(layer "In5.Cu")
		(net "P52V_HS1")
	)
	(segment
		(start 396.831566 -98.254566)
		(end 397.637 -99.06)
		(width 0.508)
		(layer "In5.Cu")
		(net "P52V_HS1")
	)
	(segment
		(start 377.273566 -118.574566)
		(end 378.079 -119.38)
		(width 0.508)
		(layer "In5.Cu")
		(net "P52V_HS1")
	)
	(segment
		(start 397.637 -99.06)
		(end 398.442434 -98.254566)
		(width 0.508)
		(layer "In5.Cu")
		(net "P52V_HS1")
	)
	(segment
		(start 377.273566 -99.865434)
		(end 378.079 -99.06)
		(width 0.508)
		(layer "In5.Cu")
		(net "P52V_HS1")
	)
	(segment
		(start 396.831566 -120.185434)
		(end 397.637 -119.38)
		(width 0.635)
		(layer "In7.Cu")
		(net "P52V_HS1")
	)
	(segment
		(start 397.637 -58.42)
		(end 398.442434 -57.614566)
		(width 0.635)
		(layer "In7.Cu")
		(net "P52V_HS1")
	)
	(segment
		(start 397.637 -139.7)
		(end 398.442434 -138.894566)
		(width 0.635)
		(layer "In7.Cu")
		(net "P52V_HS1")
	)
	(segment
		(start 396.831566 -138.894566)
		(end 397.637 -139.7)
		(width 0.635)
		(layer "In7.Cu")
		(net "P52V_HS1")
	)
	(segment
		(start 397.637 -119.38)
		(end 398.442434 -120.185434)
		(width 0.635)
		(layer "In7.Cu")
		(net "P52V_HS1")
	)
	(segment
		(start 378.079 -78.74)
		(end 378.884434 -79.545434)
		(width 0.635)
		(layer "In7.Cu")
		(net "P52V_HS1")
	)
	(segment
		(start 377.273566 -57.614566)
		(end 378.079 -58.42)
		(width 0.635)
		(layer "In7.Cu")
		(net "P52V_HS1")
	)
	(segment
		(start 396.831566 -79.545434)
		(end 397.637 -78.74)
		(width 0.635)
		(layer "In7.Cu")
		(net "P52V_HS1")
	)
	(segment
		(start 377.273566 -99.865434)
		(end 378.079 -99.06)
		(width 0.635)
		(layer "In7.Cu")
		(net "P52V_HS1")
	)
	(segment
		(start 378.079 -78.74)
		(end 378.884434 -77.934566)
		(width 0.635)
		(layer "In7.Cu")
		(net "P52V_HS1")
	)
	(segment
		(start 377.273566 -118.574566)
		(end 378.079 -119.38)
		(width 0.635)
		(layer "In7.Cu")
		(net "P52V_HS1")
	)
	(segment
		(start 397.637 -99.06)
		(end 398.442434 -98.254566)
		(width 0.635)
		(layer "In7.Cu")
		(net "P52V_HS1")
	)
	(segment
		(start 377.273566 -79.545434)
		(end 378.079 -78.74)
		(width 0.635)
		(layer "In7.Cu")
		(net "P52V_HS1")
	)
	(segment
		(start 397.637 -58.42)
		(end 398.442434 -59.225434)
		(width 0.635)
		(layer "In7.Cu")
		(net "P52V_HS1")
	)
	(segment
		(start 397.637 -78.74)
		(end 398.442434 -79.545434)
		(width 0.635)
		(layer "In7.Cu")
		(net "P52V_HS1")
	)
	(segment
		(start 397.637 -119.38)
		(end 398.442434 -118.574566)
		(width 0.635)
		(layer "In7.Cu")
		(net "P52V_HS1")
	)
	(segment
		(start 378.079 -119.38)
		(end 378.884434 -120.185434)
		(width 0.635)
		(layer "In7.Cu")
		(net "P52V_HS1")
	)
	(segment
		(start 377.273566 -140.505434)
		(end 378.079 -139.7)
		(width 0.635)
		(layer "In7.Cu")
		(net "P52V_HS1")
	)
	(segment
		(start 396.831566 -118.574566)
		(end 397.637 -119.38)
		(width 0.635)
		(layer "In7.Cu")
		(net "P52V_HS1")
	)
	(segment
		(start 396.831566 -77.934566)
		(end 397.637 -78.74)
		(width 0.635)
		(layer "In7.Cu")
		(net "P52V_HS1")
	)
	(segment
		(start 377.273566 -138.894566)
		(end 378.079 -139.7)
		(width 0.635)
		(layer "In7.Cu")
		(net "P52V_HS1")
	)
	(segment
		(start 378.079 -99.06)
		(end 378.884434 -98.254566)
		(width 0.635)
		(layer "In7.Cu")
		(net "P52V_HS1")
	)
	(segment
		(start 377.273566 -98.254566)
		(end 378.079 -99.06)
		(width 0.635)
		(layer "In7.Cu")
		(net "P52V_HS1")
	)
	(segment
		(start 377.273566 -120.185434)
		(end 378.079 -119.38)
		(width 0.635)
		(layer "In7.Cu")
		(net "P52V_HS1")
	)
	(segment
		(start 378.079 -99.06)
		(end 378.884434 -99.865434)
		(width 0.635)
		(layer "In7.Cu")
		(net "P52V_HS1")
	)
	(segment
		(start 377.273566 -77.934566)
		(end 378.079 -78.74)
		(width 0.635)
		(layer "In7.Cu")
		(net "P52V_HS1")
	)
	(segment
		(start 378.079 -58.42)
		(end 378.884434 -57.614566)
		(width 0.635)
		(layer "In7.Cu")
		(net "P52V_HS1")
	)
	(segment
		(start 378.079 -139.7)
		(end 378.884434 -140.505434)
		(width 0.635)
		(layer "In7.Cu")
		(net "P52V_HS1")
	)
	(segment
		(start 396.831566 -59.225434)
		(end 397.637 -58.42)
		(width 0.635)
		(layer "In7.Cu")
		(net "P52V_HS1")
	)
	(segment
		(start 396.831566 -57.614566)
		(end 397.637 -58.42)
		(width 0.635)
		(layer "In7.Cu")
		(net "P52V_HS1")
	)
	(segment
		(start 377.273566 -59.225434)
		(end 378.079 -58.42)
		(width 0.635)
		(layer "In7.Cu")
		(net "P52V_HS1")
	)
	(segment
		(start 396.831566 -99.865434)
		(end 397.637 -99.06)
		(width 0.635)
		(layer "In7.Cu")
		(net "P52V_HS1")
	)
	(segment
		(start 378.079 -119.38)
		(end 378.884434 -118.574566)
		(width 0.635)
		(layer "In7.Cu")
		(net "P52V_HS1")
	)
	(segment
		(start 397.637 -139.7)
		(end 398.442434 -140.505434)
		(width 0.635)
		(layer "In7.Cu")
		(net "P52V_HS1")
	)
	(segment
		(start 397.637 -99.06)
		(end 398.442434 -99.865434)
		(width 0.635)
		(layer "In7.Cu")
		(net "P52V_HS1")
	)
	(segment
		(start 397.637 -78.74)
		(end 398.442434 -77.934566)
		(width 0.635)
		(layer "In7.Cu")
		(net "P52V_HS1")
	)
	(segment
		(start 378.079 -58.42)
		(end 378.884434 -59.225434)
		(width 0.635)
		(layer "In7.Cu")
		(net "P52V_HS1")
	)
	(segment
		(start 396.831566 -98.254566)
		(end 397.637 -99.06)
		(width 0.635)
		(layer "In7.Cu")
		(net "P52V_HS1")
	)
	(segment
		(start 396.831566 -140.505434)
		(end 397.637 -139.7)
		(width 0.635)
		(layer "In7.Cu")
		(net "P52V_HS1")
	)
	(segment
		(start 378.079 -139.7)
		(end 378.884434 -138.894566)
		(width 0.635)
		(layer "In7.Cu")
		(net "P52V_HS1")
	)
	(segment
		(start 150.05304 -80.772)
		(end 150.05304 -79.724504)
		(width 0.4572)
		(layer "F.Cu")
		(net "P52V_2")
	)
	(segment
		(start 150.05304 -79.724504)
		(end 150.033736 -79.7052)
		(width 0.4572)
		(layer "F.Cu")
		(net "P52V_2")
	)
	(via
		(at 148.128736 -32.2072)
		(size 0.508)
		(drill 0.254)
		(layers "F.Cu" "B.Cu")
		(net "P52V_2")
	)
	(via
		(at 148.128736 -26.8732)
		(size 0.508)
		(drill 0.254)
		(layers "F.Cu" "B.Cu")
		(net "P52V_2")
	)
	(via
		(at 148.128736 -66.04)
		(size 0.508)
		(drill 0.254)
		(layers "F.Cu" "B.Cu")
		(net "P52V_2")
	)
	(via
		(at 188.608716 -33.288224)
		(size 0.508)
		(drill 0.254)
		(layers "F.Cu" "B.Cu")
		(net "P52V_2")
	)
	(via
		(at 174.112936 -53.975)
		(size 0.508)
		(drill 0.254)
		(layers "F.Cu" "B.Cu")
		(net "P52V_2")
	)
	(via
		(at 174.747936 -53.975)
		(size 0.508)
		(drill 0.254)
		(layers "F.Cu" "B.Cu")
		(net "P52V_2")
	)
	(via
		(at 148.890736 -26.8732)
		(size 0.508)
		(drill 0.254)
		(layers "F.Cu" "B.Cu")
		(net "P52V_2")
	)
	(via
		(at 148.128736 -28.3972)
		(size 0.508)
		(drill 0.254)
		(layers "F.Cu" "B.Cu")
		(net "P52V_2")
	)
	(via
		(at 147.366736 -62.992)
		(size 0.508)
		(drill 0.254)
		(layers "F.Cu" "B.Cu")
		(net "P52V_2")
	)
	(via
		(at 148.890736 -27.6352)
		(size 0.508)
		(drill 0.254)
		(layers "F.Cu" "B.Cu")
		(net "P52V_2")
	)
	(via
		(at 168.778936 -53.975)
		(size 0.508)
		(drill 0.254)
		(layers "F.Cu" "B.Cu")
		(net "P52V_2")
	)
	(via
		(at 147.366736 -30.6832)
		(size 0.508)
		(drill 0.254)
		(layers "F.Cu" "B.Cu")
		(net "P52V_2")
	)
	(via
		(at 150.033736 -78.9432)
		(size 0.508)
		(drill 0.254)
		(layers "F.Cu" "B.Cu")
		(net "P52V_2")
	)
	(via
		(at 148.128736 -61.468)
		(size 0.508)
		(drill 0.254)
		(layers "F.Cu" "B.Cu")
		(net "P52V_2")
	)
	(via
		(at 148.128736 -65.278)
		(size 0.508)
		(drill 0.254)
		(layers "F.Cu" "B.Cu")
		(net "P52V_2")
	)
	(via
		(at 148.128736 -29.9212)
		(size 0.508)
		(drill 0.254)
		(layers "F.Cu" "B.Cu")
		(net "P52V_2")
	)
	(via
		(at 147.366736 -65.278)
		(size 0.508)
		(drill 0.254)
		(layers "F.Cu" "B.Cu")
		(net "P52V_2")
	)
	(via
		(at 148.890736 -28.3972)
		(size 0.508)
		(drill 0.254)
		(layers "F.Cu" "B.Cu")
		(net "P52V_2")
	)
	(via
		(at 147.366736 -66.04)
		(size 0.508)
		(drill 0.254)
		(layers "F.Cu" "B.Cu")
		(net "P52V_2")
	)
	(via
		(at 169.413936 -53.975)
		(size 0.508)
		(drill 0.254)
		(layers "F.Cu" "B.Cu")
		(net "P52V_2")
	)
	(via
		(at 147.366736 -32.2072)
		(size 0.508)
		(drill 0.254)
		(layers "F.Cu" "B.Cu")
		(net "P52V_2")
	)
	(via
		(at 147.366736 -62.23)
		(size 0.508)
		(drill 0.254)
		(layers "F.Cu" "B.Cu")
		(net "P52V_2")
	)
	(via
		(at 148.890736 -31.4452)
		(size 0.508)
		(drill 0.254)
		(layers "F.Cu" "B.Cu")
		(net "P52V_2")
	)
	(via
		(at 150.033736 -79.7052)
		(size 0.508)
		(drill 0.254)
		(layers "F.Cu" "B.Cu")
		(net "P52V_2")
	)
	(via
		(at 148.128736 -64.516)
		(size 0.508)
		(drill 0.254)
		(layers "F.Cu" "B.Cu")
		(net "P52V_2")
	)
	(via
		(at 188.608716 -32.526224)
		(size 0.762)
		(drill 0.254)
		(layers "F.Cu" "B.Cu")
		(net "P52V_2")
	)
	(via
		(at 147.366736 -31.4452)
		(size 0.508)
		(drill 0.254)
		(layers "F.Cu" "B.Cu")
		(net "P52V_2")
	)
	(via
		(at 148.128736 -62.992)
		(size 0.508)
		(drill 0.254)
		(layers "F.Cu" "B.Cu")
		(net "P52V_2")
	)
	(via
		(at 147.366736 -28.3972)
		(size 0.508)
		(drill 0.254)
		(layers "F.Cu" "B.Cu")
		(net "P52V_2")
	)
	(via
		(at 148.128736 -27.6352)
		(size 0.508)
		(drill 0.254)
		(layers "F.Cu" "B.Cu")
		(net "P52V_2")
	)
	(via
		(at 148.128736 -31.4452)
		(size 0.508)
		(drill 0.254)
		(layers "F.Cu" "B.Cu")
		(net "P52V_2")
	)
	(via
		(at 147.366736 -61.468)
		(size 0.508)
		(drill 0.254)
		(layers "F.Cu" "B.Cu")
		(net "P52V_2")
	)
	(via
		(at 147.366736 -29.9212)
		(size 0.508)
		(drill 0.254)
		(layers "F.Cu" "B.Cu")
		(net "P52V_2")
	)
	(via
		(at 171.445936 -53.975)
		(size 0.508)
		(drill 0.254)
		(layers "F.Cu" "B.Cu")
		(net "P52V_2")
	)
	(via
		(at 147.366736 -29.1592)
		(size 0.508)
		(drill 0.254)
		(layers "F.Cu" "B.Cu")
		(net "P52V_2")
	)
	(via
		(at 148.128736 -63.754)
		(size 0.508)
		(drill 0.254)
		(layers "F.Cu" "B.Cu")
		(net "P52V_2")
	)
	(via
		(at 148.128736 -60.706)
		(size 0.508)
		(drill 0.254)
		(layers "F.Cu" "B.Cu")
		(net "P52V_2")
	)
	(via
		(at 148.128736 -29.1592)
		(size 0.508)
		(drill 0.254)
		(layers "F.Cu" "B.Cu")
		(net "P52V_2")
	)
	(via
		(at 147.366736 -63.754)
		(size 0.508)
		(drill 0.254)
		(layers "F.Cu" "B.Cu")
		(net "P52V_2")
	)
	(via
		(at 148.890736 -29.1592)
		(size 0.508)
		(drill 0.254)
		(layers "F.Cu" "B.Cu")
		(net "P52V_2")
	)
	(via
		(at 173.223936 -53.975)
		(size 0.508)
		(drill 0.254)
		(layers "F.Cu" "B.Cu")
		(net "P52V_2")
	)
	(via
		(at 170.810936 -53.975)
		(size 0.508)
		(drill 0.254)
		(layers "F.Cu" "B.Cu")
		(net "P52V_2")
	)
	(via
		(at 147.366736 -26.8732)
		(size 0.508)
		(drill 0.254)
		(layers "F.Cu" "B.Cu")
		(net "P52V_2")
	)
	(via
		(at 148.128736 -30.6832)
		(size 0.508)
		(drill 0.254)
		(layers "F.Cu" "B.Cu")
		(net "P52V_2")
	)
	(via
		(at 187.084716 -33.288224)
		(size 0.762)
		(drill 0.254)
		(layers "F.Cu" "B.Cu")
		(net "P52V_2")
	)
	(via
		(at 148.890736 -30.6832)
		(size 0.508)
		(drill 0.254)
		(layers "F.Cu" "B.Cu")
		(net "P52V_2")
	)
	(via
		(at 148.890736 -29.9212)
		(size 0.508)
		(drill 0.254)
		(layers "F.Cu" "B.Cu")
		(net "P52V_2")
	)
	(via
		(at 148.128736 -62.23)
		(size 0.508)
		(drill 0.254)
		(layers "F.Cu" "B.Cu")
		(net "P52V_2")
	)
	(via
		(at 147.366736 -64.516)
		(size 0.508)
		(drill 0.254)
		(layers "F.Cu" "B.Cu")
		(net "P52V_2")
	)
	(via
		(at 147.366736 -60.706)
		(size 0.508)
		(drill 0.254)
		(layers "F.Cu" "B.Cu")
		(net "P52V_2")
	)
	(via
		(at 187.846716 -33.288224)
		(size 0.508)
		(drill 0.254)
		(layers "F.Cu" "B.Cu")
		(net "P52V_2")
	)
	(via
		(at 147.366736 -27.6352)
		(size 0.508)
		(drill 0.254)
		(layers "F.Cu" "B.Cu")
		(net "P52V_2")
	)
	(via
		(at 172.588936 -53.975)
		(size 0.508)
		(drill 0.254)
		(layers "F.Cu" "B.Cu")
		(net "P52V_2")
	)
	(via
		(at 187.846716 -32.526224)
		(size 0.508)
		(drill 0.254)
		(layers "F.Cu" "B.Cu")
		(net "P52V_2")
	)
	(via
		(at 148.890736 -32.2072)
		(size 0.508)
		(drill 0.254)
		(layers "F.Cu" "B.Cu")
		(net "P52V_2")
	)
	(via
		(at 187.084716 -32.526224)
		(size 0.508)
		(drill 0.254)
		(layers "F.Cu" "B.Cu")
		(net "P52V_2")
	)
	(segment
		(start 61.92139 -119.38)
		(end 62.988698 -118.312692)
		(width 0.635)
		(layer "F.Cu")
		(net "P52V_HS2")
	)
	(segment
		(start 42.36339 -139.7)
		(end 43.430698 -140.767308)
		(width 0.635)
		(layer "F.Cu")
		(net "P52V_HS2")
	)
	(segment
		(start 60.854082 -59.487308)
		(end 61.92139 -58.42)
		(width 0.635)
		(layer "F.Cu")
		(net "P52V_HS2")
	)
	(segment
		(start 60.854082 -118.312692)
		(end 61.92139 -119.38)
		(width 0.635)
		(layer "F.Cu")
		(net "P52V_HS2")
	)
	(segment
		(start 60.854082 -77.672692)
		(end 61.92139 -78.74)
		(width 0.635)
		(layer "F.Cu")
		(net "P52V_HS2")
	)
	(segment
		(start 61.92139 -99.06)
		(end 62.988698 -97.992692)
		(width 0.635)
		(layer "F.Cu")
		(net "P52V_HS2")
	)
	(segment
		(start 41.296082 -120.447308)
		(end 42.36339 -119.38)
		(width 0.635)
		(layer "F.Cu")
		(net "P52V_HS2")
	)
	(segment
		(start 60.854082 -138.632692)
		(end 61.92139 -139.7)
		(width 0.635)
		(layer "F.Cu")
		(net "P52V_HS2")
	)
	(segment
		(start 41.296082 -140.767308)
		(end 42.36339 -139.7)
		(width 0.635)
		(layer "F.Cu")
		(net "P52V_HS2")
	)
	(segment
		(start 61.92139 -58.42)
		(end 62.988698 -57.352692)
		(width 0.635)
		(layer "F.Cu")
		(net "P52V_HS2")
	)
	(segment
		(start 42.36339 -58.42)
		(end 43.430698 -59.487308)
		(width 0.635)
		(layer "F.Cu")
		(net "P52V_HS2")
	)
	(segment
		(start 41.296082 -59.487308)
		(end 42.36339 -58.42)
		(width 0.635)
		(layer "F.Cu")
		(net "P52V_HS2")
	)
	(segment
		(start 60.854082 -120.447308)
		(end 61.92139 -119.38)
		(width 0.635)
		(layer "F.Cu")
		(net "P52V_HS2")
	)
	(segment
		(start 42.36339 -119.38)
		(end 43.430698 -118.312692)
		(width 0.635)
		(layer "F.Cu")
		(net "P52V_HS2")
	)
	(segment
		(start 60.854082 -97.992692)
		(end 61.92139 -99.06)
		(width 0.635)
		(layer "F.Cu")
		(net "P52V_HS2")
	)
	(segment
		(start 42.36339 -78.74)
		(end 43.430698 -77.672692)
		(width 0.635)
		(layer "F.Cu")
		(net "P52V_HS2")
	)
	(segment
		(start 41.296082 -118.312692)
		(end 42.36339 -119.38)
		(width 0.635)
		(layer "F.Cu")
		(net "P52V_HS2")
	)
	(segment
		(start 60.854082 -100.127308)
		(end 61.92139 -99.06)
		(width 0.635)
		(layer "F.Cu")
		(net "P52V_HS2")
	)
	(segment
		(start 42.36339 -58.42)
		(end 43.430698 -57.352692)
		(width 0.635)
		(layer "F.Cu")
		(net "P52V_HS2")
	)
	(segment
		(start 42.36339 -99.06)
		(end 43.430698 -97.992692)
		(width 0.635)
		(layer "F.Cu")
		(net "P52V_HS2")
	)
	(segment
		(start 42.36339 -139.7)
		(end 43.430698 -138.632692)
		(width 0.635)
		(layer "F.Cu")
		(net "P52V_HS2")
	)
	(segment
		(start 42.36339 -78.74)
		(end 43.430698 -79.807308)
		(width 0.635)
		(layer "F.Cu")
		(net "P52V_HS2")
	)
	(segment
		(start 61.92139 -139.7)
		(end 62.988698 -138.632692)
		(width 0.635)
		(layer "F.Cu")
		(net "P52V_HS2")
	)
	(segment
		(start 61.92139 -58.42)
		(end 62.988698 -59.487308)
		(width 0.635)
		(layer "F.Cu")
		(net "P52V_HS2")
	)
	(segment
		(start 60.854082 -57.352692)
		(end 61.92139 -58.42)
		(width 0.635)
		(layer "F.Cu")
		(net "P52V_HS2")
	)
	(segment
		(start 41.296082 -97.992692)
		(end 42.36339 -99.06)
		(width 0.635)
		(layer "F.Cu")
		(net "P52V_HS2")
	)
	(segment
		(start 61.92139 -78.74)
		(end 62.988698 -77.672692)
		(width 0.635)
		(layer "F.Cu")
		(net "P52V_HS2")
	)
	(segment
		(start 41.296082 -57.352692)
		(end 42.36339 -58.42)
		(width 0.635)
		(layer "F.Cu")
		(net "P52V_HS2")
	)
	(segment
		(start 41.296082 -77.672692)
		(end 42.36339 -78.74)
		(width 0.635)
		(layer "F.Cu")
		(net "P52V_HS2")
	)
	(segment
		(start 41.296082 -100.127308)
		(end 42.36339 -99.06)
		(width 0.635)
		(layer "F.Cu")
		(net "P52V_HS2")
	)
	(segment
		(start 61.92139 -99.06)
		(end 62.988698 -100.127308)
		(width 0.635)
		(layer "F.Cu")
		(net "P52V_HS2")
	)
	(segment
		(start 61.92139 -119.38)
		(end 62.988698 -120.447308)
		(width 0.635)
		(layer "F.Cu")
		(net "P52V_HS2")
	)
	(segment
		(start 41.296082 -79.807308)
		(end 42.36339 -78.74)
		(width 0.635)
		(layer "F.Cu")
		(net "P52V_HS2")
	)
	(segment
		(start 41.296082 -138.632692)
		(end 42.36339 -139.7)
		(width 0.635)
		(layer "F.Cu")
		(net "P52V_HS2")
	)
	(segment
		(start 60.854082 -79.807308)
		(end 61.92139 -78.74)
		(width 0.635)
		(layer "F.Cu")
		(net "P52V_HS2")
	)
	(segment
		(start 42.36339 -119.38)
		(end 43.430698 -120.447308)
		(width 0.635)
		(layer "F.Cu")
		(net "P52V_HS2")
	)
	(segment
		(start 61.92139 -78.74)
		(end 62.988698 -79.807308)
		(width 0.635)
		(layer "F.Cu")
		(net "P52V_HS2")
	)
	(segment
		(start 42.36339 -99.06)
		(end 43.430698 -100.127308)
		(width 0.635)
		(layer "F.Cu")
		(net "P52V_HS2")
	)
	(segment
		(start 61.92139 -139.7)
		(end 62.988698 -140.767308)
		(width 0.635)
		(layer "F.Cu")
		(net "P52V_HS2")
	)
	(segment
		(start 60.854082 -140.767308)
		(end 61.92139 -139.7)
		(width 0.635)
		(layer "F.Cu")
		(net "P52V_HS2")
	)
	(via
		(at 112.455452 -49.5808)
		(size 0.508)
		(drill 0.254)
		(layers "F.Cu" "B.Cu")
		(net "P52V_HS2")
	)
	(via
		(at 113.979452 -48.0568)
		(size 0.508)
		(drill 0.254)
		(layers "F.Cu" "B.Cu")
		(net "P52V_HS2")
	)
	(via
		(at 112.455452 -25.5016)
		(size 0.508)
		(drill 0.254)
		(layers "F.Cu" "B.Cu")
		(net "P52V_HS2")
	)
	(via
		(at 113.217452 -59.3344)
		(size 0.508)
		(drill 0.254)
		(layers "F.Cu" "B.Cu")
		(net "P52V_HS2")
	)
	(via
		(at 113.979452 -27.0256)
		(size 0.508)
		(drill 0.254)
		(layers "F.Cu" "B.Cu")
		(net "P52V_HS2")
	)
	(via
		(at 114.741452 -28.5496)
		(size 0.508)
		(drill 0.254)
		(layers "F.Cu" "B.Cu")
		(net "P52V_HS2")
	)
	(via
		(at 114.741452 -37.5412)
		(size 0.508)
		(drill 0.254)
		(layers "F.Cu" "B.Cu")
		(net "P52V_HS2")
	)
	(via
		(at 113.217452 -27.7876)
		(size 0.508)
		(drill 0.254)
		(layers "F.Cu" "B.Cu")
		(net "P52V_HS2")
	)
	(via
		(at 113.979452 -37.5412)
		(size 0.508)
		(drill 0.254)
		(layers "F.Cu" "B.Cu")
		(net "P52V_HS2")
	)
	(via
		(at 115.503452 -48.8188)
		(size 0.508)
		(drill 0.254)
		(layers "F.Cu" "B.Cu")
		(net "P52V_HS2")
	)
	(via
		(at 113.217452 -71.374)
		(size 0.508)
		(drill 0.254)
		(layers "F.Cu" "B.Cu")
		(net "P52V_HS2")
	)
	(via
		(at 112.455452 -48.8188)
		(size 0.508)
		(drill 0.254)
		(layers "F.Cu" "B.Cu")
		(net "P52V_HS2")
	)
	(via
		(at 115.503452 -27.7876)
		(size 0.508)
		(drill 0.254)
		(layers "F.Cu" "B.Cu")
		(net "P52V_HS2")
	)
	(via
		(at 114.741452 -14.986)
		(size 0.508)
		(drill 0.254)
		(layers "F.Cu" "B.Cu")
		(net "P52V_HS2")
	)
	(via
		(at 112.455452 -60.8584)
		(size 0.508)
		(drill 0.254)
		(layers "F.Cu" "B.Cu")
		(net "P52V_HS2")
	)
	(via
		(at 112.455452 -50.3428)
		(size 0.508)
		(drill 0.254)
		(layers "F.Cu" "B.Cu")
		(net "P52V_HS2")
	)
	(via
		(at 114.741452 -17.272)
		(size 0.508)
		(drill 0.254)
		(layers "F.Cu" "B.Cu")
		(net "P52V_HS2")
	)
	(via
		(at 113.979452 -14.224)
		(size 0.508)
		(drill 0.254)
		(layers "F.Cu" "B.Cu")
		(net "P52V_HS2")
	)
	(via
		(at 112.455452 -28.5496)
		(size 0.508)
		(drill 0.254)
		(layers "F.Cu" "B.Cu")
		(net "P52V_HS2")
	)
	(via
		(at 114.741452 -62.3824)
		(size 0.508)
		(drill 0.254)
		(layers "F.Cu" "B.Cu")
		(net "P52V_HS2")
	)
	(via
		(at 113.217452 -26.2636)
		(size 0.508)
		(drill 0.254)
		(layers "F.Cu" "B.Cu")
		(net "P52V_HS2")
	)
	(via
		(at 113.979452 -27.7876)
		(size 0.508)
		(drill 0.254)
		(layers "F.Cu" "B.Cu")
		(net "P52V_HS2")
	)
	(via
		(at 113.217452 -39.8272)
		(size 0.508)
		(drill 0.254)
		(layers "F.Cu" "B.Cu")
		(net "P52V_HS2")
	)
	(via
		(at 115.503452 -49.5808)
		(size 0.508)
		(drill 0.254)
		(layers "F.Cu" "B.Cu")
		(net "P52V_HS2")
	)
	(via
		(at 115.503452 -28.5496)
		(size 0.508)
		(drill 0.254)
		(layers "F.Cu" "B.Cu")
		(net "P52V_HS2")
	)
	(via
		(at 114.741452 -39.0652)
		(size 0.508)
		(drill 0.254)
		(layers "F.Cu" "B.Cu")
		(net "P52V_HS2")
	)
	(via
		(at 113.217452 -72.898)
		(size 0.508)
		(drill 0.254)
		(layers "F.Cu" "B.Cu")
		(net "P52V_HS2")
	)
	(via
		(at 113.979452 -26.2636)
		(size 0.508)
		(drill 0.254)
		(layers "F.Cu" "B.Cu")
		(net "P52V_HS2")
	)
	(via
		(at 115.503452 -14.224)
		(size 0.508)
		(drill 0.254)
		(layers "F.Cu" "B.Cu")
		(net "P52V_HS2")
	)
	(via
		(at 115.503452 -60.8584)
		(size 0.508)
		(drill 0.254)
		(layers "F.Cu" "B.Cu")
		(net "P52V_HS2")
	)
	(via
		(at 113.979452 -36.7792)
		(size 0.508)
		(drill 0.254)
		(layers "F.Cu" "B.Cu")
		(net "P52V_HS2")
	)
	(via
		(at 113.217452 -14.986)
		(size 0.508)
		(drill 0.254)
		(layers "F.Cu" "B.Cu")
		(net "P52V_HS2")
	)
	(via
		(at 114.741452 -72.136)
		(size 0.508)
		(drill 0.254)
		(layers "F.Cu" "B.Cu")
		(net "P52V_HS2")
	)
	(via
		(at 113.217452 -60.8584)
		(size 0.508)
		(drill 0.254)
		(layers "F.Cu" "B.Cu")
		(net "P52V_HS2")
	)
	(via
		(at 114.741452 -71.374)
		(size 0.508)
		(drill 0.254)
		(layers "F.Cu" "B.Cu")
		(net "P52V_HS2")
	)
	(via
		(at 115.503452 -37.5412)
		(size 0.508)
		(drill 0.254)
		(layers "F.Cu" "B.Cu")
		(net "P52V_HS2")
	)
	(via
		(at 167.2844 -60.3758)
		(size 0.508)
		(drill 0.254)
		(layers "F.Cu" "B.Cu")
		(net "P52V_HS2")
	)
	(via
		(at 113.979452 -39.8272)
		(size 0.508)
		(drill 0.254)
		(layers "F.Cu" "B.Cu")
		(net "P52V_HS2")
	)
	(via
		(at 114.741452 -51.1048)
		(size 0.508)
		(drill 0.254)
		(layers "F.Cu" "B.Cu")
		(net "P52V_HS2")
	)
	(via
		(at 185.5724 -68.58)
		(size 0.508)
		(drill 0.254)
		(layers "F.Cu" "B.Cu")
		(net "P52V_HS2")
	)
	(via
		(at 184.8104 -68.58)
		(size 0.508)
		(drill 0.254)
		(layers "F.Cu" "B.Cu")
		(net "P52V_HS2")
	)
	(via
		(at 115.503452 -48.0568)
		(size 0.508)
		(drill 0.254)
		(layers "F.Cu" "B.Cu")
		(net "P52V_HS2")
	)
	(via
		(at 112.455452 -62.3824)
		(size 0.508)
		(drill 0.254)
		(layers "F.Cu" "B.Cu")
		(net "P52V_HS2")
	)
	(via
		(at 113.217452 -51.1048)
		(size 0.508)
		(drill 0.254)
		(layers "F.Cu" "B.Cu")
		(net "P52V_HS2")
	)
	(via
		(at 112.455452 -15.748)
		(size 0.508)
		(drill 0.254)
		(layers "F.Cu" "B.Cu")
		(net "P52V_HS2")
	)
	(via
		(at 115.503452 -16.51)
		(size 0.508)
		(drill 0.254)
		(layers "F.Cu" "B.Cu")
		(net "P52V_HS2")
	)
	(via
		(at 113.979452 -70.612)
		(size 0.508)
		(drill 0.254)
		(layers "F.Cu" "B.Cu")
		(net "P52V_HS2")
	)
	(via
		(at 113.979452 -50.3428)
		(size 0.508)
		(drill 0.254)
		(layers "F.Cu" "B.Cu")
		(net "P52V_HS2")
	)
	(via
		(at 113.217452 -14.224)
		(size 0.508)
		(drill 0.254)
		(layers "F.Cu" "B.Cu")
		(net "P52V_HS2")
	)
	(via
		(at 113.217452 -61.6204)
		(size 0.508)
		(drill 0.254)
		(layers "F.Cu" "B.Cu")
		(net "P52V_HS2")
	)
	(via
		(at 115.503452 -70.612)
		(size 0.508)
		(drill 0.254)
		(layers "F.Cu" "B.Cu")
		(net "P52V_HS2")
	)
	(via
		(at 112.455452 -37.5412)
		(size 0.508)
		(drill 0.254)
		(layers "F.Cu" "B.Cu")
		(net "P52V_HS2")
	)
	(via
		(at 112.455452 -27.7876)
		(size 0.508)
		(drill 0.254)
		(layers "F.Cu" "B.Cu")
		(net "P52V_HS2")
	)
	(via
		(at 113.217452 -72.136)
		(size 0.508)
		(drill 0.254)
		(layers "F.Cu" "B.Cu")
		(net "P52V_HS2")
	)
	(via
		(at 115.503452 -25.5016)
		(size 0.508)
		(drill 0.254)
		(layers "F.Cu" "B.Cu")
		(net "P52V_HS2")
	)
	(via
		(at 113.217452 -16.51)
		(size 0.508)
		(drill 0.254)
		(layers "F.Cu" "B.Cu")
		(net "P52V_HS2")
	)
	(via
		(at 114.741452 -14.224)
		(size 0.508)
		(drill 0.254)
		(layers "F.Cu" "B.Cu")
		(net "P52V_HS2")
	)
	(via
		(at 66.802 -35.814)
		(size 0.762)
		(drill 0.381)
		(layers "F.Cu" "B.Cu")
		(net "P52V_HS2")
	)
	(via
		(at 113.979452 -72.898)
		(size 0.508)
		(drill 0.254)
		(layers "F.Cu" "B.Cu")
		(net "P52V_HS2")
	)
	(via
		(at 113.217452 -73.66)
		(size 0.508)
		(drill 0.254)
		(layers "F.Cu" "B.Cu")
		(net "P52V_HS2")
	)
	(via
		(at 114.741452 -48.8188)
		(size 0.508)
		(drill 0.254)
		(layers "F.Cu" "B.Cu")
		(net "P52V_HS2")
	)
	(via
		(at 115.503452 -15.748)
		(size 0.508)
		(drill 0.254)
		(layers "F.Cu" "B.Cu")
		(net "P52V_HS2")
	)
	(via
		(at 150.488904 -60.88634)
		(size 0.508)
		(drill 0.254)
		(layers "F.Cu" "B.Cu")
		(net "P52V_HS2")
	)
	(via
		(at 114.741452 -59.3344)
		(size 0.508)
		(drill 0.254)
		(layers "F.Cu" "B.Cu")
		(net "P52V_HS2")
	)
	(via
		(at 115.503452 -72.136)
		(size 0.508)
		(drill 0.254)
		(layers "F.Cu" "B.Cu")
		(net "P52V_HS2")
	)
	(via
		(at 113.979452 -60.0964)
		(size 0.508)
		(drill 0.254)
		(layers "F.Cu" "B.Cu")
		(net "P52V_HS2")
	)
	(via
		(at 113.979452 -39.0652)
		(size 0.508)
		(drill 0.254)
		(layers "F.Cu" "B.Cu")
		(net "P52V_HS2")
	)
	(via
		(at 113.217452 -60.0964)
		(size 0.508)
		(drill 0.254)
		(layers "F.Cu" "B.Cu")
		(net "P52V_HS2")
	)
	(via
		(at 112.455452 -14.224)
		(size 0.508)
		(drill 0.254)
		(layers "F.Cu" "B.Cu")
		(net "P52V_HS2")
	)
	(via
		(at 112.455452 -39.0652)
		(size 0.508)
		(drill 0.254)
		(layers "F.Cu" "B.Cu")
		(net "P52V_HS2")
	)
	(via
		(at 113.979452 -14.986)
		(size 0.508)
		(drill 0.254)
		(layers "F.Cu" "B.Cu")
		(net "P52V_HS2")
	)
	(via
		(at 113.979452 -51.1048)
		(size 0.508)
		(drill 0.254)
		(layers "F.Cu" "B.Cu")
		(net "P52V_HS2")
	)
	(via
		(at 112.455452 -72.898)
		(size 0.508)
		(drill 0.254)
		(layers "F.Cu" "B.Cu")
		(net "P52V_HS2")
	)
	(via
		(at 115.503452 -14.986)
		(size 0.508)
		(drill 0.254)
		(layers "F.Cu" "B.Cu")
		(net "P52V_HS2")
	)
	(via
		(at 166.5224 -60.3758)
		(size 0.508)
		(drill 0.254)
		(layers "F.Cu" "B.Cu")
		(net "P52V_HS2")
	)
	(via
		(at 113.217452 -17.272)
		(size 0.508)
		(drill 0.254)
		(layers "F.Cu" "B.Cu")
		(net "P52V_HS2")
	)
	(via
		(at 115.503452 -71.374)
		(size 0.508)
		(drill 0.254)
		(layers "F.Cu" "B.Cu")
		(net "P52V_HS2")
	)
	(via
		(at 113.217452 -25.5016)
		(size 0.508)
		(drill 0.254)
		(layers "F.Cu" "B.Cu")
		(net "P52V_HS2")
	)
	(via
		(at 113.979452 -49.5808)
		(size 0.508)
		(drill 0.254)
		(layers "F.Cu" "B.Cu")
		(net "P52V_HS2")
	)
	(via
		(at 114.741452 -15.748)
		(size 0.508)
		(drill 0.254)
		(layers "F.Cu" "B.Cu")
		(net "P52V_HS2")
	)
	(via
		(at 115.503452 -73.66)
		(size 0.508)
		(drill 0.254)
		(layers "F.Cu" "B.Cu")
		(net "P52V_HS2")
	)
	(via
		(at 113.217452 -50.3428)
		(size 0.508)
		(drill 0.254)
		(layers "F.Cu" "B.Cu")
		(net "P52V_HS2")
	)
	(via
		(at 64.516 -35.814)
		(size 0.762)
		(drill 0.381)
		(layers "F.Cu" "B.Cu")
		(net "P52V_HS2")
	)
	(via
		(at 115.503452 -39.0652)
		(size 0.508)
		(drill 0.254)
		(layers "F.Cu" "B.Cu")
		(net "P52V_HS2")
	)
	(via
		(at 114.741452 -27.0256)
		(size 0.508)
		(drill 0.254)
		(layers "F.Cu" "B.Cu")
		(net "P52V_HS2")
	)
	(via
		(at 114.741452 -26.2636)
		(size 0.508)
		(drill 0.254)
		(layers "F.Cu" "B.Cu")
		(net "P52V_HS2")
	)
	(via
		(at 113.217452 -36.7792)
		(size 0.508)
		(drill 0.254)
		(layers "F.Cu" "B.Cu")
		(net "P52V_HS2")
	)
	(via
		(at 113.217452 -37.5412)
		(size 0.508)
		(drill 0.254)
		(layers "F.Cu" "B.Cu")
		(net "P52V_HS2")
	)
	(via
		(at 112.455452 -71.374)
		(size 0.508)
		(drill 0.254)
		(layers "F.Cu" "B.Cu")
		(net "P52V_HS2")
	)
	(via
		(at 114.741452 -70.612)
		(size 0.508)
		(drill 0.254)
		(layers "F.Cu" "B.Cu")
		(net "P52V_HS2")
	)
	(via
		(at 115.503452 -38.3032)
		(size 0.508)
		(drill 0.254)
		(layers "F.Cu" "B.Cu")
		(net "P52V_HS2")
	)
	(via
		(at 114.741452 -25.5016)
		(size 0.508)
		(drill 0.254)
		(layers "F.Cu" "B.Cu")
		(net "P52V_HS2")
	)
	(via
		(at 113.979452 -71.374)
		(size 0.508)
		(drill 0.254)
		(layers "F.Cu" "B.Cu")
		(net "P52V_HS2")
	)
	(via
		(at 114.741452 -61.6204)
		(size 0.508)
		(drill 0.254)
		(layers "F.Cu" "B.Cu")
		(net "P52V_HS2")
	)
	(via
		(at 112.455452 -27.0256)
		(size 0.508)
		(drill 0.254)
		(layers "F.Cu" "B.Cu")
		(net "P52V_HS2")
	)
	(via
		(at 112.455452 -36.7792)
		(size 0.508)
		(drill 0.254)
		(layers "F.Cu" "B.Cu")
		(net "P52V_HS2")
	)
	(via
		(at 112.455452 -26.2636)
		(size 0.508)
		(drill 0.254)
		(layers "F.Cu" "B.Cu")
		(net "P52V_HS2")
	)
	(via
		(at 115.503452 -51.1048)
		(size 0.508)
		(drill 0.254)
		(layers "F.Cu" "B.Cu")
		(net "P52V_HS2")
	)
	(via
		(at 114.741452 -60.0964)
		(size 0.508)
		(drill 0.254)
		(layers "F.Cu" "B.Cu")
		(net "P52V_HS2")
	)
	(via
		(at 112.455452 -51.1048)
		(size 0.508)
		(drill 0.254)
		(layers "F.Cu" "B.Cu")
		(net "P52V_HS2")
	)
	(via
		(at 113.979452 -72.136)
		(size 0.508)
		(drill 0.254)
		(layers "F.Cu" "B.Cu")
		(net "P52V_HS2")
	)
	(via
		(at 114.741452 -60.8584)
		(size 0.508)
		(drill 0.254)
		(layers "F.Cu" "B.Cu")
		(net "P52V_HS2")
	)
	(via
		(at 115.503452 -39.8272)
		(size 0.508)
		(drill 0.254)
		(layers "F.Cu" "B.Cu")
		(net "P52V_HS2")
	)
	(via
		(at 113.217452 -62.3824)
		(size 0.508)
		(drill 0.254)
		(layers "F.Cu" "B.Cu")
		(net "P52V_HS2")
	)
	(via
		(at 115.503452 -62.3824)
		(size 0.508)
		(drill 0.254)
		(layers "F.Cu" "B.Cu")
		(net "P52V_HS2")
	)
	(via
		(at 115.503452 -59.3344)
		(size 0.508)
		(drill 0.254)
		(layers "F.Cu" "B.Cu")
		(net "P52V_HS2")
	)
	(via
		(at 113.217452 -70.612)
		(size 0.508)
		(drill 0.254)
		(layers "F.Cu" "B.Cu")
		(net "P52V_HS2")
	)
	(via
		(at 114.741452 -50.3428)
		(size 0.508)
		(drill 0.254)
		(layers "F.Cu" "B.Cu")
		(net "P52V_HS2")
	)
	(via
		(at 112.455452 -39.8272)
		(size 0.508)
		(drill 0.254)
		(layers "F.Cu" "B.Cu")
		(net "P52V_HS2")
	)
	(via
		(at 176.251616 -82.304128)
		(size 0.508)
		(drill 0.254)
		(layers "F.Cu" "B.Cu")
		(net "P52V_HS2")
	)
	(via
		(at 115.503452 -72.898)
		(size 0.508)
		(drill 0.254)
		(layers "F.Cu" "B.Cu")
		(net "P52V_HS2")
	)
	(via
		(at 113.979452 -16.51)
		(size 0.508)
		(drill 0.254)
		(layers "F.Cu" "B.Cu")
		(net "P52V_HS2")
	)
	(via
		(at 112.455452 -61.6204)
		(size 0.508)
		(drill 0.254)
		(layers "F.Cu" "B.Cu")
		(net "P52V_HS2")
	)
	(via
		(at 114.741452 -39.8272)
		(size 0.508)
		(drill 0.254)
		(layers "F.Cu" "B.Cu")
		(net "P52V_HS2")
	)
	(via
		(at 114.741452 -48.0568)
		(size 0.508)
		(drill 0.254)
		(layers "F.Cu" "B.Cu")
		(net "P52V_HS2")
	)
	(via
		(at 114.741452 -16.51)
		(size 0.508)
		(drill 0.254)
		(layers "F.Cu" "B.Cu")
		(net "P52V_HS2")
	)
	(via
		(at 113.979452 -38.3032)
		(size 0.508)
		(drill 0.254)
		(layers "F.Cu" "B.Cu")
		(net "P52V_HS2")
	)
	(via
		(at 113.217452 -49.5808)
		(size 0.508)
		(drill 0.254)
		(layers "F.Cu" "B.Cu")
		(net "P52V_HS2")
	)
	(via
		(at 115.503452 -17.272)
		(size 0.508)
		(drill 0.254)
		(layers "F.Cu" "B.Cu")
		(net "P52V_HS2")
	)
	(via
		(at 112.455452 -72.136)
		(size 0.508)
		(drill 0.254)
		(layers "F.Cu" "B.Cu")
		(net "P52V_HS2")
	)
	(via
		(at 113.217452 -38.3032)
		(size 0.508)
		(drill 0.254)
		(layers "F.Cu" "B.Cu")
		(net "P52V_HS2")
	)
	(via
		(at 112.455452 -14.986)
		(size 0.508)
		(drill 0.254)
		(layers "F.Cu" "B.Cu")
		(net "P52V_HS2")
	)
	(via
		(at 113.217452 -48.0568)
		(size 0.508)
		(drill 0.254)
		(layers "F.Cu" "B.Cu")
		(net "P52V_HS2")
	)
	(via
		(at 113.979452 -17.272)
		(size 0.508)
		(drill 0.254)
		(layers "F.Cu" "B.Cu")
		(net "P52V_HS2")
	)
	(via
		(at 115.503452 -60.0964)
		(size 0.508)
		(drill 0.254)
		(layers "F.Cu" "B.Cu")
		(net "P52V_HS2")
	)
	(via
		(at 114.741452 -49.5808)
		(size 0.508)
		(drill 0.254)
		(layers "F.Cu" "B.Cu")
		(net "P52V_HS2")
	)
	(via
		(at 115.503452 -61.6204)
		(size 0.508)
		(drill 0.254)
		(layers "F.Cu" "B.Cu")
		(net "P52V_HS2")
	)
	(via
		(at 176.939702 -82.304128)
		(size 0.508)
		(drill 0.254)
		(layers "F.Cu" "B.Cu")
		(net "P52V_HS2")
	)
	(via
		(at 112.455452 -16.51)
		(size 0.508)
		(drill 0.254)
		(layers "F.Cu" "B.Cu")
		(net "P52V_HS2")
	)
	(via
		(at 114.741452 -36.7792)
		(size 0.508)
		(drill 0.254)
		(layers "F.Cu" "B.Cu")
		(net "P52V_HS2")
	)
	(via
		(at 113.979452 -15.748)
		(size 0.508)
		(drill 0.254)
		(layers "F.Cu" "B.Cu")
		(net "P52V_HS2")
	)
	(via
		(at 113.979452 -59.3344)
		(size 0.508)
		(drill 0.254)
		(layers "F.Cu" "B.Cu")
		(net "P52V_HS2")
	)
	(via
		(at 115.503452 -36.7792)
		(size 0.508)
		(drill 0.254)
		(layers "F.Cu" "B.Cu")
		(net "P52V_HS2")
	)
	(via
		(at 113.979452 -48.8188)
		(size 0.508)
		(drill 0.254)
		(layers "F.Cu" "B.Cu")
		(net "P52V_HS2")
	)
	(via
		(at 112.455452 -73.66)
		(size 0.508)
		(drill 0.254)
		(layers "F.Cu" "B.Cu")
		(net "P52V_HS2")
	)
	(via
		(at 112.455452 -17.272)
		(size 0.508)
		(drill 0.254)
		(layers "F.Cu" "B.Cu")
		(net "P52V_HS2")
	)
	(via
		(at 113.979452 -60.8584)
		(size 0.508)
		(drill 0.254)
		(layers "F.Cu" "B.Cu")
		(net "P52V_HS2")
	)
	(via
		(at 112.455452 -60.0964)
		(size 0.508)
		(drill 0.254)
		(layers "F.Cu" "B.Cu")
		(net "P52V_HS2")
	)
	(via
		(at 114.741452 -73.66)
		(size 0.508)
		(drill 0.254)
		(layers "F.Cu" "B.Cu")
		(net "P52V_HS2")
	)
	(via
		(at 113.979452 -62.3824)
		(size 0.508)
		(drill 0.254)
		(layers "F.Cu" "B.Cu")
		(net "P52V_HS2")
	)
	(via
		(at 113.979452 -73.66)
		(size 0.508)
		(drill 0.254)
		(layers "F.Cu" "B.Cu")
		(net "P52V_HS2")
	)
	(via
		(at 112.455452 -48.0568)
		(size 0.508)
		(drill 0.254)
		(layers "F.Cu" "B.Cu")
		(net "P52V_HS2")
	)
	(via
		(at 113.217452 -48.8188)
		(size 0.508)
		(drill 0.254)
		(layers "F.Cu" "B.Cu")
		(net "P52V_HS2")
	)
	(via
		(at 113.217452 -28.5496)
		(size 0.508)
		(drill 0.254)
		(layers "F.Cu" "B.Cu")
		(net "P52V_HS2")
	)
	(via
		(at 113.979452 -28.5496)
		(size 0.508)
		(drill 0.254)
		(layers "F.Cu" "B.Cu")
		(net "P52V_HS2")
	)
	(via
		(at 113.979452 -25.5016)
		(size 0.508)
		(drill 0.254)
		(layers "F.Cu" "B.Cu")
		(net "P52V_HS2")
	)
	(via
		(at 113.217452 -39.0652)
		(size 0.508)
		(drill 0.254)
		(layers "F.Cu" "B.Cu")
		(net "P52V_HS2")
	)
	(via
		(at 113.217452 -15.748)
		(size 0.508)
		(drill 0.254)
		(layers "F.Cu" "B.Cu")
		(net "P52V_HS2")
	)
	(via
		(at 114.741452 -38.3032)
		(size 0.508)
		(drill 0.254)
		(layers "F.Cu" "B.Cu")
		(net "P52V_HS2")
	)
	(via
		(at 115.503452 -27.0256)
		(size 0.508)
		(drill 0.254)
		(layers "F.Cu" "B.Cu")
		(net "P52V_HS2")
	)
	(via
		(at 151.200104 -60.88634)
		(size 0.508)
		(drill 0.254)
		(layers "F.Cu" "B.Cu")
		(net "P52V_HS2")
	)
	(via
		(at 112.455452 -59.3344)
		(size 0.508)
		(drill 0.254)
		(layers "F.Cu" "B.Cu")
		(net "P52V_HS2")
	)
	(via
		(at 112.455452 -70.612)
		(size 0.508)
		(drill 0.254)
		(layers "F.Cu" "B.Cu")
		(net "P52V_HS2")
	)
	(via
		(at 115.503452 -50.3428)
		(size 0.508)
		(drill 0.254)
		(layers "F.Cu" "B.Cu")
		(net "P52V_HS2")
	)
	(via
		(at 113.217452 -27.0256)
		(size 0.508)
		(drill 0.254)
		(layers "F.Cu" "B.Cu")
		(net "P52V_HS2")
	)
	(via
		(at 112.455452 -38.3032)
		(size 0.508)
		(drill 0.254)
		(layers "F.Cu" "B.Cu")
		(net "P52V_HS2")
	)
	(via
		(at 113.979452 -61.6204)
		(size 0.508)
		(drill 0.254)
		(layers "F.Cu" "B.Cu")
		(net "P52V_HS2")
	)
	(via
		(at 114.741452 -72.898)
		(size 0.508)
		(drill 0.254)
		(layers "F.Cu" "B.Cu")
		(net "P52V_HS2")
	)
	(via
		(at 114.741452 -27.7876)
		(size 0.508)
		(drill 0.254)
		(layers "F.Cu" "B.Cu")
		(net "P52V_HS2")
	)
	(via
		(at 115.503452 -26.2636)
		(size 0.508)
		(drill 0.254)
		(layers "F.Cu" "B.Cu")
		(net "P52V_HS2")
	)
	(segment
		(start 42.36339 -119.38)
		(end 43.430698 -118.312692)
		(width 0.635)
		(layer "B.Cu")
		(net "P52V_HS2")
	)
	(segment
		(start 61.92139 -139.7)
		(end 62.988698 -140.767308)
		(width 0.635)
		(layer "B.Cu")
		(net "P52V_HS2")
	)
	(segment
		(start 42.36339 -58.42)
		(end 43.430698 -57.352692)
		(width 0.635)
		(layer "B.Cu")
		(net "P52V_HS2")
	)
	(segment
		(start 61.92139 -99.06)
		(end 62.988698 -100.127308)
		(width 0.635)
		(layer "B.Cu")
		(net "P52V_HS2")
	)
	(segment
		(start 42.36339 -78.74)
		(end 43.430698 -77.672692)
		(width 0.635)
		(layer "B.Cu")
		(net "P52V_HS2")
	)
	(segment
		(start 41.296082 -120.447308)
		(end 42.36339 -119.38)
		(width 0.635)
		(layer "B.Cu")
		(net "P52V_HS2")
	)
	(segment
		(start 60.854082 -140.767308)
		(end 61.92139 -139.7)
		(width 0.635)
		(layer "B.Cu")
		(net "P52V_HS2")
	)
	(segment
		(start 60.854082 -57.352692)
		(end 61.92139 -58.42)
		(width 0.635)
		(layer "B.Cu")
		(net "P52V_HS2")
	)
	(segment
		(start 61.92139 -119.38)
		(end 62.988698 -118.312692)
		(width 0.635)
		(layer "B.Cu")
		(net "P52V_HS2")
	)
	(segment
		(start 60.854082 -118.312692)
		(end 61.92139 -119.38)
		(width 0.635)
		(layer "B.Cu")
		(net "P52V_HS2")
	)
	(segment
		(start 61.92139 -58.42)
		(end 62.988698 -59.487308)
		(width 0.635)
		(layer "B.Cu")
		(net "P52V_HS2")
	)
	(segment
		(start 41.296082 -79.807308)
		(end 42.36339 -78.74)
		(width 0.635)
		(layer "B.Cu")
		(net "P52V_HS2")
	)
	(segment
		(start 60.854082 -59.487308)
		(end 61.92139 -58.42)
		(width 0.635)
		(layer "B.Cu")
		(net "P52V_HS2")
	)
	(segment
		(start 42.36339 -99.06)
		(end 43.430698 -97.992692)
		(width 0.635)
		(layer "B.Cu")
		(net "P52V_HS2")
	)
	(segment
		(start 61.92139 -78.74)
		(end 62.988698 -77.672692)
		(width 0.635)
		(layer "B.Cu")
		(net "P52V_HS2")
	)
	(segment
		(start 42.36339 -58.42)
		(end 43.430698 -59.487308)
		(width 0.635)
		(layer "B.Cu")
		(net "P52V_HS2")
	)
	(segment
		(start 60.854082 -120.447308)
		(end 61.92139 -119.38)
		(width 0.635)
		(layer "B.Cu")
		(net "P52V_HS2")
	)
	(segment
		(start 41.296082 -140.767308)
		(end 42.36339 -139.7)
		(width 0.635)
		(layer "B.Cu")
		(net "P52V_HS2")
	)
	(segment
		(start 41.296082 -59.487308)
		(end 42.36339 -58.42)
		(width 0.635)
		(layer "B.Cu")
		(net "P52V_HS2")
	)
	(segment
		(start 42.36339 -119.38)
		(end 43.430698 -120.447308)
		(width 0.635)
		(layer "B.Cu")
		(net "P52V_HS2")
	)
	(segment
		(start 61.92139 -58.42)
		(end 62.988698 -57.352692)
		(width 0.635)
		(layer "B.Cu")
		(net "P52V_HS2")
	)
	(segment
		(start 41.296082 -97.992692)
		(end 42.36339 -99.06)
		(width 0.635)
		(layer "B.Cu")
		(net "P52V_HS2")
	)
	(segment
		(start 41.296082 -118.312692)
		(end 42.36339 -119.38)
		(width 0.635)
		(layer "B.Cu")
		(net "P52V_HS2")
	)
	(segment
		(start 61.92139 -78.74)
		(end 62.988698 -79.807308)
		(width 0.635)
		(layer "B.Cu")
		(net "P52V_HS2")
	)
	(segment
		(start 41.296082 -138.632692)
		(end 42.36339 -139.7)
		(width 0.635)
		(layer "B.Cu")
		(net "P52V_HS2")
	)
	(segment
		(start 42.36339 -139.7)
		(end 43.430698 -140.767308)
		(width 0.635)
		(layer "B.Cu")
		(net "P52V_HS2")
	)
	(segment
		(start 60.854082 -79.807308)
		(end 61.92139 -78.74)
		(width 0.635)
		(layer "B.Cu")
		(net "P52V_HS2")
	)
	(segment
		(start 60.854082 -138.632692)
		(end 61.92139 -139.7)
		(width 0.635)
		(layer "B.Cu")
		(net "P52V_HS2")
	)
	(segment
		(start 41.296082 -77.672692)
		(end 42.36339 -78.74)
		(width 0.635)
		(layer "B.Cu")
		(net "P52V_HS2")
	)
	(segment
		(start 60.854082 -77.672692)
		(end 61.92139 -78.74)
		(width 0.635)
		(layer "B.Cu")
		(net "P52V_HS2")
	)
	(segment
		(start 61.92139 -99.06)
		(end 62.988698 -97.992692)
		(width 0.635)
		(layer "B.Cu")
		(net "P52V_HS2")
	)
	(segment
		(start 60.854082 -100.127308)
		(end 61.92139 -99.06)
		(width 0.635)
		(layer "B.Cu")
		(net "P52V_HS2")
	)
	(segment
		(start 42.36339 -139.7)
		(end 43.430698 -138.632692)
		(width 0.635)
		(layer "B.Cu")
		(net "P52V_HS2")
	)
	(segment
		(start 42.36339 -99.06)
		(end 43.430698 -100.127308)
		(width 0.635)
		(layer "B.Cu")
		(net "P52V_HS2")
	)
	(segment
		(start 42.36339 -78.74)
		(end 43.430698 -79.807308)
		(width 0.635)
		(layer "B.Cu")
		(net "P52V_HS2")
	)
	(segment
		(start 41.296082 -100.127308)
		(end 42.36339 -99.06)
		(width 0.635)
		(layer "B.Cu")
		(net "P52V_HS2")
	)
	(segment
		(start 60.854082 -97.992692)
		(end 61.92139 -99.06)
		(width 0.635)
		(layer "B.Cu")
		(net "P52V_HS2")
	)
	(segment
		(start 61.92139 -139.7)
		(end 62.988698 -138.632692)
		(width 0.635)
		(layer "B.Cu")
		(net "P52V_HS2")
	)
	(segment
		(start 61.92139 -119.38)
		(end 62.988698 -120.447308)
		(width 0.635)
		(layer "B.Cu")
		(net "P52V_HS2")
	)
	(segment
		(start 41.296082 -57.352692)
		(end 42.36339 -58.42)
		(width 0.635)
		(layer "B.Cu")
		(net "P52V_HS2")
	)
	(segment
		(start 61.92139 -78.74)
		(end 62.726824 -77.934566)
		(width 0.635)
		(layer "In2.Cu")
		(net "P52V_HS2")
	)
	(segment
		(start 61.115956 -77.934566)
		(end 61.92139 -78.74)
		(width 0.635)
		(layer "In2.Cu")
		(net "P52V_HS2")
	)
	(segment
		(start 61.115956 -99.865434)
		(end 61.92139 -99.06)
		(width 0.635)
		(layer "In2.Cu")
		(net "P52V_HS2")
	)
	(segment
		(start 61.115956 -118.574566)
		(end 61.92139 -119.38)
		(width 0.635)
		(layer "In2.Cu")
		(net "P52V_HS2")
	)
	(segment
		(start 41.557956 -99.865434)
		(end 42.36339 -99.06)
		(width 0.635)
		(layer "In2.Cu")
		(net "P52V_HS2")
	)
	(segment
		(start 42.36339 -119.38)
		(end 43.168824 -118.574566)
		(width 0.635)
		(layer "In2.Cu")
		(net "P52V_HS2")
	)
	(segment
		(start 61.92139 -99.06)
		(end 62.726824 -98.254566)
		(width 0.635)
		(layer "In2.Cu")
		(net "P52V_HS2")
	)
	(segment
		(start 61.92139 -139.7)
		(end 62.726824 -138.894566)
		(width 0.635)
		(layer "In2.Cu")
		(net "P52V_HS2")
	)
	(segment
		(start 61.92139 -99.06)
		(end 62.726824 -99.865434)
		(width 0.635)
		(layer "In2.Cu")
		(net "P52V_HS2")
	)
	(segment
		(start 41.557956 -140.505434)
		(end 42.36339 -139.7)
		(width 0.635)
		(layer "In2.Cu")
		(net "P52V_HS2")
	)
	(segment
		(start 42.36339 -99.06)
		(end 43.168824 -99.865434)
		(width 0.635)
		(layer "In2.Cu")
		(net "P52V_HS2")
	)
	(segment
		(start 42.36339 -119.38)
		(end 43.168824 -120.185434)
		(width 0.635)
		(layer "In2.Cu")
		(net "P52V_HS2")
	)
	(segment
		(start 61.115956 -98.254566)
		(end 61.92139 -99.06)
		(width 0.635)
		(layer "In2.Cu")
		(net "P52V_HS2")
	)
	(segment
		(start 42.36339 -139.7)
		(end 43.168824 -138.894566)
		(width 0.635)
		(layer "In2.Cu")
		(net "P52V_HS2")
	)
	(segment
		(start 41.557956 -79.545434)
		(end 42.36339 -78.74)
		(width 0.635)
		(layer "In2.Cu")
		(net "P52V_HS2")
	)
	(segment
		(start 61.92139 -139.7)
		(end 62.726824 -140.505434)
		(width 0.635)
		(layer "In2.Cu")
		(net "P52V_HS2")
	)
	(segment
		(start 41.557956 -57.614566)
		(end 42.36339 -58.42)
		(width 0.635)
		(layer "In2.Cu")
		(net "P52V_HS2")
	)
	(segment
		(start 61.115956 -79.545434)
		(end 61.92139 -78.74)
		(width 0.635)
		(layer "In2.Cu")
		(net "P52V_HS2")
	)
	(segment
		(start 61.92139 -58.42)
		(end 62.726824 -59.225434)
		(width 0.635)
		(layer "In2.Cu")
		(net "P52V_HS2")
	)
	(segment
		(start 42.36339 -78.74)
		(end 43.168824 -77.934566)
		(width 0.635)
		(layer "In2.Cu")
		(net "P52V_HS2")
	)
	(segment
		(start 41.557956 -98.254566)
		(end 42.36339 -99.06)
		(width 0.635)
		(layer "In2.Cu")
		(net "P52V_HS2")
	)
	(segment
		(start 61.115956 -59.225434)
		(end 61.92139 -58.42)
		(width 0.635)
		(layer "In2.Cu")
		(net "P52V_HS2")
	)
	(segment
		(start 61.115956 -57.614566)
		(end 61.92139 -58.42)
		(width 0.635)
		(layer "In2.Cu")
		(net "P52V_HS2")
	)
	(segment
		(start 61.115956 -140.505434)
		(end 61.92139 -139.7)
		(width 0.635)
		(layer "In2.Cu")
		(net "P52V_HS2")
	)
	(segment
		(start 61.115956 -138.894566)
		(end 61.92139 -139.7)
		(width 0.635)
		(layer "In2.Cu")
		(net "P52V_HS2")
	)
	(segment
		(start 61.92139 -58.42)
		(end 62.726824 -57.614566)
		(width 0.635)
		(layer "In2.Cu")
		(net "P52V_HS2")
	)
	(segment
		(start 61.92139 -119.38)
		(end 62.726824 -120.185434)
		(width 0.635)
		(layer "In2.Cu")
		(net "P52V_HS2")
	)
	(segment
		(start 61.92139 -119.38)
		(end 62.726824 -118.574566)
		(width 0.635)
		(layer "In2.Cu")
		(net "P52V_HS2")
	)
	(segment
		(start 41.557956 -77.934566)
		(end 42.36339 -78.74)
		(width 0.635)
		(layer "In2.Cu")
		(net "P52V_HS2")
	)
	(segment
		(start 41.557956 -120.185434)
		(end 42.36339 -119.38)
		(width 0.635)
		(layer "In2.Cu")
		(net "P52V_HS2")
	)
	(segment
		(start 42.36339 -99.06)
		(end 43.168824 -98.254566)
		(width 0.635)
		(layer "In2.Cu")
		(net "P52V_HS2")
	)
	(segment
		(start 41.557956 -59.225434)
		(end 42.36339 -58.42)
		(width 0.635)
		(layer "In2.Cu")
		(net "P52V_HS2")
	)
	(segment
		(start 61.92139 -78.74)
		(end 62.726824 -79.545434)
		(width 0.635)
		(layer "In2.Cu")
		(net "P52V_HS2")
	)
	(segment
		(start 42.36339 -78.74)
		(end 43.168824 -79.545434)
		(width 0.635)
		(layer "In2.Cu")
		(net "P52V_HS2")
	)
	(segment
		(start 42.36339 -58.42)
		(end 43.168824 -57.614566)
		(width 0.635)
		(layer "In2.Cu")
		(net "P52V_HS2")
	)
	(segment
		(start 42.36339 -139.7)
		(end 43.168824 -140.505434)
		(width 0.635)
		(layer "In2.Cu")
		(net "P52V_HS2")
	)
	(segment
		(start 42.36339 -58.42)
		(end 43.168824 -59.225434)
		(width 0.635)
		(layer "In2.Cu")
		(net "P52V_HS2")
	)
	(segment
		(start 61.115956 -120.185434)
		(end 61.92139 -119.38)
		(width 0.635)
		(layer "In2.Cu")
		(net "P52V_HS2")
	)
	(segment
		(start 41.557956 -118.574566)
		(end 42.36339 -119.38)
		(width 0.635)
		(layer "In2.Cu")
		(net "P52V_HS2")
	)
	(segment
		(start 41.557956 -138.894566)
		(end 42.36339 -139.7)
		(width 0.635)
		(layer "In2.Cu")
		(net "P52V_HS2")
	)
	(segment
		(start 41.557956 -77.934566)
		(end 42.36339 -78.74)
		(width 0.508)
		(layer "In4.Cu")
		(net "P52V_HS2")
	)
	(segment
		(start 61.92139 -78.74)
		(end 62.726824 -79.545434)
		(width 0.508)
		(layer "In4.Cu")
		(net "P52V_HS2")
	)
	(segment
		(start 61.115956 -138.894566)
		(end 61.92139 -139.7)
		(width 0.508)
		(layer "In4.Cu")
		(net "P52V_HS2")
	)
	(segment
		(start 41.557956 -138.894566)
		(end 42.36339 -139.7)
		(width 0.508)
		(layer "In4.Cu")
		(net "P52V_HS2")
	)
	(segment
		(start 42.36339 -58.42)
		(end 43.168824 -59.225434)
		(width 0.508)
		(layer "In4.Cu")
		(net "P52V_HS2")
	)
	(segment
		(start 61.115956 -79.545434)
		(end 61.92139 -78.74)
		(width 0.508)
		(layer "In4.Cu")
		(net "P52V_HS2")
	)
	(segment
		(start 42.36339 -99.06)
		(end 43.168824 -99.865434)
		(width 0.508)
		(layer "In4.Cu")
		(net "P52V_HS2")
	)
	(segment
		(start 42.36339 -139.7)
		(end 43.168824 -140.505434)
		(width 0.508)
		(layer "In4.Cu")
		(net "P52V_HS2")
	)
	(segment
		(start 42.36339 -119.38)
		(end 43.168824 -120.185434)
		(width 0.508)
		(layer "In4.Cu")
		(net "P52V_HS2")
	)
	(segment
		(start 61.115956 -140.505434)
		(end 61.92139 -139.7)
		(width 0.508)
		(layer "In4.Cu")
		(net "P52V_HS2")
	)
	(segment
		(start 61.92139 -58.42)
		(end 62.726824 -57.614566)
		(width 0.508)
		(layer "In4.Cu")
		(net "P52V_HS2")
	)
	(segment
		(start 61.92139 -58.42)
		(end 62.726824 -59.225434)
		(width 0.508)
		(layer "In4.Cu")
		(net "P52V_HS2")
	)
	(segment
		(start 41.557956 -59.225434)
		(end 42.36339 -58.42)
		(width 0.508)
		(layer "In4.Cu")
		(net "P52V_HS2")
	)
	(segment
		(start 61.92139 -119.38)
		(end 62.726824 -118.574566)
		(width 0.508)
		(layer "In4.Cu")
		(net "P52V_HS2")
	)
	(segment
		(start 61.115956 -98.254566)
		(end 61.92139 -99.06)
		(width 0.508)
		(layer "In4.Cu")
		(net "P52V_HS2")
	)
	(segment
		(start 61.92139 -139.7)
		(end 62.726824 -140.505434)
		(width 0.508)
		(layer "In4.Cu")
		(net "P52V_HS2")
	)
	(segment
		(start 41.557956 -120.185434)
		(end 42.36339 -119.38)
		(width 0.508)
		(layer "In4.Cu")
		(net "P52V_HS2")
	)
	(segment
		(start 42.36339 -78.74)
		(end 43.168824 -77.934566)
		(width 0.508)
		(layer "In4.Cu")
		(net "P52V_HS2")
	)
	(segment
		(start 61.92139 -99.06)
		(end 62.726824 -99.865434)
		(width 0.508)
		(layer "In4.Cu")
		(net "P52V_HS2")
	)
	(segment
		(start 61.115956 -99.865434)
		(end 61.92139 -99.06)
		(width 0.508)
		(layer "In4.Cu")
		(net "P52V_HS2")
	)
	(segment
		(start 61.115956 -57.614566)
		(end 61.92139 -58.42)
		(width 0.508)
		(layer "In4.Cu")
		(net "P52V_HS2")
	)
	(segment
		(start 61.115956 -77.934566)
		(end 61.92139 -78.74)
		(width 0.508)
		(layer "In4.Cu")
		(net "P52V_HS2")
	)
	(segment
		(start 41.557956 -57.614566)
		(end 42.36339 -58.42)
		(width 0.508)
		(layer "In4.Cu")
		(net "P52V_HS2")
	)
	(segment
		(start 61.92139 -99.06)
		(end 62.726824 -98.254566)
		(width 0.508)
		(layer "In4.Cu")
		(net "P52V_HS2")
	)
	(segment
		(start 42.36339 -119.38)
		(end 43.168824 -118.574566)
		(width 0.508)
		(layer "In4.Cu")
		(net "P52V_HS2")
	)
	(segment
		(start 41.557956 -140.505434)
		(end 42.36339 -139.7)
		(width 0.508)
		(layer "In4.Cu")
		(net "P52V_HS2")
	)
	(segment
		(start 61.115956 -120.185434)
		(end 61.92139 -119.38)
		(width 0.508)
		(layer "In4.Cu")
		(net "P52V_HS2")
	)
	(segment
		(start 61.92139 -119.38)
		(end 62.726824 -120.185434)
		(width 0.508)
		(layer "In4.Cu")
		(net "P52V_HS2")
	)
	(segment
		(start 41.557956 -98.254566)
		(end 42.36339 -99.06)
		(width 0.508)
		(layer "In4.Cu")
		(net "P52V_HS2")
	)
	(segment
		(start 42.36339 -99.06)
		(end 43.168824 -98.254566)
		(width 0.508)
		(layer "In4.Cu")
		(net "P52V_HS2")
	)
	(segment
		(start 42.36339 -139.7)
		(end 43.168824 -138.894566)
		(width 0.508)
		(layer "In4.Cu")
		(net "P52V_HS2")
	)
	(segment
		(start 42.36339 -58.42)
		(end 43.168824 -57.614566)
		(width 0.508)
		(layer "In4.Cu")
		(net "P52V_HS2")
	)
	(segment
		(start 61.115956 -59.225434)
		(end 61.92139 -58.42)
		(width 0.508)
		(layer "In4.Cu")
		(net "P52V_HS2")
	)
	(segment
		(start 41.557956 -79.545434)
		(end 42.36339 -78.74)
		(width 0.508)
		(layer "In4.Cu")
		(net "P52V_HS2")
	)
	(segment
		(start 41.557956 -118.574566)
		(end 42.36339 -119.38)
		(width 0.508)
		(layer "In4.Cu")
		(net "P52V_HS2")
	)
	(segment
		(start 42.36339 -78.74)
		(end 43.168824 -79.545434)
		(width 0.508)
		(layer "In4.Cu")
		(net "P52V_HS2")
	)
	(segment
		(start 61.92139 -139.7)
		(end 62.726824 -138.894566)
		(width 0.508)
		(layer "In4.Cu")
		(net "P52V_HS2")
	)
	(segment
		(start 61.115956 -118.574566)
		(end 61.92139 -119.38)
		(width 0.508)
		(layer "In4.Cu")
		(net "P52V_HS2")
	)
	(segment
		(start 61.92139 -78.74)
		(end 62.726824 -77.934566)
		(width 0.508)
		(layer "In4.Cu")
		(net "P52V_HS2")
	)
	(segment
		(start 41.557956 -99.865434)
		(end 42.36339 -99.06)
		(width 0.508)
		(layer "In4.Cu")
		(net "P52V_HS2")
	)
	(segment
		(start 61.115956 -118.574566)
		(end 61.92139 -119.38)
		(width 0.508)
		(layer "In5.Cu")
		(net "P52V_HS2")
	)
	(segment
		(start 61.92139 -139.7)
		(end 62.726824 -138.894566)
		(width 0.508)
		(layer "In5.Cu")
		(net "P52V_HS2")
	)
	(segment
		(start 41.557956 -120.185434)
		(end 42.36339 -119.38)
		(width 0.508)
		(layer "In5.Cu")
		(net "P52V_HS2")
	)
	(segment
		(start 61.92139 -99.06)
		(end 62.726824 -98.254566)
		(width 0.508)
		(layer "In5.Cu")
		(net "P52V_HS2")
	)
	(segment
		(start 61.92139 -119.38)
		(end 62.726824 -118.574566)
		(width 0.508)
		(layer "In5.Cu")
		(net "P52V_HS2")
	)
	(segment
		(start 61.115956 -59.225434)
		(end 61.92139 -58.42)
		(width 0.508)
		(layer "In5.Cu")
		(net "P52V_HS2")
	)
	(segment
		(start 41.557956 -57.614566)
		(end 42.36339 -58.42)
		(width 0.508)
		(layer "In5.Cu")
		(net "P52V_HS2")
	)
	(segment
		(start 41.557956 -138.894566)
		(end 42.36339 -139.7)
		(width 0.508)
		(layer "In5.Cu")
		(net "P52V_HS2")
	)
	(segment
		(start 41.557956 -77.934566)
		(end 42.36339 -78.74)
		(width 0.508)
		(layer "In5.Cu")
		(net "P52V_HS2")
	)
	(segment
		(start 42.36339 -99.06)
		(end 43.168824 -99.865434)
		(width 0.508)
		(layer "In5.Cu")
		(net "P52V_HS2")
	)
	(segment
		(start 42.36339 -119.38)
		(end 43.168824 -118.574566)
		(width 0.508)
		(layer "In5.Cu")
		(net "P52V_HS2")
	)
	(segment
		(start 61.115956 -57.614566)
		(end 61.92139 -58.42)
		(width 0.508)
		(layer "In5.Cu")
		(net "P52V_HS2")
	)
	(segment
		(start 41.557956 -79.545434)
		(end 42.36339 -78.74)
		(width 0.508)
		(layer "In5.Cu")
		(net "P52V_HS2")
	)
	(segment
		(start 42.36339 -78.74)
		(end 43.168824 -79.545434)
		(width 0.508)
		(layer "In5.Cu")
		(net "P52V_HS2")
	)
	(segment
		(start 61.92139 -99.06)
		(end 62.726824 -99.865434)
		(width 0.508)
		(layer "In5.Cu")
		(net "P52V_HS2")
	)
	(segment
		(start 61.92139 -58.42)
		(end 62.726824 -59.225434)
		(width 0.508)
		(layer "In5.Cu")
		(net "P52V_HS2")
	)
	(segment
		(start 42.36339 -58.42)
		(end 43.168824 -59.225434)
		(width 0.508)
		(layer "In5.Cu")
		(net "P52V_HS2")
	)
	(segment
		(start 42.36339 -119.38)
		(end 43.168824 -120.185434)
		(width 0.508)
		(layer "In5.Cu")
		(net "P52V_HS2")
	)
	(segment
		(start 41.557956 -99.865434)
		(end 42.36339 -99.06)
		(width 0.508)
		(layer "In5.Cu")
		(net "P52V_HS2")
	)
	(segment
		(start 61.115956 -98.254566)
		(end 61.92139 -99.06)
		(width 0.508)
		(layer "In5.Cu")
		(net "P52V_HS2")
	)
	(segment
		(start 61.115956 -79.545434)
		(end 61.92139 -78.74)
		(width 0.508)
		(layer "In5.Cu")
		(net "P52V_HS2")
	)
	(segment
		(start 42.36339 -99.06)
		(end 43.168824 -98.254566)
		(width 0.508)
		(layer "In5.Cu")
		(net "P52V_HS2")
	)
	(segment
		(start 61.115956 -99.865434)
		(end 61.92139 -99.06)
		(width 0.508)
		(layer "In5.Cu")
		(net "P52V_HS2")
	)
	(segment
		(start 41.557956 -98.254566)
		(end 42.36339 -99.06)
		(width 0.508)
		(layer "In5.Cu")
		(net "P52V_HS2")
	)
	(segment
		(start 61.92139 -139.7)
		(end 62.726824 -140.505434)
		(width 0.508)
		(layer "In5.Cu")
		(net "P52V_HS2")
	)
	(segment
		(start 61.92139 -58.42)
		(end 62.726824 -57.614566)
		(width 0.508)
		(layer "In5.Cu")
		(net "P52V_HS2")
	)
	(segment
		(start 42.36339 -139.7)
		(end 43.168824 -138.894566)
		(width 0.508)
		(layer "In5.Cu")
		(net "P52V_HS2")
	)
	(segment
		(start 61.115956 -77.934566)
		(end 61.92139 -78.74)
		(width 0.508)
		(layer "In5.Cu")
		(net "P52V_HS2")
	)
	(segment
		(start 61.115956 -140.505434)
		(end 61.92139 -139.7)
		(width 0.508)
		(layer "In5.Cu")
		(net "P52V_HS2")
	)
	(segment
		(start 61.92139 -119.38)
		(end 62.726824 -120.185434)
		(width 0.508)
		(layer "In5.Cu")
		(net "P52V_HS2")
	)
	(segment
		(start 41.557956 -118.574566)
		(end 42.36339 -119.38)
		(width 0.508)
		(layer "In5.Cu")
		(net "P52V_HS2")
	)
	(segment
		(start 61.115956 -138.894566)
		(end 61.92139 -139.7)
		(width 0.508)
		(layer "In5.Cu")
		(net "P52V_HS2")
	)
	(segment
		(start 61.92139 -78.74)
		(end 62.726824 -77.934566)
		(width 0.508)
		(layer "In5.Cu")
		(net "P52V_HS2")
	)
	(segment
		(start 42.36339 -58.42)
		(end 43.168824 -57.614566)
		(width 0.508)
		(layer "In5.Cu")
		(net "P52V_HS2")
	)
	(segment
		(start 61.92139 -78.74)
		(end 62.726824 -79.545434)
		(width 0.508)
		(layer "In5.Cu")
		(net "P52V_HS2")
	)
	(segment
		(start 41.557956 -140.505434)
		(end 42.36339 -139.7)
		(width 0.508)
		(layer "In5.Cu")
		(net "P52V_HS2")
	)
	(segment
		(start 41.557956 -59.225434)
		(end 42.36339 -58.42)
		(width 0.508)
		(layer "In5.Cu")
		(net "P52V_HS2")
	)
	(segment
		(start 42.36339 -78.74)
		(end 43.168824 -77.934566)
		(width 0.508)
		(layer "In5.Cu")
		(net "P52V_HS2")
	)
	(segment
		(start 61.115956 -120.185434)
		(end 61.92139 -119.38)
		(width 0.508)
		(layer "In5.Cu")
		(net "P52V_HS2")
	)
	(segment
		(start 42.36339 -139.7)
		(end 43.168824 -140.505434)
		(width 0.508)
		(layer "In5.Cu")
		(net "P52V_HS2")
	)
	(segment
		(start 42.36339 -119.38)
		(end 43.168824 -120.185434)
		(width 0.635)
		(layer "In7.Cu")
		(net "P52V_HS2")
	)
	(segment
		(start 42.36339 -99.06)
		(end 43.168824 -99.865434)
		(width 0.635)
		(layer "In7.Cu")
		(net "P52V_HS2")
	)
	(segment
		(start 42.36339 -99.06)
		(end 43.168824 -98.254566)
		(width 0.635)
		(layer "In7.Cu")
		(net "P52V_HS2")
	)
	(segment
		(start 41.557956 -138.894566)
		(end 42.36339 -139.7)
		(width 0.635)
		(layer "In7.Cu")
		(net "P52V_HS2")
	)
	(segment
		(start 61.115956 -118.574566)
		(end 61.92139 -119.38)
		(width 0.635)
		(layer "In7.Cu")
		(net "P52V_HS2")
	)
	(segment
		(start 42.36339 -139.7)
		(end 43.168824 -138.894566)
		(width 0.635)
		(layer "In7.Cu")
		(net "P52V_HS2")
	)
	(segment
		(start 61.115956 -99.865434)
		(end 61.92139 -99.06)
		(width 0.635)
		(layer "In7.Cu")
		(net "P52V_HS2")
	)
	(segment
		(start 41.557956 -118.574566)
		(end 42.36339 -119.38)
		(width 0.635)
		(layer "In7.Cu")
		(net "P52V_HS2")
	)
	(segment
		(start 61.92139 -139.7)
		(end 62.726824 -140.505434)
		(width 0.635)
		(layer "In7.Cu")
		(net "P52V_HS2")
	)
	(segment
		(start 61.115956 -120.185434)
		(end 61.92139 -119.38)
		(width 0.635)
		(layer "In7.Cu")
		(net "P52V_HS2")
	)
	(segment
		(start 41.557956 -79.545434)
		(end 42.36339 -78.74)
		(width 0.635)
		(layer "In7.Cu")
		(net "P52V_HS2")
	)
	(segment
		(start 42.36339 -58.42)
		(end 43.168824 -57.614566)
		(width 0.635)
		(layer "In7.Cu")
		(net "P52V_HS2")
	)
	(segment
		(start 61.115956 -59.225434)
		(end 61.92139 -58.42)
		(width 0.635)
		(layer "In7.Cu")
		(net "P52V_HS2")
	)
	(segment
		(start 61.92139 -119.38)
		(end 62.726824 -118.574566)
		(width 0.635)
		(layer "In7.Cu")
		(net "P52V_HS2")
	)
	(segment
		(start 42.36339 -119.38)
		(end 43.168824 -118.574566)
		(width 0.635)
		(layer "In7.Cu")
		(net "P52V_HS2")
	)
	(segment
		(start 61.92139 -78.74)
		(end 62.726824 -79.545434)
		(width 0.635)
		(layer "In7.Cu")
		(net "P52V_HS2")
	)
	(segment
		(start 41.557956 -77.934566)
		(end 42.36339 -78.74)
		(width 0.635)
		(layer "In7.Cu")
		(net "P52V_HS2")
	)
	(segment
		(start 61.115956 -138.894566)
		(end 61.92139 -139.7)
		(width 0.635)
		(layer "In7.Cu")
		(net "P52V_HS2")
	)
	(segment
		(start 41.557956 -59.225434)
		(end 42.36339 -58.42)
		(width 0.635)
		(layer "In7.Cu")
		(net "P52V_HS2")
	)
	(segment
		(start 61.92139 -139.7)
		(end 62.726824 -138.894566)
		(width 0.635)
		(layer "In7.Cu")
		(net "P52V_HS2")
	)
	(segment
		(start 42.36339 -58.42)
		(end 43.168824 -59.225434)
		(width 0.635)
		(layer "In7.Cu")
		(net "P52V_HS2")
	)
	(segment
		(start 41.557956 -99.865434)
		(end 42.36339 -99.06)
		(width 0.635)
		(layer "In7.Cu")
		(net "P52V_HS2")
	)
	(segment
		(start 42.36339 -139.7)
		(end 43.168824 -140.505434)
		(width 0.635)
		(layer "In7.Cu")
		(net "P52V_HS2")
	)
	(segment
		(start 61.115956 -77.934566)
		(end 61.92139 -78.74)
		(width 0.635)
		(layer "In7.Cu")
		(net "P52V_HS2")
	)
	(segment
		(start 61.92139 -119.38)
		(end 62.726824 -120.185434)
		(width 0.635)
		(layer "In7.Cu")
		(net "P52V_HS2")
	)
	(segment
		(start 61.92139 -99.06)
		(end 62.726824 -98.254566)
		(width 0.635)
		(layer "In7.Cu")
		(net "P52V_HS2")
	)
	(segment
		(start 41.557956 -57.614566)
		(end 42.36339 -58.42)
		(width 0.635)
		(layer "In7.Cu")
		(net "P52V_HS2")
	)
	(segment
		(start 61.92139 -99.06)
		(end 62.726824 -99.865434)
		(width 0.635)
		(layer "In7.Cu")
		(net "P52V_HS2")
	)
	(segment
		(start 41.557956 -120.185434)
		(end 42.36339 -119.38)
		(width 0.635)
		(layer "In7.Cu")
		(net "P52V_HS2")
	)
	(segment
		(start 41.557956 -98.254566)
		(end 42.36339 -99.06)
		(width 0.635)
		(layer "In7.Cu")
		(net "P52V_HS2")
	)
	(segment
		(start 61.115956 -57.614566)
		(end 61.92139 -58.42)
		(width 0.635)
		(layer "In7.Cu")
		(net "P52V_HS2")
	)
	(segment
		(start 61.115956 -140.505434)
		(end 61.92139 -139.7)
		(width 0.635)
		(layer "In7.Cu")
		(net "P52V_HS2")
	)
	(segment
		(start 61.92139 -78.74)
		(end 62.726824 -77.934566)
		(width 0.635)
		(layer "In7.Cu")
		(net "P52V_HS2")
	)
	(segment
		(start 42.36339 -78.74)
		(end 43.168824 -79.545434)
		(width 0.635)
		(layer "In7.Cu")
		(net "P52V_HS2")
	)
	(segment
		(start 61.115956 -79.545434)
		(end 61.92139 -78.74)
		(width 0.635)
		(layer "In7.Cu")
		(net "P52V_HS2")
	)
	(segment
		(start 61.115956 -98.254566)
		(end 61.92139 -99.06)
		(width 0.635)
		(layer "In7.Cu")
		(net "P52V_HS2")
	)
	(segment
		(start 42.36339 -78.74)
		(end 43.168824 -77.934566)
		(width 0.635)
		(layer "In7.Cu")
		(net "P52V_HS2")
	)
	(segment
		(start 61.92139 -58.42)
		(end 62.726824 -59.225434)
		(width 0.635)
		(layer "In7.Cu")
		(net "P52V_HS2")
	)
	(segment
		(start 41.557956 -140.505434)
		(end 42.36339 -139.7)
		(width 0.635)
		(layer "In7.Cu")
		(net "P52V_HS2")
	)
	(segment
		(start 61.92139 -58.42)
		(end 62.726824 -57.614566)
		(width 0.635)
		(layer "In7.Cu")
		(net "P52V_HS2")
	)
	(segment
		(start 438.429146 -38.862)
		(end 437.15305 -38.862)
		(width 0.17272)
		(layer "F.Cu")
		(net "MB_P52V_I2C_EN")
	)
	(segment
		(start 440.362594 -38.440106)
		(end 438.85104 -38.440106)
		(width 0.17272)
		(layer "F.Cu")
		(net "MB_P52V_I2C_EN")
	)
	(segment
		(start 438.85104 -38.440106)
		(end 438.429146 -38.862)
		(width 0.17272)
		(layer "F.Cu")
		(net "MB_P52V_I2C_EN")
	)
	(via
		(at 438.429146 -38.862)
		(size 0.508)
		(drill 0.254)
		(layers "F.Cu" "B.Cu")
		(net "MB_P52V_I2C_EN")
	)
	(segment
		(start 449.199 -37.61105)
		(end 448.056 -37.61105)
		(width 0.17272)
		(layer "F.Cu")
		(net "SMB_P52V_PDB_SDA_R")
	)
	(segment
		(start 447.58864 -37.61105)
		(end 447.40957 -37.79012)
		(width 0.17272)
		(layer "F.Cu")
		(net "SMB_P52V_PDB_SDA_R")
	)
	(segment
		(start 448.056 -37.61105)
		(end 447.58864 -37.61105)
		(width 0.17272)
		(layer "F.Cu")
		(net "SMB_P52V_PDB_SDA_R")
	)
	(segment
		(start 446.6844 -37.79012)
		(end 444.827406 -37.79012)
		(width 0.17272)
		(layer "F.Cu")
		(net "SMB_P52V_PDB_SDA_R")
	)
	(segment
		(start 450.342 -37.61105)
		(end 449.199 -37.61105)
		(width 0.17272)
		(layer "F.Cu")
		(net "SMB_P52V_PDB_SDA_R")
	)
	(segment
		(start 447.40957 -37.79012)
		(end 446.6844 -37.79012)
		(width 0.17272)
		(layer "F.Cu")
		(net "SMB_P52V_PDB_SDA_R")
	)
	(via
		(at 446.6844 -37.79012)
		(size 0.762)
		(drill 0.381)
		(layers "F.Cu" "B.Cu")
		(net "SMB_P52V_PDB_SDA_R")
	)
	(segment
		(start 438.4294 -37.79012)
		(end 440.362594 -37.79012)
		(width 0.17272)
		(layer "F.Cu")
		(net "SMB_P52V_PDB_SCL_R")
	)
	(segment
		(start 436.1434 -37.61105)
		(end 437.134 -37.61105)
		(width 0.17272)
		(layer "F.Cu")
		(net "SMB_P52V_PDB_SCL_R")
	)
	(segment
		(start 434.7464 -37.61105)
		(end 436.1434 -37.61105)
		(width 0.17272)
		(layer "F.Cu")
		(net "SMB_P52V_PDB_SCL_R")
	)
	(segment
		(start 437.967374 -37.79012)
		(end 438.4294 -37.79012)
		(width 0.17272)
		(layer "F.Cu")
		(net "SMB_P52V_PDB_SCL_R")
	)
	(segment
		(start 437.134 -37.61105)
		(end 437.788304 -37.61105)
		(width 0.17272)
		(layer "F.Cu")
		(net "SMB_P52V_PDB_SCL_R")
	)
	(segment
		(start 437.788304 -37.61105)
		(end 437.967374 -37.79012)
		(width 0.17272)
		(layer "F.Cu")
		(net "SMB_P52V_PDB_SCL_R")
	)
	(via
		(at 438.4294 -37.79012)
		(size 0.762)
		(drill 0.381)
		(layers "F.Cu" "B.Cu")
		(net "SMB_P52V_PDB_SCL_R")
	)
	(segment
		(start 283.8704 -86.1314)
		(end 283.8704 -80.46339)
		(width 0.17272)
		(layer "F.Cu")
		(net "SMB_P52V_PDB_SCL")
	)
	(segment
		(start 289.179 -88.265)
		(end 286.004 -88.265)
		(width 0.17272)
		(layer "F.Cu")
		(net "SMB_P52V_PDB_SCL")
	)
	(segment
		(start 284.8864 -70.97141)
		(end 284.8864 -71.882)
		(width 0.17272)
		(layer "F.Cu")
		(net "SMB_P52V_PDB_SCL")
	)
	(segment
		(start 284.226 -72.5424)
		(end 284.8864 -71.882)
		(width 0.17272)
		(layer "F.Cu")
		(net "SMB_P52V_PDB_SCL")
	)
	(segment
		(start 285.473648 -78.860142)
		(end 285.473648 -74.83602)
		(width 0.17272)
		(layer "F.Cu")
		(net "SMB_P52V_PDB_SCL")
	)
	(segment
		(start 434.7464 -36.81095)
		(end 435.3814 -36.81095)
		(width 0.17272)
		(layer "F.Cu")
		(net "SMB_P52V_PDB_SCL")
	)
	(segment
		(start 286.004 -88.265)
		(end 283.8704 -86.1314)
		(width 0.17272)
		(layer "F.Cu")
		(net "SMB_P52V_PDB_SCL")
	)
	(segment
		(start 279.781 -68.961)
		(end 282.87599 -68.961)
		(width 0.17272)
		(layer "F.Cu")
		(net "SMB_P52V_PDB_SCL")
	)
	(segment
		(start 284.226 -73.588372)
		(end 284.226 -72.5424)
		(width 0.17272)
		(layer "F.Cu")
		(net "SMB_P52V_PDB_SCL")
	)
	(segment
		(start 282.87599 -68.961)
		(end 284.8864 -70.97141)
		(width 0.17272)
		(layer "F.Cu")
		(net "SMB_P52V_PDB_SCL")
	)
	(segment
		(start 162.733736 -68.326)
		(end 165.654736 -71.247)
		(width 0.17272)
		(layer "F.Cu")
		(net "SMB_P52V_PDB_SCL")
	)
	(segment
		(start 165.654736 -71.247)
		(end 168.194736 -71.247)
		(width 0.17272)
		(layer "F.Cu")
		(net "SMB_P52V_PDB_SCL")
	)
	(segment
		(start 283.8704 -80.46339)
		(end 285.473648 -78.860142)
		(width 0.17272)
		(layer "F.Cu")
		(net "SMB_P52V_PDB_SCL")
	)
	(segment
		(start 285.473648 -74.83602)
		(end 284.226 -73.588372)
		(width 0.17272)
		(layer "F.Cu")
		(net "SMB_P52V_PDB_SCL")
	)
	(segment
		(start 223.05645 -91.948)
		(end 223.05645 -92.636086)
		(width 0.17272)
		(layer "F.Cu")
		(net "SMB_P52V_PDB_SCL")
	)
	(via
		(at 284.8864 -71.882)
		(size 0.508)
		(drill 0.254)
		(layers "F.Cu" "B.Cu")
		(net "SMB_P52V_PDB_SCL")
	)
	(via
		(at 435.3814 -36.81095)
		(size 0.508)
		(drill 0.254)
		(layers "F.Cu" "B.Cu")
		(net "SMB_P52V_PDB_SCL")
	)
	(via
		(at 168.194736 -71.247)
		(size 0.508)
		(drill 0.254)
		(layers "F.Cu" "B.Cu")
		(net "SMB_P52V_PDB_SCL")
	)
	(via
		(at 223.05645 -92.636086)
		(size 0.508)
		(drill 0.254)
		(layers "F.Cu" "B.Cu")
		(net "SMB_P52V_PDB_SCL")
	)
	(via
		(at 289.179 -88.265)
		(size 0.508)
		(drill 0.254)
		(layers "F.Cu" "B.Cu")
		(net "SMB_P52V_PDB_SCL")
	)
	(via
		(at 162.733736 -68.326)
		(size 0.508)
		(drill 0.254)
		(layers "F.Cu" "B.Cu")
		(net "SMB_P52V_PDB_SCL")
	)
	(via
		(at 279.781 -68.961)
		(size 0.508)
		(drill 0.254)
		(layers "F.Cu" "B.Cu")
		(net "SMB_P52V_PDB_SCL")
	)
	(segment
		(start 168.810686 -71.247)
		(end 168.194736 -71.247)
		(width 0.17272)
		(layer "B.Cu")
		(net "SMB_P52V_PDB_SCL")
	)
	(segment
		(start 279.781 -69.596)
		(end 279.509474 -69.867526)
		(width 0.17272)
		(layer "B.Cu")
		(net "SMB_P52V_PDB_SCL")
	)
	(segment
		(start 279.781 -68.961)
		(end 279.781 -69.596)
		(width 0.17272)
		(layer "B.Cu")
		(net "SMB_P52V_PDB_SCL")
	)
	(segment
		(start 278.80945 -69.64045)
		(end 278.80945 -68.961)
		(width 0.17272)
		(layer "B.Cu")
		(net "SMB_P52V_PDB_SCL")
	)
	(segment
		(start 279.036526 -69.867526)
		(end 278.80945 -69.64045)
		(width 0.17272)
		(layer "B.Cu")
		(net "SMB_P52V_PDB_SCL")
	)
	(segment
		(start 162.117786 -68.326)
		(end 162.733736 -68.326)
		(width 0.17272)
		(layer "B.Cu")
		(net "SMB_P52V_PDB_SCL")
	)
	(segment
		(start 279.509474 -69.867526)
		(end 279.036526 -69.867526)
		(width 0.17272)
		(layer "B.Cu")
		(net "SMB_P52V_PDB_SCL")
	)
	(segment
		(start 285.50235 -71.882)
		(end 284.8864 -71.882)
		(width 0.17272)
		(layer "B.Cu")
		(net "SMB_P52V_PDB_SCL")
	)
	(segment
		(start 234.688634 -88.011)
		(end 234.494578 -88.205056)
		(width 0.12954)
		(layer "In2.Cu")
		(net "SMB_P52V_PDB_SCL")
	)
	(segment
		(start 419.118542 -39.810944)
		(end 419.312598 -40.005)
		(width 0.12954)
		(layer "In2.Cu")
		(net "SMB_P52V_PDB_SCL")
	)
	(segment
		(start 233.168698 -88.205056)
		(end 233.168698 -88.451944)
		(width 0.12954)
		(layer "In2.Cu")
		(net "SMB_P52V_PDB_SCL")
	)
	(segment
		(start 289.179 -88.265)
		(end 289.76574 -87.67826)
		(width 0.12954)
		(layer "In2.Cu")
		(net "SMB_P52V_PDB_SCL")
	)
	(segment
		(start 293.183818 -87.63)
		(end 328.4093 -87.63)
		(width 0.12954)
		(layer "In2.Cu")
		(net "SMB_P52V_PDB_SCL")
	)
	(segment
		(start 421.107362 -39.810944)
		(end 421.107362 -38.802056)
		(width 0.12954)
		(layer "In2.Cu")
		(net "SMB_P52V_PDB_SCL")
	)
	(segment
		(start 233.362754 -88.011)
		(end 233.168698 -88.205056)
		(width 0.12954)
		(layer "In2.Cu")
		(net "SMB_P52V_PDB_SCL")
	)
	(segment
		(start 234.025694 -88.646)
		(end 233.831638 -88.451944)
		(width 0.12954)
		(layer "In2.Cu")
		(net "SMB_P52V_PDB_SCL")
	)
	(segment
		(start 328.4093 -87.63)
		(end 336.742532 -79.296768)
		(width 0.12954)
		(layer "In2.Cu")
		(net "SMB_P52V_PDB_SCL")
	)
	(segment
		(start 231.842818 -88.451944)
		(end 231.648762 -88.646)
		(width 0.12954)
		(layer "In2.Cu")
		(net "SMB_P52V_PDB_SCL")
	)
	(segment
		(start 237.615222 -88.011)
		(end 237.340394 -88.011)
		(width 0.12954)
		(layer "In2.Cu")
		(net "SMB_P52V_PDB_SCL")
	)
	(segment
		(start 423.759122 -39.810944)
		(end 423.759122 -37.699696)
		(width 0.12954)
		(layer "In2.Cu")
		(net "SMB_P52V_PDB_SCL")
	)
	(segment
		(start 425.185078 -36.27374)
		(end 430.921922 -36.27374)
		(width 0.12954)
		(layer "In2.Cu")
		(net "SMB_P52V_PDB_SCL")
	)
	(segment
		(start 430.921922 -36.27374)
		(end 432.064922 -37.41674)
		(width 0.12954)
		(layer "In2.Cu")
		(net "SMB_P52V_PDB_SCL")
	)
	(segment
		(start 169.025824 -71.247)
		(end 174.98568 -77.206856)
		(width 0.12954)
		(layer "In2.Cu")
		(net "SMB_P52V_PDB_SCL")
	)
	(segment
		(start 237.809278 -88.451944)
		(end 237.809278 -88.205056)
		(width 0.12954)
		(layer "In2.Cu")
		(net "SMB_P52V_PDB_SCL")
	)
	(segment
		(start 399.19275 -61.289184)
		(end 410.226002 -50.255932)
		(width 0.12954)
		(layer "In2.Cu")
		(net "SMB_P52V_PDB_SCL")
	)
	(segment
		(start 420.444422 -38.802056)
		(end 420.444422 -39.810944)
		(width 0.12954)
		(layer "In2.Cu")
		(net "SMB_P52V_PDB_SCL")
	)
	(segment
		(start 235.820458 -88.205056)
		(end 235.820458 -88.451944)
		(width 0.12954)
		(layer "In2.Cu")
		(net "SMB_P52V_PDB_SCL")
	)
	(segment
		(start 234.494578 -88.451944)
		(end 234.300522 -88.646)
		(width 0.12954)
		(layer "In2.Cu")
		(net "SMB_P52V_PDB_SCL")
	)
	(segment
		(start 234.494578 -88.205056)
		(end 234.494578 -88.451944)
		(width 0.12954)
		(layer "In2.Cu")
		(net "SMB_P52V_PDB_SCL")
	)
	(segment
		(start 421.301418 -38.608)
		(end 421.576246 -38.608)
		(width 0.12954)
		(layer "In2.Cu")
		(net "SMB_P52V_PDB_SCL")
	)
	(segment
		(start 236.952282 -88.646)
		(end 236.677454 -88.646)
		(width 0.12954)
		(layer "In2.Cu")
		(net "SMB_P52V_PDB_SCL")
	)
	(segment
		(start 418.924486 -38.608)
		(end 419.118542 -38.802056)
		(width 0.12954)
		(layer "In2.Cu")
		(net "SMB_P52V_PDB_SCL")
	)
	(segment
		(start 233.637582 -88.011)
		(end 233.362754 -88.011)
		(width 0.12954)
		(layer "In2.Cu")
		(net "SMB_P52V_PDB_SCL")
	)
	(segment
		(start 183.048402 -79.162402)
		(end 184.33542 -80.44942)
		(width 0.12954)
		(layer "In2.Cu")
		(net "SMB_P52V_PDB_SCL")
	)
	(segment
		(start 292.675818 -88.138)
		(end 293.183818 -87.63)
		(width 0.12954)
		(layer "In2.Cu")
		(net "SMB_P52V_PDB_SCL")
	)
	(segment
		(start 232.505758 -88.451944)
		(end 232.505758 -88.205056)
		(width 0.12954)
		(layer "In2.Cu")
		(net "SMB_P52V_PDB_SCL")
	)
	(segment
		(start 417.792662 -38.802056)
		(end 417.792662 -39.810944)
		(width 0.12954)
		(layer "In2.Cu")
		(net "SMB_P52V_PDB_SCL")
	)
	(segment
		(start 236.483398 -88.451944)
		(end 236.483398 -88.205056)
		(width 0.12954)
		(layer "In2.Cu")
		(net "SMB_P52V_PDB_SCL")
	)
	(segment
		(start 434.77561 -37.41674)
		(end 435.3814 -36.81095)
		(width 0.12954)
		(layer "In2.Cu")
		(net "SMB_P52V_PDB_SCL")
	)
	(segment
		(start 417.986718 -40.005)
		(end 418.261546 -40.005)
		(width 0.12954)
		(layer "In2.Cu")
		(net "SMB_P52V_PDB_SCL")
	)
	(segment
		(start 235.820458 -88.451944)
		(end 235.626402 -88.646)
		(width 0.12954)
		(layer "In2.Cu")
		(net "SMB_P52V_PDB_SCL")
	)
	(segment
		(start 422.902126 -38.608)
		(end 423.096182 -38.802056)
		(width 0.12954)
		(layer "In2.Cu")
		(net "SMB_P52V_PDB_SCL")
	)
	(segment
		(start 421.107362 -38.802056)
		(end 421.301418 -38.608)
		(width 0.12954)
		(layer "In2.Cu")
		(net "SMB_P52V_PDB_SCL")
	)
	(segment
		(start 232.036874 -88.011)
		(end 231.842818 -88.205056)
		(width 0.12954)
		(layer "In2.Cu")
		(net "SMB_P52V_PDB_SCL")
	)
	(segment
		(start 357.97236 -79.296768)
		(end 375.979944 -61.289184)
		(width 0.12954)
		(layer "In2.Cu")
		(net "SMB_P52V_PDB_SCL")
	)
	(segment
		(start 422.627298 -38.608)
		(end 422.902126 -38.608)
		(width 0.12954)
		(layer "In2.Cu")
		(net "SMB_P52V_PDB_SCL")
	)
	(segment
		(start 236.677454 -88.646)
		(end 236.483398 -88.451944)
		(width 0.12954)
		(layer "In2.Cu")
		(net "SMB_P52V_PDB_SCL")
	)
	(segment
		(start 417.598606 -38.608)
		(end 417.792662 -38.802056)
		(width 0.12954)
		(layer "In2.Cu")
		(net "SMB_P52V_PDB_SCL")
	)
	(segment
		(start 419.781482 -39.810944)
		(end 419.781482 -38.802056)
		(width 0.12954)
		(layer "In2.Cu")
		(net "SMB_P52V_PDB_SCL")
	)
	(segment
		(start 238.003334 -88.646)
		(end 237.809278 -88.451944)
		(width 0.12954)
		(layer "In2.Cu")
		(net "SMB_P52V_PDB_SCL")
	)
	(segment
		(start 266.6492 -71.16064)
		(end 261.431024 -76.378816)
		(width 0.12954)
		(layer "In2.Cu")
		(net "SMB_P52V_PDB_SCL")
	)
	(segment
		(start 421.770302 -39.810944)
		(end 421.964358 -40.005)
		(width 0.12954)
		(layer "In2.Cu")
		(net "SMB_P52V_PDB_SCL")
	)
	(segment
		(start 175.472598 -79.162402)
		(end 183.048402 -79.162402)
		(width 0.12954)
		(layer "In2.Cu")
		(net "SMB_P52V_PDB_SCL")
	)
	(segment
		(start 229.154736 -88.646)
		(end 225.16465 -92.636086)
		(width 0.12954)
		(layer "In2.Cu")
		(net "SMB_P52V_PDB_SCL")
	)
	(segment
		(start 418.649658 -38.608)
		(end 418.924486 -38.608)
		(width 0.12954)
		(layer "In2.Cu")
		(net "SMB_P52V_PDB_SCL")
	)
	(segment
		(start 417.792662 -39.810944)
		(end 417.986718 -40.005)
		(width 0.12954)
		(layer "In2.Cu")
		(net "SMB_P52V_PDB_SCL")
	)
	(segment
		(start 423.096182 -39.810944)
		(end 423.290238 -40.005)
		(width 0.12954)
		(layer "In2.Cu")
		(net "SMB_P52V_PDB_SCL")
	)
	(segment
		(start 236.289342 -88.011)
		(end 236.014514 -88.011)
		(width 0.12954)
		(layer "In2.Cu")
		(net "SMB_P52V_PDB_SCL")
	)
	(segment
		(start 420.638478 -40.005)
		(end 420.913306 -40.005)
		(width 0.12954)
		(layer "In2.Cu")
		(net "SMB_P52V_PDB_SCL")
	)
	(segment
		(start 422.433242 -38.802056)
		(end 422.627298 -38.608)
		(width 0.12954)
		(layer "In2.Cu")
		(net "SMB_P52V_PDB_SCL")
	)
	(segment
		(start 421.964358 -40.005)
		(end 422.239186 -40.005)
		(width 0.12954)
		(layer "In2.Cu")
		(net "SMB_P52V_PDB_SCL")
	)
	(segment
		(start 423.565066 -40.005)
		(end 423.759122 -39.810944)
		(width 0.12954)
		(layer "In2.Cu")
		(net "SMB_P52V_PDB_SCL")
	)
	(segment
		(start 232.311702 -88.011)
		(end 232.036874 -88.011)
		(width 0.12954)
		(layer "In2.Cu")
		(net "SMB_P52V_PDB_SCL")
	)
	(segment
		(start 336.742532 -79.296768)
		(end 357.97236 -79.296768)
		(width 0.12954)
		(layer "In2.Cu")
		(net "SMB_P52V_PDB_SCL")
	)
	(segment
		(start 423.759122 -37.699696)
		(end 425.185078 -36.27374)
		(width 0.12954)
		(layer "In2.Cu")
		(net "SMB_P52V_PDB_SCL")
	)
	(segment
		(start 261.431024 -77.21854)
		(end 258.258564 -80.391)
		(width 0.12954)
		(layer "In2.Cu")
		(net "SMB_P52V_PDB_SCL")
	)
	(segment
		(start 419.118542 -38.802056)
		(end 419.118542 -39.810944)
		(width 0.12954)
		(layer "In2.Cu")
		(net "SMB_P52V_PDB_SCL")
	)
	(segment
		(start 432.064922 -37.41674)
		(end 434.77561 -37.41674)
		(width 0.12954)
		(layer "In2.Cu")
		(net "SMB_P52V_PDB_SCL")
	)
	(segment
		(start 231.648762 -88.646)
		(end 229.154736 -88.646)
		(width 0.12954)
		(layer "In2.Cu")
		(net "SMB_P52V_PDB_SCL")
	)
	(segment
		(start 247.396 -80.391)
		(end 239.141 -88.646)
		(width 0.12954)
		(layer "In2.Cu")
		(net "SMB_P52V_PDB_SCL")
	)
	(segment
		(start 410.226002 -50.255932)
		(end 410.226002 -42.620438)
		(width 0.12954)
		(layer "In2.Cu")
		(net "SMB_P52V_PDB_SCL")
	)
	(segment
		(start 267.97 -66.294)
		(end 266.6492 -67.6148)
		(width 0.12954)
		(layer "In2.Cu")
		(net "SMB_P52V_PDB_SCL")
	)
	(segment
		(start 237.146338 -88.205056)
		(end 237.146338 -88.451944)
		(width 0.12954)
		(layer "In2.Cu")
		(net "SMB_P52V_PDB_SCL")
	)
	(segment
		(start 236.483398 -88.205056)
		(end 236.289342 -88.011)
		(width 0.12954)
		(layer "In2.Cu")
		(net "SMB_P52V_PDB_SCL")
	)
	(segment
		(start 420.250366 -38.608)
		(end 420.444422 -38.802056)
		(width 0.12954)
		(layer "In2.Cu")
		(net "SMB_P52V_PDB_SCL")
	)
	(segment
		(start 235.626402 -88.646)
		(end 235.351574 -88.646)
		(width 0.12954)
		(layer "In2.Cu")
		(net "SMB_P52V_PDB_SCL")
	)
	(segment
		(start 417.129722 -38.802056)
		(end 417.323778 -38.608)
		(width 0.12954)
		(layer "In2.Cu")
		(net "SMB_P52V_PDB_SCL")
	)
	(segment
		(start 237.146338 -88.451944)
		(end 236.952282 -88.646)
		(width 0.12954)
		(layer "In2.Cu")
		(net "SMB_P52V_PDB_SCL")
	)
	(segment
		(start 225.16465 -92.636086)
		(end 223.05645 -92.636086)
		(width 0.12954)
		(layer "In2.Cu")
		(net "SMB_P52V_PDB_SCL")
	)
	(segment
		(start 278.13 -66.779648)
		(end 277.644352 -66.294)
		(width 0.12954)
		(layer "In2.Cu")
		(net "SMB_P52V_PDB_SCL")
	)
	(segment
		(start 375.979944 -61.289184)
		(end 399.19275 -61.289184)
		(width 0.12954)
		(layer "In2.Cu")
		(net "SMB_P52V_PDB_SCL")
	)
	(segment
		(start 410.226002 -42.620438)
		(end 412.40964 -40.4368)
		(width 0.12954)
		(layer "In2.Cu")
		(net "SMB_P52V_PDB_SCL")
	)
	(segment
		(start 416.503866 -40.4368)
		(end 417.129722 -39.810944)
		(width 0.12954)
		(layer "In2.Cu")
		(net "SMB_P52V_PDB_SCL")
	)
	(segment
		(start 419.587426 -40.005)
		(end 419.781482 -39.810944)
		(width 0.12954)
		(layer "In2.Cu")
		(net "SMB_P52V_PDB_SCL")
	)
	(segment
		(start 223.05645 -91.33205)
		(end 223.05645 -92.636086)
		(width 0.12954)
		(layer "In2.Cu")
		(net "SMB_P52V_PDB_SCL")
	)
	(segment
		(start 184.33542 -80.44942)
		(end 201.065384 -80.44942)
		(width 0.12954)
		(layer "In2.Cu")
		(net "SMB_P52V_PDB_SCL")
	)
	(segment
		(start 237.809278 -88.205056)
		(end 237.615222 -88.011)
		(width 0.12954)
		(layer "In2.Cu")
		(net "SMB_P52V_PDB_SCL")
	)
	(segment
		(start 168.194736 -71.247)
		(end 169.025824 -71.247)
		(width 0.12954)
		(layer "In2.Cu")
		(net "SMB_P52V_PDB_SCL")
	)
	(segment
		(start 235.351574 -88.646)
		(end 235.157518 -88.451944)
		(width 0.12954)
		(layer "In2.Cu")
		(net "SMB_P52V_PDB_SCL")
	)
	(segment
		(start 235.157518 -88.205056)
		(end 234.963462 -88.011)
		(width 0.12954)
		(layer "In2.Cu")
		(net "SMB_P52V_PDB_SCL")
	)
	(segment
		(start 290.37026 -87.67826)
		(end 290.83 -88.138)
		(width 0.12954)
		(layer "In2.Cu")
		(net "SMB_P52V_PDB_SCL")
	)
	(segment
		(start 423.290238 -40.005)
		(end 423.565066 -40.005)
		(width 0.12954)
		(layer "In2.Cu")
		(net "SMB_P52V_PDB_SCL")
	)
	(segment
		(start 235.157518 -88.451944)
		(end 235.157518 -88.205056)
		(width 0.12954)
		(layer "In2.Cu")
		(net "SMB_P52V_PDB_SCL")
	)
	(segment
		(start 423.096182 -38.802056)
		(end 423.096182 -39.810944)
		(width 0.12954)
		(layer "In2.Cu")
		(net "SMB_P52V_PDB_SCL")
	)
	(segment
		(start 418.455602 -39.810944)
		(end 418.455602 -38.802056)
		(width 0.12954)
		(layer "In2.Cu")
		(net "SMB_P52V_PDB_SCL")
	)
	(segment
		(start 419.312598 -40.005)
		(end 419.587426 -40.005)
		(width 0.12954)
		(layer "In2.Cu")
		(net "SMB_P52V_PDB_SCL")
	)
	(segment
		(start 419.975538 -38.608)
		(end 420.250366 -38.608)
		(width 0.12954)
		(layer "In2.Cu")
		(net "SMB_P52V_PDB_SCL")
	)
	(segment
		(start 234.963462 -88.011)
		(end 234.688634 -88.011)
		(width 0.12954)
		(layer "In2.Cu")
		(net "SMB_P52V_PDB_SCL")
	)
	(segment
		(start 290.83 -88.138)
		(end 292.675818 -88.138)
		(width 0.12954)
		(layer "In2.Cu")
		(net "SMB_P52V_PDB_SCL")
	)
	(segment
		(start 412.40964 -40.4368)
		(end 416.503866 -40.4368)
		(width 0.12954)
		(layer "In2.Cu")
		(net "SMB_P52V_PDB_SCL")
	)
	(segment
		(start 231.842818 -88.205056)
		(end 231.842818 -88.451944)
		(width 0.12954)
		(layer "In2.Cu")
		(net "SMB_P52V_PDB_SCL")
	)
	(segment
		(start 239.141 -88.646)
		(end 238.003334 -88.646)
		(width 0.12954)
		(layer "In2.Cu")
		(net "SMB_P52V_PDB_SCL")
	)
	(segment
		(start 420.444422 -39.810944)
		(end 420.638478 -40.005)
		(width 0.12954)
		(layer "In2.Cu")
		(net "SMB_P52V_PDB_SCL")
	)
	(segment
		(start 289.76574 -87.67826)
		(end 290.37026 -87.67826)
		(width 0.12954)
		(layer "In2.Cu")
		(net "SMB_P52V_PDB_SCL")
	)
	(segment
		(start 232.505758 -88.205056)
		(end 232.311702 -88.011)
		(width 0.12954)
		(layer "In2.Cu")
		(net "SMB_P52V_PDB_SCL")
	)
	(segment
		(start 422.433242 -39.810944)
		(end 422.433242 -38.802056)
		(width 0.12954)
		(layer "In2.Cu")
		(net "SMB_P52V_PDB_SCL")
	)
	(segment
		(start 233.831638 -88.205056)
		(end 233.637582 -88.011)
		(width 0.12954)
		(layer "In2.Cu")
		(net "SMB_P52V_PDB_SCL")
	)
	(segment
		(start 174.98568 -78.675484)
		(end 175.472598 -79.162402)
		(width 0.12954)
		(layer "In2.Cu")
		(net "SMB_P52V_PDB_SCL")
	)
	(segment
		(start 174.98568 -77.206856)
		(end 174.98568 -78.675484)
		(width 0.12954)
		(layer "In2.Cu")
		(net "SMB_P52V_PDB_SCL")
	)
	(segment
		(start 266.6492 -67.6148)
		(end 266.6492 -71.16064)
		(width 0.12954)
		(layer "In2.Cu")
		(net "SMB_P52V_PDB_SCL")
	)
	(segment
		(start 232.974642 -88.646)
		(end 232.699814 -88.646)
		(width 0.12954)
		(layer "In2.Cu")
		(net "SMB_P52V_PDB_SCL")
	)
	(segment
		(start 233.831638 -88.451944)
		(end 233.831638 -88.205056)
		(width 0.12954)
		(layer "In2.Cu")
		(net "SMB_P52V_PDB_SCL")
	)
	(segment
		(start 236.014514 -88.011)
		(end 235.820458 -88.205056)
		(width 0.12954)
		(layer "In2.Cu")
		(net "SMB_P52V_PDB_SCL")
	)
	(segment
		(start 234.300522 -88.646)
		(end 234.025694 -88.646)
		(width 0.12954)
		(layer "In2.Cu")
		(net "SMB_P52V_PDB_SCL")
	)
	(segment
		(start 417.323778 -38.608)
		(end 417.598606 -38.608)
		(width 0.12954)
		(layer "In2.Cu")
		(net "SMB_P52V_PDB_SCL")
	)
	(segment
		(start 201.065384 -80.44942)
		(end 209.566764 -88.9508)
		(width 0.12954)
		(layer "In2.Cu")
		(net "SMB_P52V_PDB_SCL")
	)
	(segment
		(start 232.699814 -88.646)
		(end 232.505758 -88.451944)
		(width 0.12954)
		(layer "In2.Cu")
		(net "SMB_P52V_PDB_SCL")
	)
	(segment
		(start 220.6752 -88.9508)
		(end 223.05645 -91.33205)
		(width 0.12954)
		(layer "In2.Cu")
		(net "SMB_P52V_PDB_SCL")
	)
	(segment
		(start 209.566764 -88.9508)
		(end 220.6752 -88.9508)
		(width 0.12954)
		(layer "In2.Cu")
		(net "SMB_P52V_PDB_SCL")
	)
	(segment
		(start 261.431024 -76.378816)
		(end 261.431024 -77.21854)
		(width 0.12954)
		(layer "In2.Cu")
		(net "SMB_P52V_PDB_SCL")
	)
	(segment
		(start 233.168698 -88.451944)
		(end 232.974642 -88.646)
		(width 0.12954)
		(layer "In2.Cu")
		(net "SMB_P52V_PDB_SCL")
	)
	(segment
		(start 237.340394 -88.011)
		(end 237.146338 -88.205056)
		(width 0.12954)
		(layer "In2.Cu")
		(net "SMB_P52V_PDB_SCL")
	)
	(segment
		(start 422.239186 -40.005)
		(end 422.433242 -39.810944)
		(width 0.12954)
		(layer "In2.Cu")
		(net "SMB_P52V_PDB_SCL")
	)
	(segment
		(start 418.455602 -38.802056)
		(end 418.649658 -38.608)
		(width 0.12954)
		(layer "In2.Cu")
		(net "SMB_P52V_PDB_SCL")
	)
	(segment
		(start 277.644352 -66.294)
		(end 267.97 -66.294)
		(width 0.12954)
		(layer "In2.Cu")
		(net "SMB_P52V_PDB_SCL")
	)
	(segment
		(start 421.770302 -38.802056)
		(end 421.770302 -39.810944)
		(width 0.12954)
		(layer "In2.Cu")
		(net "SMB_P52V_PDB_SCL")
	)
	(segment
		(start 278.13 -67.31)
		(end 278.13 -66.779648)
		(width 0.12954)
		(layer "In2.Cu")
		(net "SMB_P52V_PDB_SCL")
	)
	(segment
		(start 279.781 -68.961)
		(end 278.13 -67.31)
		(width 0.12954)
		(layer "In2.Cu")
		(net "SMB_P52V_PDB_SCL")
	)
	(segment
		(start 258.258564 -80.391)
		(end 247.396 -80.391)
		(width 0.12954)
		(layer "In2.Cu")
		(net "SMB_P52V_PDB_SCL")
	)
	(segment
		(start 418.261546 -40.005)
		(end 418.455602 -39.810944)
		(width 0.12954)
		(layer "In2.Cu")
		(net "SMB_P52V_PDB_SCL")
	)
	(segment
		(start 419.781482 -38.802056)
		(end 419.975538 -38.608)
		(width 0.12954)
		(layer "In2.Cu")
		(net "SMB_P52V_PDB_SCL")
	)
	(segment
		(start 417.129722 -39.810944)
		(end 417.129722 -38.802056)
		(width 0.12954)
		(layer "In2.Cu")
		(net "SMB_P52V_PDB_SCL")
	)
	(segment
		(start 421.576246 -38.608)
		(end 421.770302 -38.802056)
		(width 0.12954)
		(layer "In2.Cu")
		(net "SMB_P52V_PDB_SCL")
	)
	(segment
		(start 420.913306 -40.005)
		(end 421.107362 -39.810944)
		(width 0.12954)
		(layer "In2.Cu")
		(net "SMB_P52V_PDB_SCL")
	)
	(segment
		(start 289.306 -87.63)
		(end 286.258 -87.63)
		(width 0.17272)
		(layer "F.Cu")
		(net "SMB_P52V_PDB_SDA")
	)
	(segment
		(start 282.3718 -67.564)
		(end 285.4706 -70.6628)
		(width 0.17272)
		(layer "F.Cu")
		(net "SMB_P52V_PDB_SDA")
	)
	(segment
		(start 278.0284 -67.564)
		(end 282.3718 -67.564)
		(width 0.17272)
		(layer "F.Cu")
		(net "SMB_P52V_PDB_SDA")
	)
	(segment
		(start 450.342 -36.81095)
		(end 450.342 -36.20135)
		(width 0.17272)
		(layer "F.Cu")
		(net "SMB_P52V_PDB_SDA")
	)
	(segment
		(start 168.239948 -70.556628)
		(end 166.107364 -70.556628)
		(width 0.17272)
		(layer "F.Cu")
		(net "SMB_P52V_PDB_SDA")
	)
	(segment
		(start 285.4706 -72.4408)
		(end 284.8864 -73.025)
		(width 0.17272)
		(layer "F.Cu")
		(net "SMB_P52V_PDB_SDA")
	)
	(segment
		(start 286.1056 -79.1718)
		(end 286.1056 -74.6252)
		(width 0.17272)
		(layer "F.Cu")
		(net "SMB_P52V_PDB_SDA")
	)
	(segment
		(start 223.05645 -95.0214)
		(end 223.05645 -97.028)
		(width 0.17272)
		(layer "F.Cu")
		(net "SMB_P52V_PDB_SDA")
	)
	(segment
		(start 286.258 -87.63)
		(end 284.48 -85.852)
		(width 0.17272)
		(layer "F.Cu")
		(net "SMB_P52V_PDB_SDA")
	)
	(segment
		(start 170.226736 -72.543416)
		(end 168.239948 -70.556628)
		(width 0.17272)
		(layer "F.Cu")
		(net "SMB_P52V_PDB_SDA")
	)
	(segment
		(start 277.3934 -66.929)
		(end 278.0284 -67.564)
		(width 0.17272)
		(layer "F.Cu")
		(net "SMB_P52V_PDB_SDA")
	)
	(segment
		(start 284.48 -85.852)
		(end 284.48 -80.7974)
		(width 0.17272)
		(layer "F.Cu")
		(net "SMB_P52V_PDB_SDA")
	)
	(segment
		(start 289.941 -88.265)
		(end 289.306 -87.63)
		(width 0.17272)
		(layer "F.Cu")
		(net "SMB_P52V_PDB_SDA")
	)
	(segment
		(start 286.1056 -74.6252)
		(end 284.8864 -73.406)
		(width 0.17272)
		(layer "F.Cu")
		(net "SMB_P52V_PDB_SDA")
	)
	(segment
		(start 285.4706 -70.6628)
		(end 285.4706 -72.4408)
		(width 0.17272)
		(layer "F.Cu")
		(net "SMB_P52V_PDB_SDA")
	)
	(segment
		(start 284.48 -80.7974)
		(end 286.1056 -79.1718)
		(width 0.17272)
		(layer "F.Cu")
		(net "SMB_P52V_PDB_SDA")
	)
	(segment
		(start 170.226736 -73.279)
		(end 170.226736 -72.543416)
		(width 0.17272)
		(layer "F.Cu")
		(net "SMB_P52V_PDB_SDA")
	)
	(segment
		(start 166.107364 -70.556628)
		(end 162.733736 -67.183)
		(width 0.17272)
		(layer "F.Cu")
		(net "SMB_P52V_PDB_SDA")
	)
	(segment
		(start 284.8864 -73.406)
		(end 284.8864 -73.025)
		(width 0.17272)
		(layer "F.Cu")
		(net "SMB_P52V_PDB_SDA")
	)
	(via
		(at 450.342 -36.20135)
		(size 0.508)
		(drill 0.254)
		(layers "F.Cu" "B.Cu")
		(net "SMB_P52V_PDB_SDA")
	)
	(via
		(at 170.226736 -73.279)
		(size 0.508)
		(drill 0.254)
		(layers "F.Cu" "B.Cu")
		(net "SMB_P52V_PDB_SDA")
	)
	(via
		(at 284.8864 -73.025)
		(size 0.508)
		(drill 0.254)
		(layers "F.Cu" "B.Cu")
		(net "SMB_P52V_PDB_SDA")
	)
	(via
		(at 289.941 -88.265)
		(size 0.508)
		(drill 0.254)
		(layers "F.Cu" "B.Cu")
		(net "SMB_P52V_PDB_SDA")
	)
	(via
		(at 162.733736 -67.183)
		(size 0.508)
		(drill 0.254)
		(layers "F.Cu" "B.Cu")
		(net "SMB_P52V_PDB_SDA")
	)
	(via
		(at 223.05645 -95.0214)
		(size 0.508)
		(drill 0.254)
		(layers "F.Cu" "B.Cu")
		(net "SMB_P52V_PDB_SDA")
	)
	(via
		(at 277.3934 -66.929)
		(size 0.508)
		(drill 0.254)
		(layers "F.Cu" "B.Cu")
		(net "SMB_P52V_PDB_SDA")
	)
	(segment
		(start 278.00935 -66.929)
		(end 277.3934 -66.929)
		(width 0.17272)
		(layer "B.Cu")
		(net "SMB_P52V_PDB_SDA")
	)
	(segment
		(start 278.80945 -64.897)
		(end 278.80945 -65.913)
		(width 0.17272)
		(layer "B.Cu")
		(net "SMB_P52V_PDB_SDA")
	)
	(segment
		(start 169.610786 -73.279)
		(end 170.226736 -73.279)
		(width 0.17272)
		(layer "B.Cu")
		(net "SMB_P52V_PDB_SDA")
	)
	(segment
		(start 162.117786 -67.183)
		(end 162.733736 -67.183)
		(width 0.17272)
		(layer "B.Cu")
		(net "SMB_P52V_PDB_SDA")
	)
	(segment
		(start 278.80945 -65.913)
		(end 278.00935 -66.7131)
		(width 0.17272)
		(layer "B.Cu")
		(net "SMB_P52V_PDB_SDA")
	)
	(segment
		(start 278.00935 -66.7131)
		(end 278.00935 -66.929)
		(width 0.17272)
		(layer "B.Cu")
		(net "SMB_P52V_PDB_SDA")
	)
	(segment
		(start 168.810686 -75.311)
		(end 168.810686 -74.295)
		(width 0.17272)
		(layer "B.Cu")
		(net "SMB_P52V_PDB_SDA")
	)
	(segment
		(start 169.610786 -73.4949)
		(end 169.610786 -73.279)
		(width 0.17272)
		(layer "B.Cu")
		(net "SMB_P52V_PDB_SDA")
	)
	(segment
		(start 162.117786 -66.04)
		(end 162.117786 -67.183)
		(width 0.17272)
		(layer "B.Cu")
		(net "SMB_P52V_PDB_SDA")
	)
	(segment
		(start 168.810686 -74.295)
		(end 169.610786 -73.4949)
		(width 0.17272)
		(layer "B.Cu")
		(net "SMB_P52V_PDB_SDA")
	)
	(segment
		(start 285.50235 -74.168)
		(end 285.50235 -73.025)
		(width 0.17272)
		(layer "B.Cu")
		(net "SMB_P52V_PDB_SDA")
	)
	(segment
		(start 285.50235 -73.025)
		(end 284.8864 -73.025)
		(width 0.17272)
		(layer "B.Cu")
		(net "SMB_P52V_PDB_SDA")
	)
	(segment
		(start 289.941 -88.265)
		(end 290.449 -88.773)
		(width 0.12954)
		(layer "In2.Cu")
		(net "SMB_P52V_PDB_SDA")
	)
	(segment
		(start 293.378636 -88.265)
		(end 328.604118 -88.265)
		(width 0.12954)
		(layer "In2.Cu")
		(net "SMB_P52V_PDB_SDA")
	)
	(segment
		(start 328.604118 -88.265)
		(end 336.939382 -79.929736)
		(width 0.12954)
		(layer "In2.Cu")
		(net "SMB_P52V_PDB_SDA")
	)
	(segment
		(start 200.870566 -81.08442)
		(end 209.323686 -89.53754)
		(width 0.12954)
		(layer "In2.Cu")
		(net "SMB_P52V_PDB_SDA")
	)
	(segment
		(start 222.221298 -91.326716)
		(end 222.221298 -92.681552)
		(width 0.12954)
		(layer "In2.Cu")
		(net "SMB_P52V_PDB_SDA")
	)
	(segment
		(start 290.449 -88.773)
		(end 292.870636 -88.773)
		(width 0.12954)
		(layer "In2.Cu")
		(net "SMB_P52V_PDB_SDA")
	)
	(segment
		(start 222.221298 -92.681552)
		(end 223.05645 -93.516704)
		(width 0.12954)
		(layer "In2.Cu")
		(net "SMB_P52V_PDB_SDA")
	)
	(segment
		(start 224.028 -95.0214)
		(end 229.764082 -89.285318)
		(width 0.12954)
		(layer "In2.Cu")
		(net "SMB_P52V_PDB_SDA")
	)
	(segment
		(start 376.223022 -61.875924)
		(end 399.548604 -61.875924)
		(width 0.12954)
		(layer "In2.Cu")
		(net "SMB_P52V_PDB_SDA")
	)
	(segment
		(start 174.39894 -77.451204)
		(end 174.39894 -78.918562)
		(width 0.12954)
		(layer "In2.Cu")
		(net "SMB_P52V_PDB_SDA")
	)
	(segment
		(start 274.3962 -71.7296)
		(end 274.3962 -68.9102)
		(width 0.12954)
		(layer "In2.Cu")
		(net "SMB_P52V_PDB_SDA")
	)
	(segment
		(start 410.903928 -42.77233)
		(end 412.629858 -41.0464)
		(width 0.12954)
		(layer "In2.Cu")
		(net "SMB_P52V_PDB_SDA")
	)
	(segment
		(start 448.44335 -38.1)
		(end 450.342 -36.20135)
		(width 0.12954)
		(layer "In2.Cu")
		(net "SMB_P52V_PDB_SDA")
	)
	(segment
		(start 276.3774 -66.929)
		(end 277.3934 -66.929)
		(width 0.12954)
		(layer "In2.Cu")
		(net "SMB_P52V_PDB_SDA")
	)
	(segment
		(start 170.226736 -73.279)
		(end 174.39894 -77.451204)
		(width 0.12954)
		(layer "In2.Cu")
		(net "SMB_P52V_PDB_SDA")
	)
	(segment
		(start 223.05645 -95.0214)
		(end 224.028 -95.0214)
		(width 0.12954)
		(layer "In2.Cu")
		(net "SMB_P52V_PDB_SDA")
	)
	(segment
		(start 426.3898 -38.1)
		(end 448.44335 -38.1)
		(width 0.12954)
		(layer "In2.Cu")
		(net "SMB_P52V_PDB_SDA")
	)
	(segment
		(start 399.548604 -61.875924)
		(end 410.903928 -50.5206)
		(width 0.12954)
		(layer "In2.Cu")
		(net "SMB_P52V_PDB_SDA")
	)
	(segment
		(start 174.39894 -78.918562)
		(end 175.22952 -79.749142)
		(width 0.12954)
		(layer "In2.Cu")
		(net "SMB_P52V_PDB_SDA")
	)
	(segment
		(start 223.05645 -93.516704)
		(end 223.05645 -95.0214)
		(width 0.12954)
		(layer "In2.Cu")
		(net "SMB_P52V_PDB_SDA")
	)
	(segment
		(start 178.978052 -79.749142)
		(end 180.31333 -81.08442)
		(width 0.12954)
		(layer "In2.Cu")
		(net "SMB_P52V_PDB_SDA")
	)
	(segment
		(start 258.326382 -81.153)
		(end 262.017764 -77.461618)
		(width 0.12954)
		(layer "In2.Cu")
		(net "SMB_P52V_PDB_SDA")
	)
	(segment
		(start 247.523 -81.153)
		(end 258.326382 -81.153)
		(width 0.12954)
		(layer "In2.Cu")
		(net "SMB_P52V_PDB_SDA")
	)
	(segment
		(start 209.323686 -89.53754)
		(end 220.432122 -89.53754)
		(width 0.12954)
		(layer "In2.Cu")
		(net "SMB_P52V_PDB_SDA")
	)
	(segment
		(start 262.017764 -76.621894)
		(end 266.54506 -72.094598)
		(width 0.12954)
		(layer "In2.Cu")
		(net "SMB_P52V_PDB_SDA")
	)
	(segment
		(start 270.281654 -72.74306)
		(end 273.38274 -72.74306)
		(width 0.12954)
		(layer "In2.Cu")
		(net "SMB_P52V_PDB_SDA")
	)
	(segment
		(start 292.870636 -88.773)
		(end 293.378636 -88.265)
		(width 0.12954)
		(layer "In2.Cu")
		(net "SMB_P52V_PDB_SDA")
	)
	(segment
		(start 180.31333 -81.08442)
		(end 200.870566 -81.08442)
		(width 0.12954)
		(layer "In2.Cu")
		(net "SMB_P52V_PDB_SDA")
	)
	(segment
		(start 336.939382 -79.929736)
		(end 358.16921 -79.929736)
		(width 0.12954)
		(layer "In2.Cu")
		(net "SMB_P52V_PDB_SDA")
	)
	(segment
		(start 175.22952 -79.749142)
		(end 178.978052 -79.749142)
		(width 0.12954)
		(layer "In2.Cu")
		(net "SMB_P52V_PDB_SDA")
	)
	(segment
		(start 410.903928 -50.5206)
		(end 410.903928 -42.77233)
		(width 0.12954)
		(layer "In2.Cu")
		(net "SMB_P52V_PDB_SDA")
	)
	(segment
		(start 229.764082 -89.285318)
		(end 239.390682 -89.285318)
		(width 0.12954)
		(layer "In2.Cu")
		(net "SMB_P52V_PDB_SDA")
	)
	(segment
		(start 262.017764 -77.461618)
		(end 262.017764 -76.621894)
		(width 0.12954)
		(layer "In2.Cu")
		(net "SMB_P52V_PDB_SDA")
	)
	(segment
		(start 269.633192 -72.094598)
		(end 270.281654 -72.74306)
		(width 0.12954)
		(layer "In2.Cu")
		(net "SMB_P52V_PDB_SDA")
	)
	(segment
		(start 266.54506 -72.094598)
		(end 269.633192 -72.094598)
		(width 0.12954)
		(layer "In2.Cu")
		(net "SMB_P52V_PDB_SDA")
	)
	(segment
		(start 274.3962 -68.9102)
		(end 276.3774 -66.929)
		(width 0.12954)
		(layer "In2.Cu")
		(net "SMB_P52V_PDB_SDA")
	)
	(segment
		(start 423.4434 -41.0464)
		(end 426.3898 -38.1)
		(width 0.12954)
		(layer "In2.Cu")
		(net "SMB_P52V_PDB_SDA")
	)
	(segment
		(start 358.16921 -79.929736)
		(end 376.223022 -61.875924)
		(width 0.12954)
		(layer "In2.Cu")
		(net "SMB_P52V_PDB_SDA")
	)
	(segment
		(start 273.38274 -72.74306)
		(end 274.3962 -71.7296)
		(width 0.12954)
		(layer "In2.Cu")
		(net "SMB_P52V_PDB_SDA")
	)
	(segment
		(start 239.390682 -89.285318)
		(end 247.523 -81.153)
		(width 0.12954)
		(layer "In2.Cu")
		(net "SMB_P52V_PDB_SDA")
	)
	(segment
		(start 412.629858 -41.0464)
		(end 423.4434 -41.0464)
		(width 0.12954)
		(layer "In2.Cu")
		(net "SMB_P52V_PDB_SDA")
	)
	(segment
		(start 220.432122 -89.53754)
		(end 222.221298 -91.326716)
		(width 0.12954)
		(layer "In2.Cu")
		(net "SMB_P52V_PDB_SDA")
	)
	(segment
		(start 446.095374 -37.13988)
		(end 444.827406 -37.13988)
		(width 0.17272)
		(layer "F.Cu")
		(net "SMB_P52V_SDA")
	)
	(segment
		(start 446.424304 -36.81095)
		(end 446.095374 -37.13988)
		(width 0.17272)
		(layer "F.Cu")
		(net "SMB_P52V_SDA")
	)
	(segment
		(start 448.056 -36.81095)
		(end 446.424304 -36.81095)
		(width 0.17272)
		(layer "F.Cu")
		(net "SMB_P52V_SDA")
	)
	(segment
		(start 448.056 -36.81095)
		(end 448.056 -36.20135)
		(width 0.17272)
		(layer "F.Cu")
		(net "SMB_P52V_SDA")
	)
	(segment
		(start 470.449656 -107.102402)
		(end 470.449656 -106.486452)
		(width 0.17272)
		(layer "F.Cu")
		(net "SMB_P52V_SDA")
	)
	(via
		(at 470.449656 -106.486452)
		(size 0.508)
		(drill 0.254)
		(layers "F.Cu" "B.Cu")
		(net "SMB_P52V_SDA")
	)
	(via
		(at 448.056 -36.20135)
		(size 0.508)
		(drill 0.254)
		(layers "F.Cu" "B.Cu")
		(net "SMB_P52V_SDA")
	)
	(segment
		(start 456.5904 -49.5046)
		(end 456.5904 -45.720254)
		(width 0.17272)
		(layer "B.Cu")
		(net "SMB_P52V_SDA")
	)
	(segment
		(start 470.449656 -105.820972)
		(end 467.09076 -102.462076)
		(width 0.17272)
		(layer "B.Cu")
		(net "SMB_P52V_SDA")
	)
	(segment
		(start 451.77837 -40.187372)
		(end 452.69277 -39.272972)
		(width 0.17272)
		(layer "B.Cu")
		(net "SMB_P52V_SDA")
	)
	(segment
		(start 452.69277 -39.028624)
		(end 452.437754 -38.773608)
		(width 0.17272)
		(layer "B.Cu")
		(net "SMB_P52V_SDA")
	)
	(segment
		(start 453.032114 -41.685464)
		(end 452.777098 -41.430448)
		(width 0.17272)
		(layer "B.Cu")
		(net "SMB_P52V_SDA")
	)
	(segment
		(start 453.436482 -39.772336)
		(end 453.192134 -39.772336)
		(width 0.17272)
		(layer "B.Cu")
		(net "SMB_P52V_SDA")
	)
	(segment
		(start 453.775826 -42.184828)
		(end 454.690226 -41.270428)
		(width 0.17272)
		(layer "B.Cu")
		(net "SMB_P52V_SDA")
	)
	(segment
		(start 467.09076 -87.54491)
		(end 459.11516 -79.56931)
		(width 0.17272)
		(layer "B.Cu")
		(net "SMB_P52V_SDA")
	)
	(segment
		(start 452.033386 -40.686736)
		(end 451.77837 -40.43172)
		(width 0.17272)
		(layer "B.Cu")
		(net "SMB_P52V_SDA")
	)
	(segment
		(start 452.277734 -40.686736)
		(end 452.033386 -40.686736)
		(width 0.17272)
		(layer "B.Cu")
		(net "SMB_P52V_SDA")
	)
	(segment
		(start 454.690226 -41.270428)
		(end 454.690226 -41.02608)
		(width 0.17272)
		(layer "B.Cu")
		(net "SMB_P52V_SDA")
	)
	(segment
		(start 454.190862 -40.771064)
		(end 453.276462 -41.685464)
		(width 0.17272)
		(layer "B.Cu")
		(net "SMB_P52V_SDA")
	)
	(segment
		(start 452.777098 -41.430448)
		(end 452.777098 -41.1861)
		(width 0.17272)
		(layer "B.Cu")
		(net "SMB_P52V_SDA")
	)
	(segment
		(start 451.77837 -40.43172)
		(end 451.77837 -40.187372)
		(width 0.17272)
		(layer "B.Cu")
		(net "SMB_P52V_SDA")
	)
	(segment
		(start 450.999098 -39.688008)
		(end 448.056 -36.74491)
		(width 0.17272)
		(layer "B.Cu")
		(net "SMB_P52V_SDA")
	)
	(segment
		(start 454.690226 -41.02608)
		(end 454.43521 -40.771064)
		(width 0.17272)
		(layer "B.Cu")
		(net "SMB_P52V_SDA")
	)
	(segment
		(start 448.056 -36.74491)
		(end 448.056 -36.20135)
		(width 0.17272)
		(layer "B.Cu")
		(net "SMB_P52V_SDA")
	)
	(segment
		(start 453.192134 -39.772336)
		(end 452.277734 -40.686736)
		(width 0.17272)
		(layer "B.Cu")
		(net "SMB_P52V_SDA")
	)
	(segment
		(start 453.691498 -40.027352)
		(end 453.436482 -39.772336)
		(width 0.17272)
		(layer "B.Cu")
		(net "SMB_P52V_SDA")
	)
	(segment
		(start 459.11516 -79.56931)
		(end 459.11516 -52.02936)
		(width 0.17272)
		(layer "B.Cu")
		(net "SMB_P52V_SDA")
	)
	(segment
		(start 470.449656 -106.486452)
		(end 470.449656 -105.820972)
		(width 0.17272)
		(layer "B.Cu")
		(net "SMB_P52V_SDA")
	)
	(segment
		(start 451.279006 -39.688008)
		(end 450.999098 -39.688008)
		(width 0.17272)
		(layer "B.Cu")
		(net "SMB_P52V_SDA")
	)
	(segment
		(start 453.276462 -41.685464)
		(end 453.032114 -41.685464)
		(width 0.17272)
		(layer "B.Cu")
		(net "SMB_P52V_SDA")
	)
	(segment
		(start 452.193406 -38.773608)
		(end 451.279006 -39.688008)
		(width 0.17272)
		(layer "B.Cu")
		(net "SMB_P52V_SDA")
	)
	(segment
		(start 467.09076 -102.462076)
		(end 467.09076 -87.54491)
		(width 0.17272)
		(layer "B.Cu")
		(net "SMB_P52V_SDA")
	)
	(segment
		(start 452.69277 -39.272972)
		(end 452.69277 -39.028624)
		(width 0.17272)
		(layer "B.Cu")
		(net "SMB_P52V_SDA")
	)
	(segment
		(start 453.691498 -40.2717)
		(end 453.691498 -40.027352)
		(width 0.17272)
		(layer "B.Cu")
		(net "SMB_P52V_SDA")
	)
	(segment
		(start 452.437754 -38.773608)
		(end 452.193406 -38.773608)
		(width 0.17272)
		(layer "B.Cu")
		(net "SMB_P52V_SDA")
	)
	(segment
		(start 456.5904 -45.720254)
		(end 453.775826 -42.90568)
		(width 0.17272)
		(layer "B.Cu")
		(net "SMB_P52V_SDA")
	)
	(segment
		(start 453.775826 -42.90568)
		(end 453.775826 -42.184828)
		(width 0.17272)
		(layer "B.Cu")
		(net "SMB_P52V_SDA")
	)
	(segment
		(start 452.777098 -41.1861)
		(end 453.691498 -40.2717)
		(width 0.17272)
		(layer "B.Cu")
		(net "SMB_P52V_SDA")
	)
	(segment
		(start 459.11516 -52.02936)
		(end 456.5904 -49.5046)
		(width 0.17272)
		(layer "B.Cu")
		(net "SMB_P52V_SDA")
	)
	(segment
		(start 454.43521 -40.771064)
		(end 454.190862 -40.771064)
		(width 0.17272)
		(layer "B.Cu")
		(net "SMB_P52V_SDA")
	)
	(segment
		(start 440.34202 -37.160454)
		(end 438.353454 -37.160454)
		(width 0.17272)
		(layer "F.Cu")
		(net "SMB_P52V_SCL")
	)
	(segment
		(start 438.00395 -36.81095)
		(end 437.134 -36.81095)
		(width 0.17272)
		(layer "F.Cu")
		(net "SMB_P52V_SCL")
	)
	(segment
		(start 437.134 -36.81095)
		(end 437.134 -36.20135)
		(width 0.17272)
		(layer "F.Cu")
		(net "SMB_P52V_SCL")
	)
	(segment
		(start 466.639656 -107.102402)
		(end 466.639656 -106.486452)
		(width 0.17272)
		(layer "F.Cu")
		(net "SMB_P52V_SCL")
	)
	(segment
		(start 440.362594 -37.13988)
		(end 440.34202 -37.160454)
		(width 0.17272)
		(layer "F.Cu")
		(net "SMB_P52V_SCL")
	)
	(segment
		(start 438.353454 -37.160454)
		(end 438.00395 -36.81095)
		(width 0.17272)
		(layer "F.Cu")
		(net "SMB_P52V_SCL")
	)
	(via
		(at 466.639656 -106.486452)
		(size 0.508)
		(drill 0.254)
		(layers "F.Cu" "B.Cu")
		(net "SMB_P52V_SCL")
	)
	(via
		(at 437.134 -36.20135)
		(size 0.508)
		(drill 0.254)
		(layers "F.Cu" "B.Cu")
		(net "SMB_P52V_SCL")
	)
	(segment
		(start 465.3534 -88.265)
		(end 457.3778 -80.2894)
		(width 0.17272)
		(layer "B.Cu")
		(net "SMB_P52V_SCL")
	)
	(segment
		(start 451.810374 -43.556174)
		(end 449.143374 -43.556174)
		(width 0.17272)
		(layer "B.Cu")
		(net "SMB_P52V_SCL")
	)
	(segment
		(start 449.143374 -43.556174)
		(end 448.0052 -42.418)
		(width 0.17272)
		(layer "B.Cu")
		(net "SMB_P52V_SCL")
	)
	(segment
		(start 436.8038 -39.598854)
		(end 437.134 -39.268654)
		(width 0.17272)
		(layer "B.Cu")
		(net "SMB_P52V_SCL")
	)
	(segment
		(start 454.85304 -46.59884)
		(end 451.810374 -43.556174)
		(width 0.17272)
		(layer "B.Cu")
		(net "SMB_P52V_SCL")
	)
	(segment
		(start 438.404 -42.418)
		(end 436.8038 -40.8178)
		(width 0.17272)
		(layer "B.Cu")
		(net "SMB_P52V_SCL")
	)
	(segment
		(start 457.3778 -52.74945)
		(end 454.85304 -50.22469)
		(width 0.17272)
		(layer "B.Cu")
		(net "SMB_P52V_SCL")
	)
	(segment
		(start 448.0052 -42.418)
		(end 438.404 -42.418)
		(width 0.17272)
		(layer "B.Cu")
		(net "SMB_P52V_SCL")
	)
	(segment
		(start 437.134 -39.268654)
		(end 437.134 -36.20135)
		(width 0.17272)
		(layer "B.Cu")
		(net "SMB_P52V_SCL")
	)
	(segment
		(start 465.3534 -105.200196)
		(end 465.3534 -88.265)
		(width 0.17272)
		(layer "B.Cu")
		(net "SMB_P52V_SCL")
	)
	(segment
		(start 457.3778 -80.2894)
		(end 457.3778 -52.74945)
		(width 0.17272)
		(layer "B.Cu")
		(net "SMB_P52V_SCL")
	)
	(segment
		(start 436.8038 -40.8178)
		(end 436.8038 -39.598854)
		(width 0.17272)
		(layer "B.Cu")
		(net "SMB_P52V_SCL")
	)
	(segment
		(start 466.639656 -106.486452)
		(end 465.3534 -105.200196)
		(width 0.17272)
		(layer "B.Cu")
		(net "SMB_P52V_SCL")
	)
	(segment
		(start 454.85304 -50.22469)
		(end 454.85304 -46.59884)
		(width 0.17272)
		(layer "B.Cu")
		(net "SMB_P52V_SCL")
	)
	(segment
		(start 466.639656 -107.902502)
		(end 466.639656 -108.772452)
		(width 0.17272)
		(layer "F.Cu")
		(net "SMB_P52V_R_SCL")
	)
	(via
		(at 466.639656 -108.772452)
		(size 0.508)
		(drill 0.254)
		(layers "F.Cu" "B.Cu")
		(net "SMB_P52V_R_SCL")
	)
	(segment
		(start 468.345266 -110.49)
		(end 470.17559 -109.73181)
		(width 0.17272)
		(layer "B.Cu")
		(net "SMB_P52V_R_SCL")
	)
	(segment
		(start 470.17559 -109.73181)
		(end 473.583 -106.3244)
		(width 0.17272)
		(layer "B.Cu")
		(net "SMB_P52V_R_SCL")
	)
	(segment
		(start 466.6234 -109.855)
		(end 467.2584 -110.49)
		(width 0.17272)
		(layer "B.Cu")
		(net "SMB_P52V_R_SCL")
	)
	(segment
		(start 467.2584 -110.49)
		(end 468.345266 -110.49)
		(width 0.17272)
		(layer "B.Cu")
		(net "SMB_P52V_R_SCL")
	)
	(segment
		(start 472.392248 -86.160102)
		(end 470.905078 -86.160102)
		(width 0.17272)
		(layer "B.Cu")
		(net "SMB_P52V_R_SCL")
	)
	(segment
		(start 466.6234 -108.788708)
		(end 466.6234 -109.855)
		(width 0.17272)
		(layer "B.Cu")
		(net "SMB_P52V_R_SCL")
	)
	(segment
		(start 466.639656 -108.772452)
		(end 466.6234 -108.788708)
		(width 0.17272)
		(layer "B.Cu")
		(net "SMB_P52V_R_SCL")
	)
	(segment
		(start 473.583 -106.3244)
		(end 473.583 -87.350854)
		(width 0.17272)
		(layer "B.Cu")
		(net "SMB_P52V_R_SCL")
	)
	(segment
		(start 473.583 -87.350854)
		(end 472.392248 -86.160102)
		(width 0.17272)
		(layer "B.Cu")
		(net "SMB_P52V_R_SCL")
	)
	(segment
		(start 470.449656 -107.902502)
		(end 470.449656 -110.626652)
		(width 0.17272)
		(layer "F.Cu")
		(net "SMB_P52V_R_SDA")
	)
	(via
		(at 470.449656 -110.626652)
		(size 0.508)
		(drill 0.254)
		(layers "F.Cu" "B.Cu")
		(net "SMB_P52V_R_SDA")
	)
	(segment
		(start 474.218 -86.933024)
		(end 472.175078 -84.890102)
		(width 0.17272)
		(layer "B.Cu")
		(net "SMB_P52V_R_SDA")
	)
	(segment
		(start 470.449656 -110.626652)
		(end 474.218 -106.858308)
		(width 0.17272)
		(layer "B.Cu")
		(net "SMB_P52V_R_SDA")
	)
	(segment
		(start 474.218 -106.858308)
		(end 474.218 -86.933024)
		(width 0.17272)
		(layer "B.Cu")
		(net "SMB_P52V_R_SDA")
	)
	(segment
		(start 31.6484 -31.778956)
		(end 32.254444 -32.385)
		(width 0.17272)
		(layer "F.Cu")
		(net "LED_D2_R5")
	)
	(segment
		(start 33.25241 -30.607)
		(end 31.6484 -30.607)
		(width 0.17272)
		(layer "F.Cu")
		(net "LED_D2_R5")
	)
	(segment
		(start 31.6484 -30.607)
		(end 31.6484 -31.778956)
		(width 0.17272)
		(layer "F.Cu")
		(net "LED_D2_R5")
	)
	(via
		(at 31.6484 -30.607)
		(size 0.762)
		(drill 0.381)
		(layers "F.Cu" "B.Cu")
		(net "LED_D2_R5")
	)
	(segment
		(start 408.2034 -30.530546)
		(end 408.2034 -29.21)
		(width 0.17272)
		(layer "F.Cu")
		(net "LED_D1_R5")
	)
	(segment
		(start 407.745946 -30.988)
		(end 408.2034 -30.530546)
		(width 0.17272)
		(layer "F.Cu")
		(net "LED_D1_R5")
	)
	(segment
		(start 408.2034 -29.21)
		(end 406.74798 -29.21)
		(width 0.17272)
		(layer "F.Cu")
		(net "LED_D1_R5")
	)
	(via
		(at 408.2034 -29.21)
		(size 0.762)
		(drill 0.381)
		(layers "F.Cu" "B.Cu")
		(net "LED_D1_R5")
	)
	(segment
		(start 34.8234 -34.671)
		(end 35.454336 -34.671)
		(width 0.17272)
		(layer "F.Cu")
		(net "LED_D2_R4")
	)
	(segment
		(start 35.454336 -32.385)
		(end 34.6964 -32.385)
		(width 0.17272)
		(layer "F.Cu")
		(net "LED_D2_R4")
	)
	(segment
		(start 34.1884 -34.036)
		(end 34.8234 -34.671)
		(width 0.17272)
		(layer "F.Cu")
		(net "LED_D2_R4")
	)
	(segment
		(start 34.6964 -32.385)
		(end 34.1884 -32.893)
		(width 0.17272)
		(layer "F.Cu")
		(net "LED_D2_R4")
	)
	(segment
		(start 34.1884 -32.893)
		(end 34.1884 -34.036)
		(width 0.17272)
		(layer "F.Cu")
		(net "LED_D2_R4")
	)
	(via
		(at 34.1884 -34.036)
		(size 0.508)
		(drill 0.254)
		(layers "F.Cu" "B.Cu")
		(net "LED_D2_R4")
	)
	(segment
		(start 32.254444 -34.671)
		(end 31.1404 -34.671)
		(width 0.17272)
		(layer "F.Cu")
		(net "LED_D2_R3")
	)
	(segment
		(start 32.254444 -36.957)
		(end 30.69336 -36.957)
		(width 0.17272)
		(layer "F.Cu")
		(net "LED_D2_R3")
	)
	(segment
		(start 31.1404 -34.671)
		(end 30.69336 -35.11804)
		(width 0.17272)
		(layer "F.Cu")
		(net "LED_D2_R3")
	)
	(segment
		(start 30.69336 -35.11804)
		(end 30.69336 -36.957)
		(width 0.17272)
		(layer "F.Cu")
		(net "LED_D2_R3")
	)
	(via
		(at 30.69336 -36.957)
		(size 0.762)
		(drill 0.381)
		(layers "F.Cu" "B.Cu")
		(net "LED_D2_R3")
	)
	(segment
		(start 280.67635 -72.39)
		(end 278.89835 -72.39)
		(width 0.17272)
		(layer "F.Cu")
		(net "P52V_HS1_ADR1")
	)
	(segment
		(start 280.67635 -72.62495)
		(end 281.4574 -73.406)
		(width 0.17272)
		(layer "F.Cu")
		(net "P52V_HS1_ADR1")
	)
	(segment
		(start 278.89835 -72.39)
		(end 278.26335 -73.025)
		(width 0.17272)
		(layer "F.Cu")
		(net "P52V_HS1_ADR1")
	)
	(segment
		(start 278.26335 -73.025)
		(end 278.26335 -70.21195)
		(width 0.17272)
		(layer "F.Cu")
		(net "P52V_HS1_ADR1")
	)
	(segment
		(start 280.67635 -72.39)
		(end 280.67635 -72.62495)
		(width 0.17272)
		(layer "F.Cu")
		(net "P52V_HS1_ADR1")
	)
	(segment
		(start 276.8981 -68.8467)
		(end 275.7424 -68.8467)
		(width 0.17272)
		(layer "F.Cu")
		(net "P52V_HS1_ADR1")
	)
	(segment
		(start 278.26335 -70.21195)
		(end 276.8981 -68.8467)
		(width 0.17272)
		(layer "F.Cu")
		(net "P52V_HS1_ADR1")
	)
	(via
		(at 275.7424 -68.8467)
		(size 0.508)
		(drill 0.254)
		(layers "F.Cu" "B.Cu")
		(net "P52V_HS1_ADR1")
	)
	(via
		(at 290.9824 -65.405)
		(size 0.762)
		(drill 0.254)
		(layers "F.Cu" "B.Cu")
		(net "P52V_HS1_ADR1")
	)
	(via
		(at 281.4574 -73.406)
		(size 0.508)
		(drill 0.254)
		(layers "F.Cu" "B.Cu")
		(net "P52V_HS1_ADR1")
	)
	(segment
		(start 274.1041 -68.8467)
		(end 275.7424 -68.8467)
		(width 0.17272)
		(layer "B.Cu")
		(net "P52V_HS1_ADR1")
	)
	(segment
		(start 291.272468 -66.703956)
		(end 291.272468 -65.695068)
		(width 0.17272)
		(layer "B.Cu")
		(net "P52V_HS1_ADR1")
	)
	(segment
		(start 290.9824 -63.39205)
		(end 290.905946 -63.39205)
		(width 0.17272)
		(layer "B.Cu")
		(net "P52V_HS1_ADR1")
	)
	(segment
		(start 291.272468 -65.695068)
		(end 290.9824 -65.405)
		(width 0.17272)
		(layer "B.Cu")
		(net "P52V_HS1_ADR1")
	)
	(segment
		(start 290.905946 -63.39205)
		(end 290.36264 -62.848744)
		(width 0.17272)
		(layer "B.Cu")
		(net "P52V_HS1_ADR1")
	)
	(segment
		(start 290.36264 -61.85281)
		(end 290.9824 -61.23305)
		(width 0.17272)
		(layer "B.Cu")
		(net "P52V_HS1_ADR1")
	)
	(segment
		(start 290.9824 -63.39205)
		(end 290.9824 -65.405)
		(width 0.17272)
		(layer "B.Cu")
		(net "P52V_HS1_ADR1")
	)
	(segment
		(start 290.36264 -62.848744)
		(end 290.36264 -61.85281)
		(width 0.17272)
		(layer "B.Cu")
		(net "P52V_HS1_ADR1")
	)
	(segment
		(start 283.3878 -72.4154)
		(end 282.3972 -73.406)
		(width 0.12954)
		(layer "In2.Cu")
		(net "P52V_HS1_ADR1")
	)
	(segment
		(start 289.9918 -71.247)
		(end 288.8234 -72.4154)
		(width 0.12954)
		(layer "In2.Cu")
		(net "P52V_HS1_ADR1")
	)
	(segment
		(start 288.8234 -72.4154)
		(end 283.3878 -72.4154)
		(width 0.12954)
		(layer "In2.Cu")
		(net "P52V_HS1_ADR1")
	)
	(segment
		(start 289.9918 -66.3956)
		(end 289.9918 -71.247)
		(width 0.12954)
		(layer "In2.Cu")
		(net "P52V_HS1_ADR1")
	)
	(segment
		(start 290.9824 -65.405)
		(end 289.9918 -66.3956)
		(width 0.12954)
		(layer "In2.Cu")
		(net "P52V_HS1_ADR1")
	)
	(segment
		(start 282.3972 -73.406)
		(end 281.4574 -73.406)
		(width 0.12954)
		(layer "In2.Cu")
		(net "P52V_HS1_ADR1")
	)
	(segment
		(start 34.1884 -38.1)
		(end 34.1884 -37.338)
		(width 0.17272)
		(layer "F.Cu")
		(net "LED_D2_R2")
	)
	(segment
		(start 34.5694 -36.957)
		(end 35.454336 -36.957)
		(width 0.17272)
		(layer "F.Cu")
		(net "LED_D2_R2")
	)
	(segment
		(start 34.1884 -38.735)
		(end 34.1884 -38.1)
		(width 0.17272)
		(layer "F.Cu")
		(net "LED_D2_R2")
	)
	(segment
		(start 34.1884 -37.338)
		(end 34.5694 -36.957)
		(width 0.17272)
		(layer "F.Cu")
		(net "LED_D2_R2")
	)
	(segment
		(start 34.6964 -39.243)
		(end 34.1884 -38.735)
		(width 0.17272)
		(layer "F.Cu")
		(net "LED_D2_R2")
	)
	(segment
		(start 35.454336 -39.243)
		(end 34.6964 -39.243)
		(width 0.17272)
		(layer "F.Cu")
		(net "LED_D2_R2")
	)
	(via
		(at 34.1884 -38.1)
		(size 0.508)
		(drill 0.254)
		(layers "F.Cu" "B.Cu")
		(net "LED_D2_R2")
	)
	(segment
		(start 30.7594 -39.624)
		(end 30.7594 -41.529)
		(width 0.17272)
		(layer "F.Cu")
		(net "LED_D2_R1")
	)
	(segment
		(start 32.254444 -41.529)
		(end 30.7594 -41.529)
		(width 0.17272)
		(layer "F.Cu")
		(net "LED_D2_R1")
	)
	(segment
		(start 31.1404 -39.243)
		(end 30.7594 -39.624)
		(width 0.17272)
		(layer "F.Cu")
		(net "LED_D2_R1")
	)
	(segment
		(start 32.254444 -39.243)
		(end 31.1404 -39.243)
		(width 0.17272)
		(layer "F.Cu")
		(net "LED_D2_R1")
	)
	(via
		(at 30.7594 -41.529)
		(size 0.762)
		(drill 0.381)
		(layers "F.Cu" "B.Cu")
		(net "LED_D2_R1")
	)
	(segment
		(start 405.2824 -33.274)
		(end 405.6634 -32.893)
		(width 0.17272)
		(layer "F.Cu")
		(net "LED_D1_R4")
	)
	(segment
		(start 405.6634 -32.893)
		(end 405.6634 -32.004)
		(width 0.17272)
		(layer "F.Cu")
		(net "LED_D1_R4")
	)
	(segment
		(start 404.546054 -33.274)
		(end 405.2824 -33.274)
		(width 0.17272)
		(layer "F.Cu")
		(net "LED_D1_R4")
	)
	(segment
		(start 405.282654 -30.988)
		(end 404.546054 -30.988)
		(width 0.17272)
		(layer "F.Cu")
		(net "LED_D1_R4")
	)
	(segment
		(start 405.6634 -32.004)
		(end 405.6634 -31.368746)
		(width 0.17272)
		(layer "F.Cu")
		(net "LED_D1_R4")
	)
	(segment
		(start 405.6634 -31.368746)
		(end 405.282654 -30.988)
		(width 0.17272)
		(layer "F.Cu")
		(net "LED_D1_R4")
	)
	(via
		(at 405.6634 -32.004)
		(size 0.508)
		(drill 0.254)
		(layers "F.Cu" "B.Cu")
		(net "LED_D1_R4")
	)
	(segment
		(start 408.8384 -35.56)
		(end 409.2194 -35.179)
		(width 0.17272)
		(layer "F.Cu")
		(net "LED_D1_R3")
	)
	(segment
		(start 409.2194 -35.179)
		(end 409.2194 -33.782254)
		(width 0.17272)
		(layer "F.Cu")
		(net "LED_D1_R3")
	)
	(segment
		(start 408.711146 -33.274)
		(end 407.745946 -33.274)
		(width 0.17272)
		(layer "F.Cu")
		(net "LED_D1_R3")
	)
	(segment
		(start 409.2194 -33.782254)
		(end 408.711146 -33.274)
		(width 0.17272)
		(layer "F.Cu")
		(net "LED_D1_R3")
	)
	(segment
		(start 407.745946 -35.56)
		(end 408.8384 -35.56)
		(width 0.17272)
		(layer "F.Cu")
		(net "LED_D1_R3")
	)
	(via
		(at 409.2194 -35.179)
		(size 0.762)
		(drill 0.381)
		(layers "F.Cu" "B.Cu")
		(net "LED_D1_R3")
	)
	(segment
		(start 404.546054 -35.56)
		(end 405.2824 -35.56)
		(width 0.17272)
		(layer "F.Cu")
		(net "LED_D1_R2")
	)
	(segment
		(start 405.6634 -37.465254)
		(end 405.282654 -37.846)
		(width 0.17272)
		(layer "F.Cu")
		(net "LED_D1_R2")
	)
	(segment
		(start 405.2824 -35.56)
		(end 405.6634 -35.941)
		(width 0.17272)
		(layer "F.Cu")
		(net "LED_D1_R2")
	)
	(segment
		(start 405.282654 -37.846)
		(end 404.546054 -37.846)
		(width 0.17272)
		(layer "F.Cu")
		(net "LED_D1_R2")
	)
	(segment
		(start 405.6634 -35.941)
		(end 405.6634 -36.83)
		(width 0.17272)
		(layer "F.Cu")
		(net "LED_D1_R2")
	)
	(segment
		(start 405.6634 -36.83)
		(end 405.6634 -37.465254)
		(width 0.17272)
		(layer "F.Cu")
		(net "LED_D1_R2")
	)
	(via
		(at 405.6634 -36.83)
		(size 0.508)
		(drill 0.254)
		(layers "F.Cu" "B.Cu")
		(net "LED_D1_R2")
	)
	(segment
		(start 407.745946 -37.846)
		(end 408.9654 -37.846)
		(width 0.17272)
		(layer "F.Cu")
		(net "LED_D1_R1")
	)
	(segment
		(start 408.9654 -40.132)
		(end 407.745946 -40.132)
		(width 0.17272)
		(layer "F.Cu")
		(net "LED_D1_R1")
	)
	(segment
		(start 409.4734 -38.354)
		(end 409.4734 -39.116)
		(width 0.17272)
		(layer "F.Cu")
		(net "LED_D1_R1")
	)
	(segment
		(start 409.4734 -39.116)
		(end 409.4734 -39.624)
		(width 0.17272)
		(layer "F.Cu")
		(net "LED_D1_R1")
	)
	(segment
		(start 409.4734 -39.624)
		(end 408.9654 -40.132)
		(width 0.17272)
		(layer "F.Cu")
		(net "LED_D1_R1")
	)
	(segment
		(start 408.9654 -37.846)
		(end 409.4734 -38.354)
		(width 0.17272)
		(layer "F.Cu")
		(net "LED_D1_R1")
	)
	(via
		(at 409.4734 -39.116)
		(size 0.762)
		(drill 0.381)
		(layers "F.Cu" "B.Cu")
		(net "LED_D1_R1")
	)
	(segment
		(start 438.5564 -42.799)
		(end 437.15305 -42.799)
		(width 0.17272)
		(layer "F.Cu")
		(net "MB_MISC_I2C_EN")
	)
	(segment
		(start 438.5564 -42.798746)
		(end 438.5564 -42.799)
		(width 0.17272)
		(layer "F.Cu")
		(net "MB_MISC_I2C_EN")
	)
	(segment
		(start 440.362594 -42.377106)
		(end 438.97804 -42.377106)
		(width 0.17272)
		(layer "F.Cu")
		(net "MB_MISC_I2C_EN")
	)
	(segment
		(start 438.97804 -42.377106)
		(end 438.5564 -42.798746)
		(width 0.17272)
		(layer "F.Cu")
		(net "MB_MISC_I2C_EN")
	)
	(via
		(at 438.5564 -42.799)
		(size 0.762)
		(drill 0.381)
		(layers "F.Cu" "B.Cu")
		(net "MB_MISC_I2C_EN")
	)
	(segment
		(start 469.179656 -107.102402)
		(end 469.179656 -106.486452)
		(width 0.17272)
		(layer "F.Cu")
		(net "SMB_PDB_SDA")
	)
	(segment
		(start 447.440304 -40.74795)
		(end 447.111374 -41.07688)
		(width 0.17272)
		(layer "F.Cu")
		(net "SMB_PDB_SDA")
	)
	(segment
		(start 448.056 -40.74795)
		(end 448.056 -40.13835)
		(width 0.17272)
		(layer "F.Cu")
		(net "SMB_PDB_SDA")
	)
	(segment
		(start 447.111374 -41.07688)
		(end 444.827406 -41.07688)
		(width 0.17272)
		(layer "F.Cu")
		(net "SMB_PDB_SDA")
	)
	(segment
		(start 448.056 -40.74795)
		(end 447.440304 -40.74795)
		(width 0.17272)
		(layer "F.Cu")
		(net "SMB_PDB_SDA")
	)
	(via
		(at 469.179656 -106.486452)
		(size 0.508)
		(drill 0.254)
		(layers "F.Cu" "B.Cu")
		(net "SMB_PDB_SDA")
	)
	(via
		(at 448.056 -40.13835)
		(size 0.508)
		(drill 0.254)
		(layers "F.Cu" "B.Cu")
		(net "SMB_PDB_SDA")
	)
	(segment
		(start 448.93865 -41.021)
		(end 448.056 -40.13835)
		(width 0.17272)
		(layer "B.Cu")
		(net "SMB_PDB_SDA")
	)
	(segment
		(start 456.01128 -46.11878)
		(end 450.9135 -41.021)
		(width 0.17272)
		(layer "B.Cu")
		(net "SMB_PDB_SDA")
	)
	(segment
		(start 450.9135 -41.021)
		(end 448.93865 -41.021)
		(width 0.17272)
		(layer "B.Cu")
		(net "SMB_PDB_SDA")
	)
	(segment
		(start 466.51164 -87.78494)
		(end 458.53604 -79.80934)
		(width 0.17272)
		(layer "B.Cu")
		(net "SMB_PDB_SDA")
	)
	(segment
		(start 469.179656 -105.451656)
		(end 466.51164 -102.78364)
		(width 0.17272)
		(layer "B.Cu")
		(net "SMB_PDB_SDA")
	)
	(segment
		(start 466.51164 -102.78364)
		(end 466.51164 -87.78494)
		(width 0.17272)
		(layer "B.Cu")
		(net "SMB_PDB_SDA")
	)
	(segment
		(start 469.179656 -106.486452)
		(end 469.179656 -105.451656)
		(width 0.17272)
		(layer "B.Cu")
		(net "SMB_PDB_SDA")
	)
	(segment
		(start 458.53604 -52.26939)
		(end 456.01128 -49.74463)
		(width 0.17272)
		(layer "B.Cu")
		(net "SMB_PDB_SDA")
	)
	(segment
		(start 456.01128 -49.74463)
		(end 456.01128 -46.11878)
		(width 0.17272)
		(layer "B.Cu")
		(net "SMB_PDB_SDA")
	)
	(segment
		(start 458.53604 -79.80934)
		(end 458.53604 -52.26939)
		(width 0.17272)
		(layer "B.Cu")
		(net "SMB_PDB_SDA")
	)
	(segment
		(start 440.362594 -41.07688)
		(end 438.33288 -41.07688)
		(width 0.17272)
		(layer "F.Cu")
		(net "SMB_PDB_SCL")
	)
	(segment
		(start 437.134 -40.74795)
		(end 437.134 -40.13835)
		(width 0.17272)
		(layer "F.Cu")
		(net "SMB_PDB_SCL")
	)
	(segment
		(start 467.909656 -107.102402)
		(end 467.909656 -106.486452)
		(width 0.17272)
		(layer "F.Cu")
		(net "SMB_PDB_SCL")
	)
	(segment
		(start 438.33288 -41.07688)
		(end 438.00395 -40.74795)
		(width 0.17272)
		(layer "F.Cu")
		(net "SMB_PDB_SCL")
	)
	(segment
		(start 438.00395 -40.74795)
		(end 437.134 -40.74795)
		(width 0.17272)
		(layer "F.Cu")
		(net "SMB_PDB_SCL")
	)
	(segment
		(start 437.134 -40.13835)
		(end 437.404002 -39.868348)
		(width 0.17272)
		(layer "F.Cu")
		(net "SMB_PDB_SCL")
	)
	(via
		(at 437.404002 -39.868348)
		(size 0.508)
		(drill 0.254)
		(layers "F.Cu" "B.Cu")
		(net "SMB_PDB_SCL")
	)
	(via
		(at 467.909656 -106.486452)
		(size 0.508)
		(drill 0.254)
		(layers "F.Cu" "B.Cu")
		(net "SMB_PDB_SCL")
	)
	(segment
		(start 457.95692 -52.50942)
		(end 457.95692 -80.04937)
		(width 0.17272)
		(layer "B.Cu")
		(net "SMB_PDB_SCL")
	)
	(segment
		(start 437.404002 -39.868348)
		(end 438.607454 -41.0718)
		(width 0.17272)
		(layer "B.Cu")
		(net "SMB_PDB_SCL")
	)
	(segment
		(start 450.72935 -41.656)
		(end 455.43216 -46.35881)
		(width 0.17272)
		(layer "B.Cu")
		(net "SMB_PDB_SCL")
	)
	(segment
		(start 455.43216 -46.35881)
		(end 455.43216 -49.98466)
		(width 0.17272)
		(layer "B.Cu")
		(net "SMB_PDB_SCL")
	)
	(segment
		(start 465.93252 -104.509316)
		(end 467.909656 -106.486452)
		(width 0.17272)
		(layer "B.Cu")
		(net "SMB_PDB_SCL")
	)
	(segment
		(start 447.192654 -41.0718)
		(end 447.776854 -41.656)
		(width 0.17272)
		(layer "B.Cu")
		(net "SMB_PDB_SCL")
	)
	(segment
		(start 447.776854 -41.656)
		(end 450.72935 -41.656)
		(width 0.17272)
		(layer "B.Cu")
		(net "SMB_PDB_SCL")
	)
	(segment
		(start 455.43216 -49.98466)
		(end 457.95692 -52.50942)
		(width 0.17272)
		(layer "B.Cu")
		(net "SMB_PDB_SCL")
	)
	(segment
		(start 457.95692 -80.04937)
		(end 465.93252 -88.02497)
		(width 0.17272)
		(layer "B.Cu")
		(net "SMB_PDB_SCL")
	)
	(segment
		(start 438.607454 -41.0718)
		(end 447.192654 -41.0718)
		(width 0.17272)
		(layer "B.Cu")
		(net "SMB_PDB_SCL")
	)
	(segment
		(start 465.93252 -88.02497)
		(end 465.93252 -104.509316)
		(width 0.17272)
		(layer "B.Cu")
		(net "SMB_PDB_SCL")
	)
	(segment
		(start 469.179656 -109.364272)
		(end 469.179656 -107.902502)
		(width 0.17272)
		(layer "F.Cu")
		(net "SMB_PDB_R_SDA")
	)
	(via
		(at 469.179656 -109.364272)
		(size 0.508)
		(drill 0.254)
		(layers "F.Cu" "B.Cu")
		(net "SMB_PDB_R_SDA")
	)
	(segment
		(start 469.84412 -101.861874)
		(end 469.6714 -102.034594)
		(width 0.17272)
		(layer "B.Cu")
		(net "SMB_PDB_R_SDA")
	)
	(segment
		(start 469.84412 -100.449634)
		(end 469.6714 -100.622354)
		(width 0.17272)
		(layer "B.Cu")
		(net "SMB_PDB_R_SDA")
	)
	(segment
		(start 472.175078 -87.430102)
		(end 472.175078 -88.82761)
		(width 0.17272)
		(layer "B.Cu")
		(net "SMB_PDB_R_SDA")
	)
	(segment
		(start 469.84412 -101.155754)
		(end 471.729054 -101.155754)
		(width 0.17272)
		(layer "B.Cu")
		(net "SMB_PDB_R_SDA")
	)
	(segment
		(start 471.729054 -101.155754)
		(end 471.901774 -101.328474)
		(width 0.17272)
		(layer "B.Cu")
		(net "SMB_PDB_R_SDA")
	)
	(segment
		(start 471.314526 -89.688162)
		(end 470.534238 -89.688162)
		(width 0.17272)
		(layer "B.Cu")
		(net "SMB_PDB_R_SDA")
	)
	(segment
		(start 471.901774 -99.916234)
		(end 471.901774 -100.276914)
		(width 0.17272)
		(layer "B.Cu")
		(net "SMB_PDB_R_SDA")
	)
	(segment
		(start 471.729054 -99.743514)
		(end 471.901774 -99.916234)
		(width 0.17272)
		(layer "B.Cu")
		(net "SMB_PDB_R_SDA")
	)
	(segment
		(start 469.6714 -100.983034)
		(end 469.84412 -101.155754)
		(width 0.17272)
		(layer "B.Cu")
		(net "SMB_PDB_R_SDA")
	)
	(segment
		(start 470.534238 -89.688162)
		(end 469.6714 -90.551)
		(width 0.17272)
		(layer "B.Cu")
		(net "SMB_PDB_R_SDA")
	)
	(segment
		(start 471.901774 -100.276914)
		(end 471.729054 -100.449634)
		(width 0.17272)
		(layer "B.Cu")
		(net "SMB_PDB_R_SDA")
	)
	(segment
		(start 472.0844 -105.283)
		(end 472.0844 -106.459528)
		(width 0.17272)
		(layer "B.Cu")
		(net "SMB_PDB_R_SDA")
	)
	(segment
		(start 469.6714 -100.622354)
		(end 469.6714 -100.983034)
		(width 0.17272)
		(layer "B.Cu")
		(net "SMB_PDB_R_SDA")
	)
	(segment
		(start 469.6714 -90.551)
		(end 469.6714 -99.570794)
		(width 0.17272)
		(layer "B.Cu")
		(net "SMB_PDB_R_SDA")
	)
	(segment
		(start 472.0844 -106.459528)
		(end 469.179656 -109.364272)
		(width 0.17272)
		(layer "B.Cu")
		(net "SMB_PDB_R_SDA")
	)
	(segment
		(start 471.729054 -100.449634)
		(end 469.84412 -100.449634)
		(width 0.17272)
		(layer "B.Cu")
		(net "SMB_PDB_R_SDA")
	)
	(segment
		(start 469.6714 -102.034594)
		(end 469.6714 -102.87)
		(width 0.17272)
		(layer "B.Cu")
		(net "SMB_PDB_R_SDA")
	)
	(segment
		(start 471.729054 -101.861874)
		(end 469.84412 -101.861874)
		(width 0.17272)
		(layer "B.Cu")
		(net "SMB_PDB_R_SDA")
	)
	(segment
		(start 471.901774 -101.689154)
		(end 471.729054 -101.861874)
		(width 0.17272)
		(layer "B.Cu")
		(net "SMB_PDB_R_SDA")
	)
	(segment
		(start 469.6714 -102.87)
		(end 472.0844 -105.283)
		(width 0.17272)
		(layer "B.Cu")
		(net "SMB_PDB_R_SDA")
	)
	(segment
		(start 471.901774 -101.328474)
		(end 471.901774 -101.689154)
		(width 0.17272)
		(layer "B.Cu")
		(net "SMB_PDB_R_SDA")
	)
	(segment
		(start 469.6714 -99.570794)
		(end 469.84412 -99.743514)
		(width 0.17272)
		(layer "B.Cu")
		(net "SMB_PDB_R_SDA")
	)
	(segment
		(start 472.175078 -88.82761)
		(end 471.314526 -89.688162)
		(width 0.17272)
		(layer "B.Cu")
		(net "SMB_PDB_R_SDA")
	)
	(segment
		(start 469.84412 -99.743514)
		(end 471.729054 -99.743514)
		(width 0.17272)
		(layer "B.Cu")
		(net "SMB_PDB_R_SDA")
	)
	(segment
		(start 467.909656 -107.902502)
		(end 467.909656 -109.813852)
		(width 0.17272)
		(layer "F.Cu")
		(net "SMB_PDB_R_SCL")
	)
	(via
		(at 467.909656 -109.813852)
		(size 0.508)
		(drill 0.254)
		(layers "F.Cu" "B.Cu")
		(net "SMB_PDB_R_SCL")
	)
	(segment
		(start 470.905078 -88.700102)
		(end 470.703148 -88.700102)
		(width 0.17272)
		(layer "B.Cu")
		(net "SMB_PDB_R_SCL")
	)
	(segment
		(start 469.09228 -103.11003)
		(end 471.50528 -105.52303)
		(width 0.17272)
		(layer "B.Cu")
		(net "SMB_PDB_R_SCL")
	)
	(segment
		(start 470.703148 -88.700102)
		(end 469.09228 -90.31097)
		(width 0.17272)
		(layer "B.Cu")
		(net "SMB_PDB_R_SCL")
	)
	(segment
		(start 471.50528 -105.52303)
		(end 471.50528 -106.219498)
		(width 0.17272)
		(layer "B.Cu")
		(net "SMB_PDB_R_SCL")
	)
	(segment
		(start 469.09228 -90.31097)
		(end 469.09228 -103.11003)
		(width 0.17272)
		(layer "B.Cu")
		(net "SMB_PDB_R_SCL")
	)
	(segment
		(start 467.910926 -109.813852)
		(end 467.909656 -109.813852)
		(width 0.17272)
		(layer "B.Cu")
		(net "SMB_PDB_R_SCL")
	)
	(segment
		(start 471.50528 -106.219498)
		(end 467.910926 -109.813852)
		(width 0.17272)
		(layer "B.Cu")
		(net "SMB_PDB_R_SCL")
	)
	(segment
		(start 380.803912 -18.307304)
		(end 380.803912 -18.923)
		(width 0.17272)
		(layer "F.Cu")
		(net "RST_SMB_PDB_BUF_N")
	)
	(segment
		(start 439.9534 -31.623)
		(end 441.452 -31.623)
		(width 0.17272)
		(layer "F.Cu")
		(net "RST_SMB_PDB_BUF_N")
	)
	(segment
		(start 83.947 -18.30705)
		(end 83.947 -18.916904)
		(width 0.17272)
		(layer "F.Cu")
		(net "RST_SMB_PDB_BUF_N")
	)
	(via
		(at 441.452 -31.623)
		(size 0.508)
		(drill 0.254)
		(layers "F.Cu" "B.Cu")
		(net "RST_SMB_PDB_BUF_N")
	)
	(via
		(at 380.803912 -18.923)
		(size 0.508)
		(drill 0.254)
		(layers "F.Cu" "B.Cu")
		(net "RST_SMB_PDB_BUF_N")
	)
	(via
		(at 83.947 -18.916904)
		(size 0.508)
		(drill 0.254)
		(layers "F.Cu" "B.Cu")
		(net "RST_SMB_PDB_BUF_N")
	)
	(segment
		(start 451.002146 -25.146)
		(end 452.12 -26.263854)
		(width 0.17272)
		(layer "B.Cu")
		(net "RST_SMB_PDB_BUF_N")
	)
	(segment
		(start 452.12 -26.263854)
		(end 452.12 -32.131)
		(width 0.17272)
		(layer "B.Cu")
		(net "RST_SMB_PDB_BUF_N")
	)
	(segment
		(start 452.12 -32.131)
		(end 458.63764 -38.64864)
		(width 0.17272)
		(layer "B.Cu")
		(net "RST_SMB_PDB_BUF_N")
	)
	(segment
		(start 466.423248 -81.080102)
		(end 468.365078 -81.080102)
		(width 0.17272)
		(layer "B.Cu")
		(net "RST_SMB_PDB_BUF_N")
	)
	(segment
		(start 461.9244 -76.581254)
		(end 466.423248 -81.080102)
		(width 0.17272)
		(layer "B.Cu")
		(net "RST_SMB_PDB_BUF_N")
	)
	(segment
		(start 461.9244 -50.545746)
		(end 461.9244 -76.581254)
		(width 0.17272)
		(layer "B.Cu")
		(net "RST_SMB_PDB_BUF_N")
	)
	(segment
		(start 441.452 -31.623)
		(end 447.929 -25.146)
		(width 0.17272)
		(layer "B.Cu")
		(net "RST_SMB_PDB_BUF_N")
	)
	(segment
		(start 447.929 -25.146)
		(end 451.002146 -25.146)
		(width 0.17272)
		(layer "B.Cu")
		(net "RST_SMB_PDB_BUF_N")
	)
	(segment
		(start 458.63764 -47.258986)
		(end 461.9244 -50.545746)
		(width 0.17272)
		(layer "B.Cu")
		(net "RST_SMB_PDB_BUF_N")
	)
	(segment
		(start 458.63764 -38.64864)
		(end 458.63764 -47.258986)
		(width 0.17272)
		(layer "B.Cu")
		(net "RST_SMB_PDB_BUF_N")
	)
	(segment
		(start 354.728272 -8.382)
		(end 350.38538 -4.039108)
		(width 0.12954)
		(layer "In2.Cu")
		(net "RST_SMB_PDB_BUF_N")
	)
	(segment
		(start 373.507 -8.382)
		(end 354.728272 -8.382)
		(width 0.12954)
		(layer "In2.Cu")
		(net "RST_SMB_PDB_BUF_N")
	)
	(segment
		(start 378.714 -18.923)
		(end 377.648978 -17.857978)
		(width 0.12954)
		(layer "In2.Cu")
		(net "RST_SMB_PDB_BUF_N")
	)
	(segment
		(start 437.287162 -21.209)
		(end 427.99 -21.209)
		(width 0.12954)
		(layer "In2.Cu")
		(net "RST_SMB_PDB_BUF_N")
	)
	(segment
		(start 380.803912 -18.923)
		(end 378.714 -18.923)
		(width 0.12954)
		(layer "In2.Cu")
		(net "RST_SMB_PDB_BUF_N")
	)
	(segment
		(start 377.648978 -17.857978)
		(end 377.648978 -12.523978)
		(width 0.12954)
		(layer "In2.Cu")
		(net "RST_SMB_PDB_BUF_N")
	)
	(segment
		(start 381.397764 -9.127236)
		(end 381.397764 -16.950436)
		(width 0.12954)
		(layer "In2.Cu")
		(net "RST_SMB_PDB_BUF_N")
	)
	(segment
		(start 380.803912 -17.544288)
		(end 380.803912 -18.923)
		(width 0.12954)
		(layer "In2.Cu")
		(net "RST_SMB_PDB_BUF_N")
	)
	(segment
		(start 411.734 -4.953)
		(end 385.572 -4.953)
		(width 0.12954)
		(layer "In2.Cu")
		(net "RST_SMB_PDB_BUF_N")
	)
	(segment
		(start 427.99 -21.209)
		(end 411.734 -4.953)
		(width 0.12954)
		(layer "In2.Cu")
		(net "RST_SMB_PDB_BUF_N")
	)
	(segment
		(start 377.648978 -12.523978)
		(end 373.507 -8.382)
		(width 0.12954)
		(layer "In2.Cu")
		(net "RST_SMB_PDB_BUF_N")
	)
	(segment
		(start 441.452 -31.623)
		(end 441.452 -25.373838)
		(width 0.12954)
		(layer "In2.Cu")
		(net "RST_SMB_PDB_BUF_N")
	)
	(segment
		(start 90.167206 -18.916904)
		(end 83.947 -18.916904)
		(width 0.12954)
		(layer "In2.Cu")
		(net "RST_SMB_PDB_BUF_N")
	)
	(segment
		(start 441.452 -25.373838)
		(end 437.287162 -21.209)
		(width 0.12954)
		(layer "In2.Cu")
		(net "RST_SMB_PDB_BUF_N")
	)
	(segment
		(start 381.397764 -16.950436)
		(end 380.803912 -17.544288)
		(width 0.12954)
		(layer "In2.Cu")
		(net "RST_SMB_PDB_BUF_N")
	)
	(segment
		(start 350.38538 -4.039108)
		(end 105.045002 -4.039108)
		(width 0.12954)
		(layer "In2.Cu")
		(net "RST_SMB_PDB_BUF_N")
	)
	(segment
		(start 105.045002 -4.039108)
		(end 90.167206 -18.916904)
		(width 0.12954)
		(layer "In2.Cu")
		(net "RST_SMB_PDB_BUF_N")
	)
	(segment
		(start 385.572 -4.953)
		(end 381.397764 -9.127236)
		(width 0.12954)
		(layer "In2.Cu")
		(net "RST_SMB_PDB_BUF_N")
	)
	(segment
		(start 178.149758 -52.368704)
		(end 174.483014 -48.70196)
		(width 0.17272)
		(layer "F.Cu")
		(net "GPU_HSC_BUF_EN")
	)
	(segment
		(start 188.37402 -64.512444)
		(end 186.401456 -62.53988)
		(width 0.17272)
		(layer "F.Cu")
		(net "GPU_HSC_BUF_EN")
	)
	(segment
		(start 186.401456 -62.53988)
		(end 184.43067 -62.53988)
		(width 0.17272)
		(layer "F.Cu")
		(net "GPU_HSC_BUF_EN")
	)
	(segment
		(start 184.656984 -83.334098)
		(end 188.37402 -79.617062)
		(width 0.17272)
		(layer "F.Cu")
		(net "GPU_HSC_BUF_EN")
	)
	(segment
		(start 178.149758 -52.909216)
		(end 178.149758 -52.368704)
		(width 0.17272)
		(layer "F.Cu")
		(net "GPU_HSC_BUF_EN")
	)
	(segment
		(start 266.91336 -50.148998)
		(end 265.979402 -50.148998)
		(width 0.17272)
		(layer "F.Cu")
		(net "GPU_HSC_BUF_EN")
	)
	(segment
		(start 181.398164 -54.502558)
		(end 180.152294 -53.256688)
		(width 0.17272)
		(layer "F.Cu")
		(net "GPU_HSC_BUF_EN")
	)
	(segment
		(start 450.2404 -45.0342)
		(end 449.63715 -45.0342)
		(width 0.17272)
		(layer "F.Cu")
		(net "GPU_HSC_BUF_EN")
	)
	(segment
		(start 182.735982 -83.334098)
		(end 184.656984 -83.334098)
		(width 0.17272)
		(layer "F.Cu")
		(net "GPU_HSC_BUF_EN")
	)
	(segment
		(start 178.49723 -53.256688)
		(end 178.149758 -52.909216)
		(width 0.17272)
		(layer "F.Cu")
		(net "GPU_HSC_BUF_EN")
	)
	(segment
		(start 449.63715 -45.0342)
		(end 448.79895 -44.196)
		(width 0.17272)
		(layer "F.Cu")
		(net "GPU_HSC_BUF_EN")
	)
	(segment
		(start 174.483014 -48.70196)
		(end 173.269402 -48.70196)
		(width 0.17272)
		(layer "F.Cu")
		(net "GPU_HSC_BUF_EN")
	)
	(segment
		(start 188.37402 -79.617062)
		(end 188.37402 -64.512444)
		(width 0.17272)
		(layer "F.Cu")
		(net "GPU_HSC_BUF_EN")
	)
	(segment
		(start 180.152294 -53.256688)
		(end 178.49723 -53.256688)
		(width 0.17272)
		(layer "F.Cu")
		(net "GPU_HSC_BUF_EN")
	)
	(segment
		(start 184.43067 -62.53988)
		(end 181.398164 -59.507374)
		(width 0.17272)
		(layer "F.Cu")
		(net "GPU_HSC_BUF_EN")
	)
	(segment
		(start 448.79895 -44.196)
		(end 447.82105 -44.196)
		(width 0.17272)
		(layer "F.Cu")
		(net "GPU_HSC_BUF_EN")
	)
	(segment
		(start 181.398164 -59.507374)
		(end 181.398164 -54.502558)
		(width 0.17272)
		(layer "F.Cu")
		(net "GPU_HSC_BUF_EN")
	)
	(via
		(at 265.979402 -50.148998)
		(size 0.508)
		(drill 0.254)
		(layers "F.Cu" "B.Cu")
		(net "GPU_HSC_BUF_EN")
	)
	(via
		(at 259.966968 -88.034622)
		(size 0.508)
		(drill 0.254)
		(layers "F.Cu" "B.Cu")
		(net "GPU_HSC_BUF_EN")
	)
	(via
		(at 182.735982 -83.334098)
		(size 0.508)
		(drill 0.254)
		(layers "F.Cu" "B.Cu")
		(net "GPU_HSC_BUF_EN")
	)
	(via
		(at 450.2404 -45.0342)
		(size 0.508)
		(drill 0.254)
		(layers "F.Cu" "B.Cu")
		(net "GPU_HSC_BUF_EN")
	)
	(segment
		(start 259.36448 -87.432134)
		(end 259.966968 -88.034622)
		(width 0.17272)
		(layer "B.Cu")
		(net "GPU_HSC_BUF_EN")
	)
	(segment
		(start 263.4234 -52.705)
		(end 263.4234 -55.372)
		(width 0.17272)
		(layer "B.Cu")
		(net "GPU_HSC_BUF_EN")
	)
	(segment
		(start 259.36448 -59.43092)
		(end 259.36448 -87.432134)
		(width 0.17272)
		(layer "B.Cu")
		(net "GPU_HSC_BUF_EN")
	)
	(segment
		(start 263.4234 -55.372)
		(end 259.36448 -59.43092)
		(width 0.17272)
		(layer "B.Cu")
		(net "GPU_HSC_BUF_EN")
	)
	(segment
		(start 265.979402 -50.148998)
		(end 263.4234 -52.705)
		(width 0.17272)
		(layer "B.Cu")
		(net "GPU_HSC_BUF_EN")
	)
	(segment
		(start 401.407376 -64.809624)
		(end 377.480576 -64.809624)
		(width 0.12954)
		(layer "In2.Cu")
		(net "GPU_HSC_BUF_EN")
	)
	(segment
		(start 283.3878 -90.932)
		(end 275.970746 -90.932)
		(width 0.12954)
		(layer "In2.Cu")
		(net "GPU_HSC_BUF_EN")
	)
	(segment
		(start 359.354882 -82.935318)
		(end 338.10956 -82.935318)
		(width 0.12954)
		(layer "In2.Cu")
		(net "GPU_HSC_BUF_EN")
	)
	(segment
		(start 450.977 -39.878)
		(end 449.78574 -38.68674)
		(width 0.12954)
		(layer "In2.Cu")
		(net "GPU_HSC_BUF_EN")
	)
	(segment
		(start 327.047098 -93.99778)
		(end 305.453034 -93.99778)
		(width 0.12954)
		(layer "In2.Cu")
		(net "GPU_HSC_BUF_EN")
	)
	(segment
		(start 206.341218 -93.218)
		(end 220.7768 -93.218)
		(width 0.12954)
		(layer "In2.Cu")
		(net "GPU_HSC_BUF_EN")
	)
	(segment
		(start 338.10956 -82.935318)
		(end 327.047098 -93.99778)
		(width 0.12954)
		(layer "In2.Cu")
		(net "GPU_HSC_BUF_EN")
	)
	(segment
		(start 449.78574 -38.68674)
		(end 439.46826 -38.68674)
		(width 0.12954)
		(layer "In2.Cu")
		(net "GPU_HSC_BUF_EN")
	)
	(segment
		(start 424.528234 -45.244512)
		(end 423.496486 -46.27626)
		(width 0.12954)
		(layer "In2.Cu")
		(net "GPU_HSC_BUF_EN")
	)
	(segment
		(start 224.3582 -96.393)
		(end 230.2002 -90.551)
		(width 0.12954)
		(layer "In2.Cu")
		(net "GPU_HSC_BUF_EN")
	)
	(segment
		(start 428.287942 -45.244512)
		(end 424.528234 -45.244512)
		(width 0.12954)
		(layer "In2.Cu")
		(net "GPU_HSC_BUF_EN")
	)
	(segment
		(start 247.8786 -82.6008)
		(end 254.54356 -82.6008)
		(width 0.12954)
		(layer "In2.Cu")
		(net "GPU_HSC_BUF_EN")
	)
	(segment
		(start 414.909 -46.989746)
		(end 414.909 -51.308)
		(width 0.12954)
		(layer "In2.Cu")
		(net "GPU_HSC_BUF_EN")
	)
	(segment
		(start 182.735982 -83.334098)
		(end 183.731916 -82.338164)
		(width 0.12954)
		(layer "In2.Cu")
		(net "GPU_HSC_BUF_EN")
	)
	(segment
		(start 295.444926 -92.01658)
		(end 294.662606 -91.23426)
		(width 0.12954)
		(layer "In2.Cu")
		(net "GPU_HSC_BUF_EN")
	)
	(segment
		(start 259.966968 -88.024208)
		(end 259.966968 -88.034622)
		(width 0.12954)
		(layer "In2.Cu")
		(net "GPU_HSC_BUF_EN")
	)
	(segment
		(start 273.938746 -88.9)
		(end 260.84276 -88.9)
		(width 0.12954)
		(layer "In2.Cu")
		(net "GPU_HSC_BUF_EN")
	)
	(segment
		(start 260.84276 -88.9)
		(end 259.977382 -88.034622)
		(width 0.12954)
		(layer "In2.Cu")
		(net "GPU_HSC_BUF_EN")
	)
	(segment
		(start 230.2002 -90.551)
		(end 239.9284 -90.551)
		(width 0.12954)
		(layer "In2.Cu")
		(net "GPU_HSC_BUF_EN")
	)
	(segment
		(start 439.46826 -38.68674)
		(end 437.134 -41.021)
		(width 0.12954)
		(layer "In2.Cu")
		(net "GPU_HSC_BUF_EN")
	)
	(segment
		(start 222.631 -96.393)
		(end 224.3582 -96.393)
		(width 0.12954)
		(layer "In2.Cu")
		(net "GPU_HSC_BUF_EN")
	)
	(segment
		(start 183.731916 -82.338164)
		(end 195.461382 -82.338164)
		(width 0.12954)
		(layer "In2.Cu")
		(net "GPU_HSC_BUF_EN")
	)
	(segment
		(start 433.07 -42.672)
		(end 430.860454 -42.672)
		(width 0.12954)
		(layer "In2.Cu")
		(net "GPU_HSC_BUF_EN")
	)
	(segment
		(start 450.977 -44.2976)
		(end 450.977 -39.878)
		(width 0.12954)
		(layer "In2.Cu")
		(net "GPU_HSC_BUF_EN")
	)
	(segment
		(start 430.860454 -42.672)
		(end 428.287942 -45.244512)
		(width 0.12954)
		(layer "In2.Cu")
		(net "GPU_HSC_BUF_EN")
	)
	(segment
		(start 220.7768 -93.218)
		(end 221.615 -94.0562)
		(width 0.12954)
		(layer "In2.Cu")
		(net "GPU_HSC_BUF_EN")
	)
	(segment
		(start 416.654234 -45.244512)
		(end 414.909 -46.989746)
		(width 0.12954)
		(layer "In2.Cu")
		(net "GPU_HSC_BUF_EN")
	)
	(segment
		(start 259.977382 -88.034622)
		(end 259.966968 -88.034622)
		(width 0.12954)
		(layer "In2.Cu")
		(net "GPU_HSC_BUF_EN")
	)
	(segment
		(start 254.54356 -82.6008)
		(end 259.966968 -88.024208)
		(width 0.12954)
		(layer "In2.Cu")
		(net "GPU_HSC_BUF_EN")
	)
	(segment
		(start 414.909 -51.308)
		(end 401.407376 -64.809624)
		(width 0.12954)
		(layer "In2.Cu")
		(net "GPU_HSC_BUF_EN")
	)
	(segment
		(start 377.480576 -64.809624)
		(end 359.354882 -82.935318)
		(width 0.12954)
		(layer "In2.Cu")
		(net "GPU_HSC_BUF_EN")
	)
	(segment
		(start 283.69006 -91.23426)
		(end 283.3878 -90.932)
		(width 0.12954)
		(layer "In2.Cu")
		(net "GPU_HSC_BUF_EN")
	)
	(segment
		(start 239.9284 -90.551)
		(end 247.8786 -82.6008)
		(width 0.12954)
		(layer "In2.Cu")
		(net "GPU_HSC_BUF_EN")
	)
	(segment
		(start 221.615 -95.377)
		(end 222.631 -96.393)
		(width 0.12954)
		(layer "In2.Cu")
		(net "GPU_HSC_BUF_EN")
	)
	(segment
		(start 434.721 -41.021)
		(end 433.07 -42.672)
		(width 0.12954)
		(layer "In2.Cu")
		(net "GPU_HSC_BUF_EN")
	)
	(segment
		(start 419.767512 -45.244512)
		(end 416.654234 -45.244512)
		(width 0.12954)
		(layer "In2.Cu")
		(net "GPU_HSC_BUF_EN")
	)
	(segment
		(start 423.496486 -46.27626)
		(end 420.79926 -46.27626)
		(width 0.12954)
		(layer "In2.Cu")
		(net "GPU_HSC_BUF_EN")
	)
	(segment
		(start 450.2404 -45.0342)
		(end 450.977 -44.2976)
		(width 0.12954)
		(layer "In2.Cu")
		(net "GPU_HSC_BUF_EN")
	)
	(segment
		(start 195.461382 -82.338164)
		(end 206.341218 -93.218)
		(width 0.12954)
		(layer "In2.Cu")
		(net "GPU_HSC_BUF_EN")
	)
	(segment
		(start 221.615 -94.0562)
		(end 221.615 -95.377)
		(width 0.12954)
		(layer "In2.Cu")
		(net "GPU_HSC_BUF_EN")
	)
	(segment
		(start 303.471834 -92.01658)
		(end 295.444926 -92.01658)
		(width 0.12954)
		(layer "In2.Cu")
		(net "GPU_HSC_BUF_EN")
	)
	(segment
		(start 437.134 -41.021)
		(end 434.721 -41.021)
		(width 0.12954)
		(layer "In2.Cu")
		(net "GPU_HSC_BUF_EN")
	)
	(segment
		(start 305.453034 -93.99778)
		(end 303.471834 -92.01658)
		(width 0.12954)
		(layer "In2.Cu")
		(net "GPU_HSC_BUF_EN")
	)
	(segment
		(start 294.662606 -91.23426)
		(end 283.69006 -91.23426)
		(width 0.12954)
		(layer "In2.Cu")
		(net "GPU_HSC_BUF_EN")
	)
	(segment
		(start 420.79926 -46.27626)
		(end 419.767512 -45.244512)
		(width 0.12954)
		(layer "In2.Cu")
		(net "GPU_HSC_BUF_EN")
	)
	(segment
		(start 275.970746 -90.932)
		(end 273.938746 -88.9)
		(width 0.12954)
		(layer "In2.Cu")
		(net "GPU_HSC_BUF_EN")
	)
	(segment
		(start 173.632368 -66.016632)
		(end 173.147736 -65.532)
		(width 0.17272)
		(layer "F.Cu")
		(net "P52V_HS2_OV")
	)
	(segment
		(start 173.147736 -59.92876)
		(end 171.866052 -58.647076)
		(width 0.17272)
		(layer "F.Cu")
		(net "P52V_HS2_OV")
	)
	(segment
		(start 173.147736 -65.532)
		(end 173.147736 -59.92876)
		(width 0.17272)
		(layer "F.Cu")
		(net "P52V_HS2_OV")
	)
	(via
		(at 153.143712 -74.668126)
		(size 0.508)
		(drill 0.254)
		(layers "F.Cu" "B.Cu")
		(net "P52V_HS2_OV")
	)
	(via
		(at 171.866052 -58.647076)
		(size 0.508)
		(drill 0.254)
		(layers "F.Cu" "B.Cu")
		(net "P52V_HS2_OV")
	)
	(via
		(at 173.632368 -66.016632)
		(size 0.508)
		(drill 0.254)
		(layers "F.Cu" "B.Cu")
		(net "P52V_HS2_OV")
	)
	(segment
		(start 153.143712 -74.668126)
		(end 153.143712 -74.522838)
		(width 0.17272)
		(layer "B.Cu")
		(net "P52V_HS2_OV")
	)
	(segment
		(start 174.714916 -66.423794)
		(end 174.714916 -67.16268)
		(width 0.17272)
		(layer "B.Cu")
		(net "P52V_HS2_OV")
	)
	(segment
		(start 173.632368 -66.016632)
		(end 174.307754 -66.016632)
		(width 0.17272)
		(layer "B.Cu")
		(net "P52V_HS2_OV")
	)
	(segment
		(start 171.115736 -57.89676)
		(end 171.115736 -56.95696)
		(width 0.17272)
		(layer "B.Cu")
		(net "P52V_HS2_OV")
	)
	(segment
		(start 171.866052 -58.647076)
		(end 171.115736 -57.89676)
		(width 0.17272)
		(layer "B.Cu")
		(net "P52V_HS2_OV")
	)
	(segment
		(start 172.7454 -65.129664)
		(end 173.632368 -66.016632)
		(width 0.17272)
		(layer "B.Cu")
		(net "P52V_HS2_OV")
	)
	(segment
		(start 153.8478 -73.81875)
		(end 153.8478 -73.504044)
		(width 0.17272)
		(layer "B.Cu")
		(net "P52V_HS2_OV")
	)
	(segment
		(start 174.307754 -66.016632)
		(end 174.714916 -66.423794)
		(width 0.17272)
		(layer "B.Cu")
		(net "P52V_HS2_OV")
	)
	(segment
		(start 172.7454 -64.15405)
		(end 172.7454 -65.129664)
		(width 0.17272)
		(layer "B.Cu")
		(net "P52V_HS2_OV")
	)
	(segment
		(start 171.7294 -64.15405)
		(end 172.7454 -64.15405)
		(width 0.17272)
		(layer "B.Cu")
		(net "P52V_HS2_OV")
	)
	(segment
		(start 153.143712 -74.522838)
		(end 153.8478 -73.81875)
		(width 0.17272)
		(layer "B.Cu")
		(net "P52V_HS2_OV")
	)
	(segment
		(start 157.226 -76.02474)
		(end 155.05557 -78.19517)
		(width 0.12954)
		(layer "In2.Cu")
		(net "P52V_HS2_OV")
	)
	(segment
		(start 152.35428 -77.83449)
		(end 152.35428 -76.265786)
		(width 0.12954)
		(layer "In2.Cu")
		(net "P52V_HS2_OV")
	)
	(segment
		(start 153.143712 -75.476354)
		(end 153.143712 -74.668126)
		(width 0.12954)
		(layer "In2.Cu")
		(net "P52V_HS2_OV")
	)
	(segment
		(start 171.7294 -69.088)
		(end 166.855648 -69.088)
		(width 0.12954)
		(layer "In2.Cu")
		(net "P52V_HS2_OV")
	)
	(segment
		(start 155.05557 -78.19517)
		(end 152.71496 -78.19517)
		(width 0.12954)
		(layer "In2.Cu")
		(net "P52V_HS2_OV")
	)
	(segment
		(start 152.35428 -76.265786)
		(end 153.143712 -75.476354)
		(width 0.12954)
		(layer "In2.Cu")
		(net "P52V_HS2_OV")
	)
	(segment
		(start 152.71496 -78.19517)
		(end 152.35428 -77.83449)
		(width 0.12954)
		(layer "In2.Cu")
		(net "P52V_HS2_OV")
	)
	(segment
		(start 172.663104 -66.016632)
		(end 172.2374 -66.442336)
		(width 0.12954)
		(layer "In2.Cu")
		(net "P52V_HS2_OV")
	)
	(segment
		(start 166.855648 -69.088)
		(end 159.918908 -76.02474)
		(width 0.12954)
		(layer "In2.Cu")
		(net "P52V_HS2_OV")
	)
	(segment
		(start 172.2374 -66.442336)
		(end 172.2374 -68.58)
		(width 0.12954)
		(layer "In2.Cu")
		(net "P52V_HS2_OV")
	)
	(segment
		(start 172.2374 -68.58)
		(end 171.7294 -69.088)
		(width 0.12954)
		(layer "In2.Cu")
		(net "P52V_HS2_OV")
	)
	(segment
		(start 173.632368 -66.016632)
		(end 172.663104 -66.016632)
		(width 0.12954)
		(layer "In2.Cu")
		(net "P52V_HS2_OV")
	)
	(segment
		(start 159.918908 -76.02474)
		(end 157.226 -76.02474)
		(width 0.12954)
		(layer "In2.Cu")
		(net "P52V_HS2_OV")
	)
	(segment
		(start 426.19803 -46.79188)
		(end 428.7774 -46.79188)
		(width 0.17272)
		(layer "F.Cu")
		(net "SMB_IOEXP_SCL")
	)
	(segment
		(start 428.7774 -46.79188)
		(end 429.29683 -46.79188)
		(width 0.17272)
		(layer "F.Cu")
		(net "SMB_IOEXP_SCL")
	)
	(segment
		(start 423.291 -44.693078)
		(end 424.099228 -44.693078)
		(width 0.17272)
		(layer "F.Cu")
		(net "SMB_IOEXP_SCL")
	)
	(segment
		(start 424.099228 -44.693078)
		(end 426.19803 -46.79188)
		(width 0.17272)
		(layer "F.Cu")
		(net "SMB_IOEXP_SCL")
	)
	(segment
		(start 429.29683 -46.79188)
		(end 429.87595 -47.371)
		(width 0.17272)
		(layer "F.Cu")
		(net "SMB_IOEXP_SCL")
	)
	(via
		(at 428.7774 -46.79188)
		(size 0.508)
		(drill 0.254)
		(layers "F.Cu" "B.Cu")
		(net "SMB_IOEXP_SCL")
	)
	(segment
		(start 426.82795 -47.371)
		(end 425.958 -47.371)
		(width 0.17272)
		(layer "F.Cu")
		(net "SMB_IOEXP_SDA")
	)
	(segment
		(start 424.7007 -46.1137)
		(end 423.909744 -45.322744)
		(width 0.17272)
		(layer "F.Cu")
		(net "SMB_IOEXP_SDA")
	)
	(segment
		(start 423.909744 -45.322744)
		(end 423.31132 -45.322744)
		(width 0.17272)
		(layer "F.Cu")
		(net "SMB_IOEXP_SDA")
	)
	(segment
		(start 425.958 -47.371)
		(end 424.7007 -46.1137)
		(width 0.17272)
		(layer "F.Cu")
		(net "SMB_IOEXP_SDA")
	)
	(segment
		(start 423.31132 -45.322744)
		(end 423.291 -45.343064)
		(width 0.17272)
		(layer "F.Cu")
		(net "SMB_IOEXP_SDA")
	)
	(via
		(at 424.7007 -46.1137)
		(size 0.508)
		(drill 0.254)
		(layers "F.Cu" "B.Cu")
		(net "SMB_IOEXP_SDA")
	)
	(segment
		(start 145.85442 -68.199)
		(end 145.85442 -68.030598)
		(width 0.4572)
		(layer "F.Cu")
		(net "P52V_HS2_SENSE_P_R1")
	)
	(segment
		(start 145.85442 -68.030598)
		(end 146.422618 -67.4624)
		(width 0.4572)
		(layer "F.Cu")
		(net "P52V_HS2_SENSE_P_R1")
	)
	(segment
		(start 143.003778 -62.909958)
		(end 143.003778 -62.820042)
		(width 0.254)
		(layer "F.Cu")
		(net "P52V_HS2_SENSE_P_R1")
	)
	(segment
		(start 145.85442 -69.977)
		(end 145.85442 -68.199)
		(width 0.4572)
		(layer "F.Cu")
		(net "P52V_HS2_SENSE_P_R1")
	)
	(segment
		(start 143.46682 -63.373)
		(end 143.003778 -62.909958)
		(width 0.254)
		(layer "F.Cu")
		(net "P52V_HS2_SENSE_P_R1")
	)
	(segment
		(start 143.78051 -63.373)
		(end 143.46682 -63.373)
		(width 0.254)
		(layer "F.Cu")
		(net "P52V_HS2_SENSE_P_R1")
	)
	(segment
		(start 145.85442 -71.755)
		(end 145.85442 -69.977)
		(width 0.4572)
		(layer "F.Cu")
		(net "P52V_HS2_SENSE_P_R1")
	)
	(via
		(at 143.003778 -62.820042)
		(size 0.508)
		(drill 0.254)
		(layers "F.Cu" "B.Cu")
		(net "P52V_HS2_SENSE_P_R1")
	)
	(via
		(at 146.422618 -67.4624)
		(size 0.508)
		(drill 0.254)
		(layers "F.Cu" "B.Cu")
		(net "P52V_HS2_SENSE_P_R1")
	)
	(segment
		(start 143.587978 -65.36944)
		(end 143.587978 -64.239902)
		(width 0.4572)
		(layer "In2.Cu")
		(net "P52V_HS2_SENSE_P_R1")
	)
	(segment
		(start 145.680938 -67.4624)
		(end 143.587978 -65.36944)
		(width 0.4572)
		(layer "In2.Cu")
		(net "P52V_HS2_SENSE_P_R1")
	)
	(segment
		(start 143.587978 -64.239902)
		(end 143.638778 -64.189102)
		(width 0.4572)
		(layer "In2.Cu")
		(net "P52V_HS2_SENSE_P_R1")
	)
	(segment
		(start 143.638778 -64.189102)
		(end 143.638778 -63.455042)
		(width 0.4572)
		(layer "In2.Cu")
		(net "P52V_HS2_SENSE_P_R1")
	)
	(segment
		(start 143.638778 -63.455042)
		(end 143.003778 -62.820042)
		(width 0.4572)
		(layer "In2.Cu")
		(net "P52V_HS2_SENSE_P_R1")
	)
	(segment
		(start 146.422618 -67.4624)
		(end 145.680938 -67.4624)
		(width 0.4572)
		(layer "In2.Cu")
		(net "P52V_HS2_SENSE_P_R1")
	)
	(segment
		(start 83.947 -16.5862)
		(end 83.947 -17.50695)
		(width 0.17272)
		(layer "F.Cu")
		(net "RST_SMB_FAN_1_R_N")
	)
	(segment
		(start 84.455 -16.0782)
		(end 83.947 -16.5862)
		(width 0.17272)
		(layer "F.Cu")
		(net "RST_SMB_FAN_1_R_N")
	)
	(via
		(at 84.455 -16.0782)
		(size 0.508)
		(drill 0.254)
		(layers "F.Cu" "B.Cu")
		(net "RST_SMB_FAN_1_R_N")
	)
	(segment
		(start 71.211186 -2.035048)
		(end 69.760084 -2.035048)
		(width 0.12954)
		(layer "In2.Cu")
		(net "RST_SMB_FAN_1_R_N")
	)
	(segment
		(start 84.455 -16.0782)
		(end 84.455 -15.9766)
		(width 0.12954)
		(layer "In2.Cu")
		(net "RST_SMB_FAN_1_R_N")
	)
	(segment
		(start 73.787 -4.074922)
		(end 73.25106 -4.074922)
		(width 0.12954)
		(layer "In2.Cu")
		(net "RST_SMB_FAN_1_R_N")
	)
	(segment
		(start 74.549 -6.0706)
		(end 74.549 -4.836922)
		(width 0.12954)
		(layer "In2.Cu")
		(net "RST_SMB_FAN_1_R_N")
	)
	(segment
		(start 73.25106 -4.074922)
		(end 71.211186 -2.035048)
		(width 0.12954)
		(layer "In2.Cu")
		(net "RST_SMB_FAN_1_R_N")
	)
	(segment
		(start 84.455 -15.9766)
		(end 74.549 -6.0706)
		(width 0.12954)
		(layer "In2.Cu")
		(net "RST_SMB_FAN_1_R_N")
	)
	(segment
		(start 74.549 -4.836922)
		(end 73.787 -4.074922)
		(width 0.12954)
		(layer "In2.Cu")
		(net "RST_SMB_FAN_1_R_N")
	)
	(segment
		(start 82.804 -17.50695)
		(end 82.804 -16.4846)
		(width 0.17272)
		(layer "F.Cu")
		(net "FAN_PWR_EN_1_R")
	)
	(segment
		(start 82.804 -16.4846)
		(end 82.5754 -16.256)
		(width 0.17272)
		(layer "F.Cu")
		(net "FAN_PWR_EN_1_R")
	)
	(via
		(at 82.5754 -16.256)
		(size 0.762)
		(drill 0.254)
		(layers "F.Cu" "B.Cu")
		(net "FAN_PWR_EN_1_R")
	)
	(segment
		(start 82.5754 -16.256)
		(end 82.5754 -15.939262)
		(width 0.12954)
		(layer "In2.Cu")
		(net "FAN_PWR_EN_1_R")
	)
	(segment
		(start 82.5754 -15.939262)
		(end 71.030084 -4.393946)
		(width 0.12954)
		(layer "In2.Cu")
		(net "FAN_PWR_EN_1_R")
	)
	(segment
		(start 71.030084 -4.393946)
		(end 71.030084 -3.305048)
		(width 0.12954)
		(layer "In2.Cu")
		(net "FAN_PWR_EN_1_R")
	)
	(segment
		(start 439.9534 -29.083)
		(end 436.64505 -29.083)
		(width 0.17272)
		(layer "F.Cu")
		(net "SMB_PDB_FAN_0_SDA")
	)
	(segment
		(start 378.517912 -20.389088)
		(end 378.517912 -18.307304)
		(width 0.17272)
		(layer "F.Cu")
		(net "SMB_PDB_FAN_0_SDA")
	)
	(segment
		(start 436.64505 -29.083)
		(end 436.64505 -28.448)
		(width 0.17272)
		(layer "F.Cu")
		(net "SMB_PDB_FAN_0_SDA")
	)
	(segment
		(start 378.46 -20.447)
		(end 378.517912 -20.389088)
		(width 0.17272)
		(layer "F.Cu")
		(net "SMB_PDB_FAN_0_SDA")
	)
	(via
		(at 378.46 -20.447)
		(size 0.508)
		(drill 0.254)
		(layers "F.Cu" "B.Cu")
		(net "SMB_PDB_FAN_0_SDA")
	)
	(via
		(at 436.64505 -28.448)
		(size 0.508)
		(drill 0.254)
		(layers "F.Cu" "B.Cu")
		(net "SMB_PDB_FAN_0_SDA")
	)
	(segment
		(start 434.959506 -24.384)
		(end 434.684678 -24.384)
		(width 0.12954)
		(layer "In2.Cu")
		(net "SMB_PDB_FAN_0_SDA")
	)
	(segment
		(start 435.153562 -24.578056)
		(end 434.959506 -24.384)
		(width 0.12954)
		(layer "In2.Cu")
		(net "SMB_PDB_FAN_0_SDA")
	)
	(segment
		(start 434.490622 -24.578056)
		(end 434.490622 -26.221944)
		(width 0.12954)
		(layer "In2.Cu")
		(net "SMB_PDB_FAN_0_SDA")
	)
	(segment
		(start 433.633626 -24.384)
		(end 433.358798 -24.384)
		(width 0.12954)
		(layer "In2.Cu")
		(net "SMB_PDB_FAN_0_SDA")
	)
	(segment
		(start 386.334 -6.223)
		(end 383.52095 -9.03605)
		(width 0.12954)
		(layer "In2.Cu")
		(net "SMB_PDB_FAN_0_SDA")
	)
	(segment
		(start 431.537364 -26.416)
		(end 411.344364 -6.223)
		(width 0.12954)
		(layer "In2.Cu")
		(net "SMB_PDB_FAN_0_SDA")
	)
	(segment
		(start 435.347618 -26.416)
		(end 435.153562 -26.221944)
		(width 0.12954)
		(layer "In2.Cu")
		(net "SMB_PDB_FAN_0_SDA")
	)
	(segment
		(start 434.296566 -26.416)
		(end 434.021738 -26.416)
		(width 0.12954)
		(layer "In2.Cu")
		(net "SMB_PDB_FAN_0_SDA")
	)
	(segment
		(start 434.684678 -24.384)
		(end 434.490622 -24.578056)
		(width 0.12954)
		(layer "In2.Cu")
		(net "SMB_PDB_FAN_0_SDA")
	)
	(segment
		(start 432.970686 -26.416)
		(end 431.537364 -26.416)
		(width 0.12954)
		(layer "In2.Cu")
		(net "SMB_PDB_FAN_0_SDA")
	)
	(segment
		(start 435.153562 -26.221944)
		(end 435.153562 -24.578056)
		(width 0.12954)
		(layer "In2.Cu")
		(net "SMB_PDB_FAN_0_SDA")
	)
	(segment
		(start 437.388 -27.70505)
		(end 437.388 -26.924)
		(width 0.12954)
		(layer "In2.Cu")
		(net "SMB_PDB_FAN_0_SDA")
	)
	(segment
		(start 437.388 -26.924)
		(end 436.88 -26.416)
		(width 0.12954)
		(layer "In2.Cu")
		(net "SMB_PDB_FAN_0_SDA")
	)
	(segment
		(start 436.88 -26.416)
		(end 435.347618 -26.416)
		(width 0.12954)
		(layer "In2.Cu")
		(net "SMB_PDB_FAN_0_SDA")
	)
	(segment
		(start 411.344364 -6.223)
		(end 386.334 -6.223)
		(width 0.12954)
		(layer "In2.Cu")
		(net "SMB_PDB_FAN_0_SDA")
	)
	(segment
		(start 433.827682 -24.578056)
		(end 433.633626 -24.384)
		(width 0.12954)
		(layer "In2.Cu")
		(net "SMB_PDB_FAN_0_SDA")
	)
	(segment
		(start 433.827682 -26.221944)
		(end 433.827682 -24.578056)
		(width 0.12954)
		(layer "In2.Cu")
		(net "SMB_PDB_FAN_0_SDA")
	)
	(segment
		(start 433.358798 -24.384)
		(end 433.164742 -24.578056)
		(width 0.12954)
		(layer "In2.Cu")
		(net "SMB_PDB_FAN_0_SDA")
	)
	(segment
		(start 436.64505 -28.448)
		(end 437.388 -27.70505)
		(width 0.12954)
		(layer "In2.Cu")
		(net "SMB_PDB_FAN_0_SDA")
	)
	(segment
		(start 381.2794 -20.447)
		(end 378.46 -20.447)
		(width 0.12954)
		(layer "In2.Cu")
		(net "SMB_PDB_FAN_0_SDA")
	)
	(segment
		(start 434.021738 -26.416)
		(end 433.827682 -26.221944)
		(width 0.12954)
		(layer "In2.Cu")
		(net "SMB_PDB_FAN_0_SDA")
	)
	(segment
		(start 434.490622 -26.221944)
		(end 434.296566 -26.416)
		(width 0.12954)
		(layer "In2.Cu")
		(net "SMB_PDB_FAN_0_SDA")
	)
	(segment
		(start 433.164742 -26.221944)
		(end 432.970686 -26.416)
		(width 0.12954)
		(layer "In2.Cu")
		(net "SMB_PDB_FAN_0_SDA")
	)
	(segment
		(start 433.164742 -24.578056)
		(end 433.164742 -26.221944)
		(width 0.12954)
		(layer "In2.Cu")
		(net "SMB_PDB_FAN_0_SDA")
	)
	(segment
		(start 383.52095 -9.03605)
		(end 383.52095 -18.20545)
		(width 0.12954)
		(layer "In2.Cu")
		(net "SMB_PDB_FAN_0_SDA")
	)
	(segment
		(start 383.52095 -18.20545)
		(end 381.2794 -20.447)
		(width 0.12954)
		(layer "In2.Cu")
		(net "SMB_PDB_FAN_0_SDA")
	)
	(segment
		(start 81.661 -17.50695)
		(end 81.661 -16.891)
		(width 0.17272)
		(layer "F.Cu")
		(net "SMB_PDB_FAN_1_R_SDA")
	)
	(via
		(at 81.661 -16.891)
		(size 0.508)
		(drill 0.254)
		(layers "F.Cu" "B.Cu")
		(net "SMB_PDB_FAN_1_R_SDA")
	)
	(segment
		(start 79.883 -16.509746)
		(end 79.883 -14.986)
		(width 0.12954)
		(layer "In2.Cu")
		(net "SMB_PDB_FAN_1_R_SDA")
	)
	(segment
		(start 79.883 -14.986)
		(end 72.517 -7.62)
		(width 0.12954)
		(layer "In2.Cu")
		(net "SMB_PDB_FAN_1_R_SDA")
	)
	(segment
		(start 72.517 -7.62)
		(end 71.716138 -7.62)
		(width 0.12954)
		(layer "In2.Cu")
		(net "SMB_PDB_FAN_1_R_SDA")
	)
	(segment
		(start 81.661 -16.891)
		(end 80.264254 -16.891)
		(width 0.12954)
		(layer "In2.Cu")
		(net "SMB_PDB_FAN_1_R_SDA")
	)
	(segment
		(start 71.716138 -7.62)
		(end 69.760084 -5.663946)
		(width 0.12954)
		(layer "In2.Cu")
		(net "SMB_PDB_FAN_1_R_SDA")
	)
	(segment
		(start 69.760084 -5.663946)
		(end 69.760084 -4.575048)
		(width 0.12954)
		(layer "In2.Cu")
		(net "SMB_PDB_FAN_1_R_SDA")
	)
	(segment
		(start 80.264254 -16.891)
		(end 79.883 -16.509746)
		(width 0.12954)
		(layer "In2.Cu")
		(net "SMB_PDB_FAN_1_R_SDA")
	)
	(segment
		(start 169.356786 -67.183)
		(end 169.356786 -69.7992)
		(width 0.17272)
		(layer "F.Cu")
		(net "P52V_HS2_ADR1")
	)
	(segment
		(start 167.182546 -67.80276)
		(end 168.737026 -67.80276)
		(width 0.17272)
		(layer "F.Cu")
		(net "P52V_HS2_ADR1")
	)
	(segment
		(start 166.943786 -67.564)
		(end 167.182546 -67.80276)
		(width 0.17272)
		(layer "F.Cu")
		(net "P52V_HS2_ADR1")
	)
	(segment
		(start 169.356786 -69.7992)
		(end 170.123866 -70.56628)
		(width 0.17272)
		(layer "F.Cu")
		(net "P52V_HS2_ADR1")
	)
	(segment
		(start 171.877736 -70.90156)
		(end 171.877736 -71.3613)
		(width 0.17272)
		(layer "F.Cu")
		(net "P52V_HS2_ADR1")
	)
	(segment
		(start 170.123866 -70.56628)
		(end 171.542456 -70.56628)
		(width 0.17272)
		(layer "F.Cu")
		(net "P52V_HS2_ADR1")
	)
	(segment
		(start 166.181786 -66.802)
		(end 166.943786 -67.564)
		(width 0.17272)
		(layer "F.Cu")
		(net "P52V_HS2_ADR1")
	)
	(segment
		(start 168.737026 -67.80276)
		(end 169.356786 -67.183)
		(width 0.17272)
		(layer "F.Cu")
		(net "P52V_HS2_ADR1")
	)
	(segment
		(start 171.542456 -70.56628)
		(end 171.877736 -70.90156)
		(width 0.17272)
		(layer "F.Cu")
		(net "P52V_HS2_ADR1")
	)
	(segment
		(start 166.1414 -66.802)
		(end 166.181786 -66.802)
		(width 0.17272)
		(layer "F.Cu")
		(net "P52V_HS2_ADR1")
	)
	(via
		(at 169.356786 -69.7992)
		(size 0.762)
		(drill 0.381)
		(layers "F.Cu" "B.Cu")
		(net "P52V_HS2_ADR1")
	)
	(via
		(at 156.637736 -74.803)
		(size 0.508)
		(drill 0.254)
		(layers "F.Cu" "B.Cu")
		(net "P52V_HS2_ADR1")
	)
	(via
		(at 166.1414 -66.802)
		(size 0.508)
		(drill 0.254)
		(layers "F.Cu" "B.Cu")
		(net "P52V_HS2_ADR1")
	)
	(via
		(at 171.877736 -71.3613)
		(size 0.508)
		(drill 0.254)
		(layers "F.Cu" "B.Cu")
		(net "P52V_HS2_ADR1")
	)
	(segment
		(start 157.257496 -77.359256)
		(end 157.257496 -78.35519)
		(width 0.17272)
		(layer "B.Cu")
		(net "P52V_HS2_ADR1")
	)
	(segment
		(start 173.516036 -71.3613)
		(end 171.877736 -71.3613)
		(width 0.17272)
		(layer "B.Cu")
		(net "P52V_HS2_ADR1")
	)
	(segment
		(start 156.637736 -74.803)
		(end 156.347668 -74.512932)
		(width 0.17272)
		(layer "B.Cu")
		(net "P52V_HS2_ADR1")
	)
	(segment
		(start 156.71419 -76.81595)
		(end 157.257496 -77.359256)
		(width 0.17272)
		(layer "B.Cu")
		(net "P52V_HS2_ADR1")
	)
	(segment
		(start 156.347668 -74.512932)
		(end 156.347668 -73.504044)
		(width 0.17272)
		(layer "B.Cu")
		(net "P52V_HS2_ADR1")
	)
	(segment
		(start 156.637736 -76.81595)
		(end 156.637736 -74.803)
		(width 0.17272)
		(layer "B.Cu")
		(net "P52V_HS2_ADR1")
	)
	(segment
		(start 156.637736 -76.81595)
		(end 156.71419 -76.81595)
		(width 0.17272)
		(layer "B.Cu")
		(net "P52V_HS2_ADR1")
	)
	(segment
		(start 157.257496 -78.35519)
		(end 156.637736 -78.97495)
		(width 0.17272)
		(layer "B.Cu")
		(net "P52V_HS2_ADR1")
	)
	(segment
		(start 156.637736 -74.803)
		(end 159.481012 -74.803)
		(width 0.12954)
		(layer "In2.Cu")
		(net "P52V_HS2_ADR1")
	)
	(segment
		(start 166.357046 -67.926966)
		(end 166.357046 -67.017646)
		(width 0.12954)
		(layer "In2.Cu")
		(net "P52V_HS2_ADR1")
	)
	(segment
		(start 166.357046 -67.017646)
		(end 166.1414 -66.802)
		(width 0.12954)
		(layer "In2.Cu")
		(net "P52V_HS2_ADR1")
	)
	(segment
		(start 159.481012 -74.803)
		(end 166.357046 -67.926966)
		(width 0.12954)
		(layer "In2.Cu")
		(net "P52V_HS2_ADR1")
	)
	(segment
		(start 80.518 -17.50695)
		(end 80.518 -16.383)
		(width 0.17272)
		(layer "F.Cu")
		(net "SMB_PDB_FAN_1_R_SCL")
	)
	(via
		(at 80.518 -16.383)
		(size 0.508)
		(drill 0.254)
		(layers "F.Cu" "B.Cu")
		(net "SMB_PDB_FAN_1_R_SCL")
	)
	(via
		(at 80.518 -14.732)
		(size 0.508)
		(drill 0.254)
		(layers "F.Cu" "B.Cu")
		(net "SMB_PDB_FAN_1_R_SCL")
	)
	(segment
		(start 71.631048 -5.845048)
		(end 71.030084 -5.845048)
		(width 0.12954)
		(layer "In2.Cu")
		(net "SMB_PDB_FAN_1_R_SCL")
	)
	(segment
		(start 80.518 -16.383)
		(end 80.518 -14.732)
		(width 0.12954)
		(layer "In2.Cu")
		(net "SMB_PDB_FAN_1_R_SCL")
	)
	(segment
		(start 80.518 -14.732)
		(end 71.631048 -5.845048)
		(width 0.12954)
		(layer "In2.Cu")
		(net "SMB_PDB_FAN_1_R_SCL")
	)
	(segment
		(start 448.92595 -31.623)
		(end 447.452496 -31.623)
		(width 0.17272)
		(layer "F.Cu")
		(net "SMB_FAN_MUX_SCL")
	)
	(segment
		(start 447.4464 -31.623)
		(end 445.2366 -31.623)
		(width 0.17272)
		(layer "F.Cu")
		(net "SMB_FAN_MUX_SCL")
	)
	(segment
		(start 447.452496 -31.623)
		(end 447.4464 -31.629096)
		(width 0.17272)
		(layer "F.Cu")
		(net "SMB_FAN_MUX_SCL")
	)
	(segment
		(start 447.4464 -31.629096)
		(end 447.4464 -31.623)
		(width 0.17272)
		(layer "F.Cu")
		(net "SMB_FAN_MUX_SCL")
	)
	(via
		(at 447.4464 -31.629096)
		(size 0.508)
		(drill 0.254)
		(layers "F.Cu" "B.Cu")
		(net "SMB_FAN_MUX_SCL")
	)
	(segment
		(start 166.5732 -74.0156)
		(end 170.2054 -74.0156)
		(width 0.17272)
		(layer "F.Cu")
		(net "P52V_HS2_EN")
	)
	(segment
		(start 180.5686 -80.814164)
		(end 180.5686 -82.3214)
		(width 0.17272)
		(layer "F.Cu")
		(net "P52V_HS2_EN")
	)
	(segment
		(start 161.191194 -72.209406)
		(end 161.191194 -70.964552)
		(width 0.17272)
		(layer "F.Cu")
		(net "P52V_HS2_EN")
	)
	(segment
		(start 163.1442 -70.5866)
		(end 166.5732 -74.0156)
		(width 0.17272)
		(layer "F.Cu")
		(net "P52V_HS2_EN")
	)
	(segment
		(start 159.3596 -72.9234)
		(end 160.4772 -72.9234)
		(width 0.17272)
		(layer "F.Cu")
		(net "P52V_HS2_EN")
	)
	(segment
		(start 158.415736 -71.979536)
		(end 159.3596 -72.9234)
		(width 0.17272)
		(layer "F.Cu")
		(net "P52V_HS2_EN")
	)
	(segment
		(start 52.832 -26.94305)
		(end 53.70195 -26.94305)
		(width 0.17272)
		(layer "F.Cu")
		(net "P52V_HS2_EN")
	)
	(segment
		(start 170.8404 -71.636636)
		(end 171.115736 -71.3613)
		(width 0.17272)
		(layer "F.Cu")
		(net "P52V_HS2_EN")
	)
	(segment
		(start 170.2054 -74.0156)
		(end 170.8404 -73.3806)
		(width 0.17272)
		(layer "F.Cu")
		(net "P52V_HS2_EN")
	)
	(segment
		(start 178.14163 -80.20304)
		(end 173.665896 -80.20304)
		(width 0.17272)
		(layer "F.Cu")
		(net "P52V_HS2_EN")
	)
	(segment
		(start 170.8404 -73.3806)
		(end 170.8404 -71.636636)
		(width 0.17272)
		(layer "F.Cu")
		(net "P52V_HS2_EN")
	)
	(segment
		(start 171.115736 -71.3613)
		(end 180.5686 -80.814164)
		(width 0.17272)
		(layer "F.Cu")
		(net "P52V_HS2_EN")
	)
	(segment
		(start 180.5686 -82.3214)
		(end 180.25999 -82.3214)
		(width 0.17272)
		(layer "F.Cu")
		(net "P52V_HS2_EN")
	)
	(segment
		(start 161.569146 -70.5866)
		(end 163.1442 -70.5866)
		(width 0.17272)
		(layer "F.Cu")
		(net "P52V_HS2_EN")
	)
	(segment
		(start 160.4772 -72.9234)
		(end 161.191194 -72.209406)
		(width 0.17272)
		(layer "F.Cu")
		(net "P52V_HS2_EN")
	)
	(segment
		(start 158.415736 -71.374)
		(end 158.415736 -71.979536)
		(width 0.17272)
		(layer "F.Cu")
		(net "P52V_HS2_EN")
	)
	(segment
		(start 161.191194 -70.964552)
		(end 161.569146 -70.5866)
		(width 0.17272)
		(layer "F.Cu")
		(net "P52V_HS2_EN")
	)
	(segment
		(start 180.25999 -82.3214)
		(end 178.14163 -80.20304)
		(width 0.17272)
		(layer "F.Cu")
		(net "P52V_HS2_EN")
	)
	(via
		(at 158.415736 -71.374)
		(size 0.508)
		(drill 0.254)
		(layers "F.Cu" "B.Cu")
		(net "P52V_HS2_EN")
	)
	(via
		(at 219.1004 -7.493)
		(size 0.508)
		(drill 0.254)
		(layers "F.Cu" "B.Cu")
		(net "P52V_HS2_EN")
	)
	(via
		(at 224.85731 -96.774)
		(size 0.508)
		(drill 0.254)
		(layers "F.Cu" "B.Cu")
		(net "P52V_HS2_EN")
	)
	(via
		(at 53.70195 -26.94305)
		(size 0.508)
		(drill 0.254)
		(layers "F.Cu" "B.Cu")
		(net "P52V_HS2_EN")
	)
	(via
		(at 180.5686 -82.3214)
		(size 0.508)
		(drill 0.254)
		(layers "F.Cu" "B.Cu")
		(net "P52V_HS2_EN")
	)
	(via
		(at 171.115736 -71.3613)
		(size 0.508)
		(drill 0.254)
		(layers "F.Cu" "B.Cu")
		(net "P52V_HS2_EN")
	)
	(segment
		(start 219.1004 -7.493)
		(end 219.76588 -8.15848)
		(width 0.17272)
		(layer "B.Cu")
		(net "P52V_HS2_EN")
	)
	(segment
		(start 158.415736 -71.374)
		(end 157.895798 -70.854062)
		(width 0.17272)
		(layer "B.Cu")
		(net "P52V_HS2_EN")
	)
	(segment
		(start 171.115736 -71.3613)
		(end 171.115736 -71.352664)
		(width 0.17272)
		(layer "B.Cu")
		(net "P52V_HS2_EN")
	)
	(segment
		(start 224.197164 -96.113854)
		(end 224.85731 -96.774)
		(width 0.17272)
		(layer "B.Cu")
		(net "P52V_HS2_EN")
	)
	(segment
		(start 171.115736 -71.352664)
		(end 172.10532 -70.36308)
		(width 0.17272)
		(layer "B.Cu")
		(net "P52V_HS2_EN")
	)
	(segment
		(start 219.76588 -87.548212)
		(end 224.197164 -91.979496)
		(width 0.17272)
		(layer "B.Cu")
		(net "P52V_HS2_EN")
	)
	(segment
		(start 172.10532 -70.36308)
		(end 173.516036 -70.36308)
		(width 0.17272)
		(layer "B.Cu")
		(net "P52V_HS2_EN")
	)
	(segment
		(start 219.76588 -8.15848)
		(end 219.76588 -87.548212)
		(width 0.17272)
		(layer "B.Cu")
		(net "P52V_HS2_EN")
	)
	(segment
		(start 157.895798 -70.854062)
		(end 157.49778 -70.854062)
		(width 0.17272)
		(layer "B.Cu")
		(net "P52V_HS2_EN")
	)
	(segment
		(start 224.197164 -91.979496)
		(end 224.197164 -96.113854)
		(width 0.17272)
		(layer "B.Cu")
		(net "P52V_HS2_EN")
	)
	(segment
		(start 222.123 -97.155)
		(end 224.47631 -97.155)
		(width 0.12954)
		(layer "In2.Cu")
		(net "P52V_HS2_EN")
	)
	(segment
		(start 180.5686 -82.3214)
		(end 180.5686 -91.5416)
		(width 0.12954)
		(layer "In2.Cu")
		(net "P52V_HS2_EN")
	)
	(segment
		(start 186.817 -97.79)
		(end 206.629 -97.79)
		(width 0.12954)
		(layer "In2.Cu")
		(net "P52V_HS2_EN")
	)
	(segment
		(start 78.822804 -20.608798)
		(end 72.488552 -26.94305)
		(width 0.12954)
		(layer "In2.Cu")
		(net "P52V_HS2_EN")
	)
	(segment
		(start 90.67419 -20.608798)
		(end 78.822804 -20.608798)
		(width 0.12954)
		(layer "In2.Cu")
		(net "P52V_HS2_EN")
	)
	(segment
		(start 220.853 -95.885)
		(end 222.123 -97.155)
		(width 0.12954)
		(layer "In2.Cu")
		(net "P52V_HS2_EN")
	)
	(segment
		(start 72.488552 -26.94305)
		(end 53.70195 -26.94305)
		(width 0.12954)
		(layer "In2.Cu")
		(net "P52V_HS2_EN")
	)
	(segment
		(start 224.47631 -97.155)
		(end 224.85731 -96.774)
		(width 0.12954)
		(layer "In2.Cu")
		(net "P52V_HS2_EN")
	)
	(segment
		(start 180.5686 -91.5416)
		(end 186.817 -97.79)
		(width 0.12954)
		(layer "In2.Cu")
		(net "P52V_HS2_EN")
	)
	(segment
		(start 216.856056 -5.248656)
		(end 106.034332 -5.248656)
		(width 0.12954)
		(layer "In2.Cu")
		(net "P52V_HS2_EN")
	)
	(segment
		(start 219.1004 -7.493)
		(end 216.856056 -5.248656)
		(width 0.12954)
		(layer "In2.Cu")
		(net "P52V_HS2_EN")
	)
	(segment
		(start 208.534 -95.885)
		(end 220.853 -95.885)
		(width 0.12954)
		(layer "In2.Cu")
		(net "P52V_HS2_EN")
	)
	(segment
		(start 106.034332 -5.248656)
		(end 90.67419 -20.608798)
		(width 0.12954)
		(layer "In2.Cu")
		(net "P52V_HS2_EN")
	)
	(segment
		(start 206.629 -97.79)
		(end 208.534 -95.885)
		(width 0.12954)
		(layer "In2.Cu")
		(net "P52V_HS2_EN")
	)
	(segment
		(start 448.92595 -27.813)
		(end 448.92595 -27.178)
		(width 0.17272)
		(layer "F.Cu")
		(net "SMB_PDB_FAN_1_SDA")
	)
	(segment
		(start 81.661 -18.30705)
		(end 81.661 -18.91665)
		(width 0.17272)
		(layer "F.Cu")
		(net "SMB_PDB_FAN_1_SDA")
	)
	(segment
		(start 445.2366 -27.813)
		(end 448.92595 -27.813)
		(width 0.17272)
		(layer "F.Cu")
		(net "SMB_PDB_FAN_1_SDA")
	)
	(via
		(at 81.661 -18.91665)
		(size 0.508)
		(drill 0.254)
		(layers "F.Cu" "B.Cu")
		(net "SMB_PDB_FAN_1_SDA")
	)
	(via
		(at 448.92595 -27.178)
		(size 0.508)
		(drill 0.254)
		(layers "F.Cu" "B.Cu")
		(net "SMB_PDB_FAN_1_SDA")
	)
	(segment
		(start 81.661 -18.91665)
		(end 81.974436 -18.91665)
		(width 0.12954)
		(layer "In2.Cu")
		(net "SMB_PDB_FAN_1_SDA")
	)
	(segment
		(start 445.900048 -23.88743)
		(end 446.086738 -23.70074)
		(width 0.12954)
		(layer "In2.Cu")
		(net "SMB_PDB_FAN_1_SDA")
	)
	(segment
		(start 442.711078 -23.88743)
		(end 442.711078 -26.35631)
		(width 0.12954)
		(layer "In2.Cu")
		(net "SMB_PDB_FAN_1_SDA")
	)
	(segment
		(start 446.086738 -23.70074)
		(end 448.414394 -23.70074)
		(width 0.12954)
		(layer "In2.Cu")
		(net "SMB_PDB_FAN_1_SDA")
	)
	(segment
		(start 444.43777 -26.543)
		(end 444.62446 -26.35631)
		(width 0.12954)
		(layer "In2.Cu")
		(net "SMB_PDB_FAN_1_SDA")
	)
	(segment
		(start 443.535562 -23.70074)
		(end 443.799976 -23.70074)
		(width 0.12954)
		(layer "In2.Cu")
		(net "SMB_PDB_FAN_1_SDA")
	)
	(segment
		(start 350.628458 -3.452368)
		(end 354.97135 -7.79526)
		(width 0.12954)
		(layer "In2.Cu")
		(net "SMB_PDB_FAN_1_SDA")
	)
	(segment
		(start 81.974436 -18.91665)
		(end 82.800952 -18.090134)
		(width 0.12954)
		(layer "In2.Cu")
		(net "SMB_PDB_FAN_1_SDA")
	)
	(segment
		(start 385.328922 -4.36626)
		(end 411.977078 -4.36626)
		(width 0.12954)
		(layer "In2.Cu")
		(net "SMB_PDB_FAN_1_SDA")
	)
	(segment
		(start 445.262254 -23.88743)
		(end 445.262254 -26.35631)
		(width 0.12954)
		(layer "In2.Cu")
		(net "SMB_PDB_FAN_1_SDA")
	)
	(segment
		(start 442.711078 -26.35631)
		(end 442.897768 -26.543)
		(width 0.12954)
		(layer "In2.Cu")
		(net "SMB_PDB_FAN_1_SDA")
	)
	(segment
		(start 445.713358 -26.543)
		(end 445.900048 -26.35631)
		(width 0.12954)
		(layer "In2.Cu")
		(net "SMB_PDB_FAN_1_SDA")
	)
	(segment
		(start 437.53024 -20.62226)
		(end 440.60872 -23.70074)
		(width 0.12954)
		(layer "In2.Cu")
		(net "SMB_PDB_FAN_1_SDA")
	)
	(segment
		(start 443.799976 -23.70074)
		(end 443.986666 -23.88743)
		(width 0.12954)
		(layer "In2.Cu")
		(net "SMB_PDB_FAN_1_SDA")
	)
	(segment
		(start 443.348872 -23.88743)
		(end 443.535562 -23.70074)
		(width 0.12954)
		(layer "In2.Cu")
		(net "SMB_PDB_FAN_1_SDA")
	)
	(segment
		(start 445.075564 -23.70074)
		(end 445.262254 -23.88743)
		(width 0.12954)
		(layer "In2.Cu")
		(net "SMB_PDB_FAN_1_SDA")
	)
	(segment
		(start 445.448944 -26.543)
		(end 445.713358 -26.543)
		(width 0.12954)
		(layer "In2.Cu")
		(net "SMB_PDB_FAN_1_SDA")
	)
	(segment
		(start 411.977078 -4.36626)
		(end 428.233078 -20.62226)
		(width 0.12954)
		(layer "In2.Cu")
		(net "SMB_PDB_FAN_1_SDA")
	)
	(segment
		(start 442.524388 -23.70074)
		(end 442.711078 -23.88743)
		(width 0.12954)
		(layer "In2.Cu")
		(net "SMB_PDB_FAN_1_SDA")
	)
	(segment
		(start 104.801924 -3.452368)
		(end 350.628458 -3.452368)
		(width 0.12954)
		(layer "In2.Cu")
		(net "SMB_PDB_FAN_1_SDA")
	)
	(segment
		(start 442.897768 -26.543)
		(end 443.162182 -26.543)
		(width 0.12954)
		(layer "In2.Cu")
		(net "SMB_PDB_FAN_1_SDA")
	)
	(segment
		(start 448.92595 -24.212296)
		(end 448.92595 -27.178)
		(width 0.12954)
		(layer "In2.Cu")
		(net "SMB_PDB_FAN_1_SDA")
	)
	(segment
		(start 443.986666 -23.88743)
		(end 443.986666 -26.35631)
		(width 0.12954)
		(layer "In2.Cu")
		(net "SMB_PDB_FAN_1_SDA")
	)
	(segment
		(start 443.348872 -26.35631)
		(end 443.348872 -23.88743)
		(width 0.12954)
		(layer "In2.Cu")
		(net "SMB_PDB_FAN_1_SDA")
	)
	(segment
		(start 445.262254 -26.35631)
		(end 445.448944 -26.543)
		(width 0.12954)
		(layer "In2.Cu")
		(net "SMB_PDB_FAN_1_SDA")
	)
	(segment
		(start 440.60872 -23.70074)
		(end 442.524388 -23.70074)
		(width 0.12954)
		(layer "In2.Cu")
		(net "SMB_PDB_FAN_1_SDA")
	)
	(segment
		(start 90.164158 -18.090134)
		(end 104.801924 -3.452368)
		(width 0.12954)
		(layer "In2.Cu")
		(net "SMB_PDB_FAN_1_SDA")
	)
	(segment
		(start 444.62446 -26.35631)
		(end 444.62446 -23.88743)
		(width 0.12954)
		(layer "In2.Cu")
		(net "SMB_PDB_FAN_1_SDA")
	)
	(segment
		(start 82.800952 -18.090134)
		(end 90.164158 -18.090134)
		(width 0.12954)
		(layer "In2.Cu")
		(net "SMB_PDB_FAN_1_SDA")
	)
	(segment
		(start 428.233078 -20.62226)
		(end 437.53024 -20.62226)
		(width 0.12954)
		(layer "In2.Cu")
		(net "SMB_PDB_FAN_1_SDA")
	)
	(segment
		(start 381.899922 -7.79526)
		(end 385.328922 -4.36626)
		(width 0.12954)
		(layer "In2.Cu")
		(net "SMB_PDB_FAN_1_SDA")
	)
	(segment
		(start 443.986666 -26.35631)
		(end 444.173356 -26.543)
		(width 0.12954)
		(layer "In2.Cu")
		(net "SMB_PDB_FAN_1_SDA")
	)
	(segment
		(start 444.81115 -23.70074)
		(end 445.075564 -23.70074)
		(width 0.12954)
		(layer "In2.Cu")
		(net "SMB_PDB_FAN_1_SDA")
	)
	(segment
		(start 354.97135 -7.79526)
		(end 381.899922 -7.79526)
		(width 0.12954)
		(layer "In2.Cu")
		(net "SMB_PDB_FAN_1_SDA")
	)
	(segment
		(start 448.414394 -23.70074)
		(end 448.92595 -24.212296)
		(width 0.12954)
		(layer "In2.Cu")
		(net "SMB_PDB_FAN_1_SDA")
	)
	(segment
		(start 444.62446 -23.88743)
		(end 444.81115 -23.70074)
		(width 0.12954)
		(layer "In2.Cu")
		(net "SMB_PDB_FAN_1_SDA")
	)
	(segment
		(start 445.900048 -26.35631)
		(end 445.900048 -23.88743)
		(width 0.12954)
		(layer "In2.Cu")
		(net "SMB_PDB_FAN_1_SDA")
	)
	(segment
		(start 443.162182 -26.543)
		(end 443.348872 -26.35631)
		(width 0.12954)
		(layer "In2.Cu")
		(net "SMB_PDB_FAN_1_SDA")
	)
	(segment
		(start 444.173356 -26.543)
		(end 444.43777 -26.543)
		(width 0.12954)
		(layer "In2.Cu")
		(net "SMB_PDB_FAN_1_SDA")
	)
	(segment
		(start 140.06322 -68.199)
		(end 140.06322 -67.4624)
		(width 0.4572)
		(layer "F.Cu")
		(net "P52V_HS2_SENSE_N_R1")
	)
	(segment
		(start 140.06322 -69.977)
		(end 140.06322 -68.199)
		(width 0.4572)
		(layer "F.Cu")
		(net "P52V_HS2_SENSE_N_R1")
	)
	(segment
		(start 140.06322 -71.755)
		(end 140.06322 -69.977)
		(width 0.4572)
		(layer "F.Cu")
		(net "P52V_HS2_SENSE_N_R1")
	)
	(segment
		(start 142.57782 -63.373)
		(end 142.227046 -63.373)
		(width 0.254)
		(layer "F.Cu")
		(net "P52V_HS2_SENSE_N_R1")
	)
	(segment
		(start 143.003778 -63.925958)
		(end 143.003778 -63.798958)
		(width 0.254)
		(layer "F.Cu")
		(net "P52V_HS2_SENSE_N_R1")
	)
	(segment
		(start 143.003778 -63.798958)
		(end 142.57782 -63.373)
		(width 0.254)
		(layer "F.Cu")
		(net "P52V_HS2_SENSE_N_R1")
	)
	(via
		(at 143.003778 -63.925958)
		(size 0.508)
		(drill 0.254)
		(layers "F.Cu" "B.Cu")
		(net "P52V_HS2_SENSE_N_R1")
	)
	(via
		(at 140.06322 -67.4624)
		(size 0.508)
		(drill 0.254)
		(layers "F.Cu" "B.Cu")
		(net "P52V_HS2_SENSE_N_R1")
	)
	(segment
		(start 143.003778 -65.401444)
		(end 143.003778 -63.925958)
		(width 0.4572)
		(layer "In2.Cu")
		(net "P52V_HS2_SENSE_N_R1")
	)
	(segment
		(start 140.942822 -67.4624)
		(end 143.003778 -65.401444)
		(width 0.4572)
		(layer "In2.Cu")
		(net "P52V_HS2_SENSE_N_R1")
	)
	(segment
		(start 140.06322 -67.4624)
		(end 140.942822 -67.4624)
		(width 0.4572)
		(layer "In2.Cu")
		(net "P52V_HS2_SENSE_N_R1")
	)
	(segment
		(start 447.4464 -32.893)
		(end 448.92595 -32.893)
		(width 0.17272)
		(layer "F.Cu")
		(net "SMB_FAN_MUX_SDA")
	)
	(segment
		(start 445.2366 -32.893)
		(end 447.4464 -32.893)
		(width 0.17272)
		(layer "F.Cu")
		(net "SMB_FAN_MUX_SDA")
	)
	(via
		(at 447.4464 -32.893)
		(size 0.762)
		(drill 0.381)
		(layers "F.Cu" "B.Cu")
		(net "SMB_FAN_MUX_SDA")
	)
	(segment
		(start 435.2544 -31.50235)
		(end 436.64505 -32.893)
		(width 0.17272)
		(layer "F.Cu")
		(net "PD_9543_FAN_A1")
	)
	(segment
		(start 433.85105 -31.50235)
		(end 435.2544 -31.50235)
		(width 0.17272)
		(layer "F.Cu")
		(net "PD_9543_FAN_A1")
	)
	(segment
		(start 433.85105 -32.893)
		(end 433.85105 -31.50235)
		(width 0.17272)
		(layer "F.Cu")
		(net "PD_9543_FAN_A1")
	)
	(segment
		(start 439.9534 -32.893)
		(end 436.64505 -32.893)
		(width 0.17272)
		(layer "F.Cu")
		(net "PD_9543_FAN_A1")
	)
	(via
		(at 433.85105 -31.50235)
		(size 0.762)
		(drill 0.381)
		(layers "F.Cu" "B.Cu")
		(net "PD_9543_FAN_A1")
	)
	(segment
		(start 434.48605 -33.528)
		(end 436.01005 -33.528)
		(width 0.17272)
		(layer "F.Cu")
		(net "PD_9543_FAN_A0")
	)
	(segment
		(start 439.9534 -34.163)
		(end 438.0484 -34.163)
		(width 0.17272)
		(layer "F.Cu")
		(net "PD_9543_FAN_A0")
	)
	(segment
		(start 438.0484 -34.163)
		(end 436.64505 -34.163)
		(width 0.17272)
		(layer "F.Cu")
		(net "PD_9543_FAN_A0")
	)
	(segment
		(start 433.85105 -34.163)
		(end 434.48605 -33.528)
		(width 0.17272)
		(layer "F.Cu")
		(net "PD_9543_FAN_A0")
	)
	(segment
		(start 436.01005 -33.528)
		(end 436.64505 -34.163)
		(width 0.17272)
		(layer "F.Cu")
		(net "PD_9543_FAN_A0")
	)
	(via
		(at 438.0484 -34.163)
		(size 0.762)
		(drill 0.381)
		(layers "F.Cu" "B.Cu")
		(net "PD_9543_FAN_A0")
	)
	(segment
		(start 436.64505 -27.813)
		(end 436.64505 -27.182064)
		(width 0.17272)
		(layer "F.Cu")
		(net "SMB_PDB_FAN_0_SCL")
	)
	(segment
		(start 379.660912 -18.307304)
		(end 379.660912 -21.209)
		(width 0.17272)
		(layer "F.Cu")
		(net "SMB_PDB_FAN_0_SCL")
	)
	(segment
		(start 439.9534 -27.813)
		(end 436.64505 -27.813)
		(width 0.17272)
		(layer "F.Cu")
		(net "SMB_PDB_FAN_0_SCL")
	)
	(via
		(at 436.64505 -27.182064)
		(size 0.508)
		(drill 0.254)
		(layers "F.Cu" "B.Cu")
		(net "SMB_PDB_FAN_0_SCL")
	)
	(via
		(at 379.660912 -21.209)
		(size 0.508)
		(drill 0.254)
		(layers "F.Cu" "B.Cu")
		(net "SMB_PDB_FAN_0_SCL")
	)
	(segment
		(start 384.10769 -9.4234)
		(end 384.10769 -18.448528)
		(width 0.12954)
		(layer "In2.Cu")
		(net "SMB_PDB_FAN_0_SCL")
	)
	(segment
		(start 386.67309 -6.858)
		(end 384.10769 -9.4234)
		(width 0.12954)
		(layer "In2.Cu")
		(net "SMB_PDB_FAN_0_SCL")
	)
	(segment
		(start 411.149546 -6.858)
		(end 386.67309 -6.858)
		(width 0.12954)
		(layer "In2.Cu")
		(net "SMB_PDB_FAN_0_SCL")
	)
	(segment
		(start 431.47361 -27.182064)
		(end 411.149546 -6.858)
		(width 0.12954)
		(layer "In2.Cu")
		(net "SMB_PDB_FAN_0_SCL")
	)
	(segment
		(start 381.347218 -21.209)
		(end 379.660912 -21.209)
		(width 0.12954)
		(layer "In2.Cu")
		(net "SMB_PDB_FAN_0_SCL")
	)
	(segment
		(start 384.10769 -18.448528)
		(end 381.347218 -21.209)
		(width 0.12954)
		(layer "In2.Cu")
		(net "SMB_PDB_FAN_0_SCL")
	)
	(segment
		(start 436.64505 -27.182064)
		(end 431.47361 -27.182064)
		(width 0.12954)
		(layer "In2.Cu")
		(net "SMB_PDB_FAN_0_SCL")
	)
	(segment
		(start 222.20555 -91.9988)
		(end 222.25635 -91.948)
		(width 0.17272)
		(layer "F.Cu")
		(net "SMB_P52V_PDB_DEBUG_SCL")
	)
	(segment
		(start 220.0656 -91.9988)
		(end 222.20555 -91.9988)
		(width 0.17272)
		(layer "F.Cu")
		(net "SMB_P52V_PDB_DEBUG_SCL")
	)
	(segment
		(start 80.518 -18.30705)
		(end 80.518 -18.91665)
		(width 0.17272)
		(layer "F.Cu")
		(net "SMB_PDB_FAN_1_SCL")
	)
	(segment
		(start 448.95135 -29.591)
		(end 448.95135 -28.960064)
		(width 0.17272)
		(layer "F.Cu")
		(net "SMB_PDB_FAN_1_SCL")
	)
	(segment
		(start 447.954654 -29.591)
		(end 447.446654 -29.083)
		(width 0.17272)
		(layer "F.Cu")
		(net "SMB_PDB_FAN_1_SCL")
	)
	(segment
		(start 448.95135 -29.591)
		(end 447.954654 -29.591)
		(width 0.17272)
		(layer "F.Cu")
		(net "SMB_PDB_FAN_1_SCL")
	)
	(segment
		(start 447.446654 -29.083)
		(end 446.9384 -29.083)
		(width 0.17272)
		(layer "F.Cu")
		(net "SMB_PDB_FAN_1_SCL")
	)
	(segment
		(start 446.9384 -29.083)
		(end 445.2366 -29.083)
		(width 0.17272)
		(layer "F.Cu")
		(net "SMB_PDB_FAN_1_SCL")
	)
	(via
		(at 446.9384 -29.083)
		(size 0.508)
		(drill 0.254)
		(layers "F.Cu" "B.Cu")
		(net "SMB_PDB_FAN_1_SCL")
	)
	(via
		(at 448.95135 -28.960064)
		(size 0.508)
		(drill 0.254)
		(layers "F.Cu" "B.Cu")
		(net "SMB_PDB_FAN_1_SCL")
	)
	(via
		(at 80.518 -18.91665)
		(size 0.508)
		(drill 0.254)
		(layers "F.Cu" "B.Cu")
		(net "SMB_PDB_FAN_1_SCL")
	)
	(segment
		(start 350.871536 -2.865628)
		(end 355.214428 -7.20852)
		(width 0.12954)
		(layer "In2.Cu")
		(net "SMB_PDB_FAN_1_SCL")
	)
	(segment
		(start 448.691 -23.114)
		(end 449.834 -24.257)
		(width 0.12954)
		(layer "In2.Cu")
		(net "SMB_PDB_FAN_1_SCL")
	)
	(segment
		(start 104.558846 -2.865628)
		(end 350.871536 -2.865628)
		(width 0.12954)
		(layer "In2.Cu")
		(net "SMB_PDB_FAN_1_SCL")
	)
	(segment
		(start 81.81086 -17.503394)
		(end 89.92108 -17.503394)
		(width 0.12954)
		(layer "In2.Cu")
		(net "SMB_PDB_FAN_1_SCL")
	)
	(segment
		(start 449.834 -24.257)
		(end 449.834 -28.077414)
		(width 0.12954)
		(layer "In2.Cu")
		(net "SMB_PDB_FAN_1_SCL")
	)
	(segment
		(start 355.214428 -7.20852)
		(end 381.656844 -7.20852)
		(width 0.12954)
		(layer "In2.Cu")
		(net "SMB_PDB_FAN_1_SCL")
	)
	(segment
		(start 428.476156 -20.03552)
		(end 437.773318 -20.03552)
		(width 0.12954)
		(layer "In2.Cu")
		(net "SMB_PDB_FAN_1_SCL")
	)
	(segment
		(start 437.773318 -20.03552)
		(end 440.851798 -23.114)
		(width 0.12954)
		(layer "In2.Cu")
		(net "SMB_PDB_FAN_1_SCL")
	)
	(segment
		(start 412.220156 -3.77952)
		(end 428.476156 -20.03552)
		(width 0.12954)
		(layer "In2.Cu")
		(net "SMB_PDB_FAN_1_SCL")
	)
	(segment
		(start 80.518 -18.796254)
		(end 81.81086 -17.503394)
		(width 0.12954)
		(layer "In2.Cu")
		(net "SMB_PDB_FAN_1_SCL")
	)
	(segment
		(start 89.92108 -17.503394)
		(end 104.558846 -2.865628)
		(width 0.12954)
		(layer "In2.Cu")
		(net "SMB_PDB_FAN_1_SCL")
	)
	(segment
		(start 80.518 -18.91665)
		(end 80.518 -18.796254)
		(width 0.12954)
		(layer "In2.Cu")
		(net "SMB_PDB_FAN_1_SCL")
	)
	(segment
		(start 385.085844 -3.77952)
		(end 412.220156 -3.77952)
		(width 0.12954)
		(layer "In2.Cu")
		(net "SMB_PDB_FAN_1_SCL")
	)
	(segment
		(start 449.834 -28.077414)
		(end 448.95135 -28.960064)
		(width 0.12954)
		(layer "In2.Cu")
		(net "SMB_PDB_FAN_1_SCL")
	)
	(segment
		(start 381.656844 -7.20852)
		(end 385.085844 -3.77952)
		(width 0.12954)
		(layer "In2.Cu")
		(net "SMB_PDB_FAN_1_SCL")
	)
	(segment
		(start 440.851798 -23.114)
		(end 448.691 -23.114)
		(width 0.12954)
		(layer "In2.Cu")
		(net "SMB_PDB_FAN_1_SCL")
	)
	(segment
		(start 220.0656 -97.0788)
		(end 222.20555 -97.0788)
		(width 0.17272)
		(layer "F.Cu")
		(net "SMB_P52V_PDB_DEBUG_SDA")
	)
	(segment
		(start 222.20555 -97.0788)
		(end 222.25635 -97.028)
		(width 0.17272)
		(layer "F.Cu")
		(net "SMB_P52V_PDB_DEBUG_SDA")
	)
	(segment
		(start 413.350964 -36.449)
		(end 413.731964 -36.068)
		(width 0.17272)
		(layer "F.Cu")
		(net "PWRGD_P52V_HS2_4287_PG")
	)
	(segment
		(start 414.4264 -37.524436)
		(end 413.350964 -36.449)
		(width 0.17272)
		(layer "F.Cu")
		(net "PWRGD_P52V_HS2_4287_PG")
	)
	(segment
		(start 414.4264 -39.861998)
		(end 414.4264 -37.524436)
		(width 0.17272)
		(layer "F.Cu")
		(net "PWRGD_P52V_HS2_4287_PG")
	)
	(segment
		(start 413.731964 -36.068)
		(end 414.53435 -36.068)
		(width 0.17272)
		(layer "F.Cu")
		(net "PWRGD_P52V_HS2_4287_PG")
	)
	(via
		(at 413.350964 -36.449)
		(size 0.762)
		(drill 0.381)
		(layers "F.Cu" "B.Cu")
		(net "PWRGD_P52V_HS2_4287_PG")
	)
	(segment
		(start 433.6288 -42.202608)
		(end 433.835556 -42.409364)
		(width 0.17272)
		(layer "F.Cu")
		(net "SMB_PDB_MISC_SCL")
	)
	(segment
		(start 434.7464 -44.069)
		(end 434.7464 -44.27728)
		(width 0.17272)
		(layer "F.Cu")
		(net "SMB_PDB_MISC_SCL")
	)
	(segment
		(start 434.107844 -42.409364)
		(end 434.3146 -42.61612)
		(width 0.17272)
		(layer "F.Cu")
		(net "SMB_PDB_MISC_SCL")
	)
	(segment
		(start 432.2064 -46.101)
		(end 432.0794 -46.228)
		(width 0.17272)
		(layer "F.Cu")
		(net "SMB_PDB_MISC_SCL")
	)
	(segment
		(start 434.99151 -46.101)
		(end 432.2064 -46.101)
		(width 0.17272)
		(layer "F.Cu")
		(net "SMB_PDB_MISC_SCL")
	)
	(segment
		(start 434.57368 -44.45)
		(end 432.76012 -44.45)
		(width 0.17272)
		(layer "F.Cu")
		(net "SMB_PDB_MISC_SCL")
	)
	(segment
		(start 433.835556 -43.115484)
		(end 433.6288 -43.32224)
		(width 0.17272)
		(layer "F.Cu")
		(net "SMB_PDB_MISC_SCL")
	)
	(segment
		(start 432.76012 -45.339)
		(end 435.0004 -45.339)
		(width 0.17272)
		(layer "F.Cu")
		(net "SMB_PDB_MISC_SCL")
	)
	(segment
		(start 433.835556 -42.409364)
		(end 434.107844 -42.409364)
		(width 0.17272)
		(layer "F.Cu")
		(net "SMB_PDB_MISC_SCL")
	)
	(segment
		(start 434.107844 -43.115484)
		(end 433.835556 -43.115484)
		(width 0.17272)
		(layer "F.Cu")
		(net "SMB_PDB_MISC_SCL")
	)
	(segment
		(start 434.3146 -42.61612)
		(end 434.3146 -42.908728)
		(width 0.17272)
		(layer "F.Cu")
		(net "SMB_PDB_MISC_SCL")
	)
	(segment
		(start 435.16423 -45.50283)
		(end 435.16423 -45.92828)
		(width 0.17272)
		(layer "F.Cu")
		(net "SMB_PDB_MISC_SCL")
	)
	(segment
		(start 433.6288 -41.54805)
		(end 433.6288 -42.202608)
		(width 0.17272)
		(layer "F.Cu")
		(net "SMB_PDB_MISC_SCL")
	)
	(segment
		(start 434.3146 -42.908728)
		(end 434.107844 -43.115484)
		(width 0.17272)
		(layer "F.Cu")
		(net "SMB_PDB_MISC_SCL")
	)
	(segment
		(start 434.6194 -43.942)
		(end 434.7464 -44.069)
		(width 0.17272)
		(layer "F.Cu")
		(net "SMB_PDB_MISC_SCL")
	)
	(segment
		(start 432.06035 -47.117)
		(end 432.06035 -46.24705)
		(width 0.17272)
		(layer "F.Cu")
		(net "SMB_PDB_MISC_SCL")
	)
	(segment
		(start 430.93005 -47.117)
		(end 432.06035 -47.117)
		(width 0.17272)
		(layer "F.Cu")
		(net "SMB_PDB_MISC_SCL")
	)
	(segment
		(start 435.0004 -45.339)
		(end 435.16423 -45.50283)
		(width 0.17272)
		(layer "F.Cu")
		(net "SMB_PDB_MISC_SCL")
	)
	(segment
		(start 435.16423 -45.92828)
		(end 434.99151 -46.101)
		(width 0.17272)
		(layer "F.Cu")
		(net "SMB_PDB_MISC_SCL")
	)
	(segment
		(start 433.6288 -43.7134)
		(end 433.8574 -43.942)
		(width 0.17272)
		(layer "F.Cu")
		(net "SMB_PDB_MISC_SCL")
	)
	(segment
		(start 432.06035 -46.24705)
		(end 432.0794 -46.228)
		(width 0.17272)
		(layer "F.Cu")
		(net "SMB_PDB_MISC_SCL")
	)
	(segment
		(start 432.76012 -44.45)
		(end 432.5874 -44.62272)
		(width 0.17272)
		(layer "F.Cu")
		(net "SMB_PDB_MISC_SCL")
	)
	(segment
		(start 432.5874 -44.62272)
		(end 432.5874 -45.16628)
		(width 0.17272)
		(layer "F.Cu")
		(net "SMB_PDB_MISC_SCL")
	)
	(segment
		(start 433.8574 -43.942)
		(end 434.6194 -43.942)
		(width 0.17272)
		(layer "F.Cu")
		(net "SMB_PDB_MISC_SCL")
	)
	(segment
		(start 432.5874 -45.16628)
		(end 432.76012 -45.339)
		(width 0.17272)
		(layer "F.Cu")
		(net "SMB_PDB_MISC_SCL")
	)
	(segment
		(start 430.67605 -47.371)
		(end 430.93005 -47.117)
		(width 0.17272)
		(layer "F.Cu")
		(net "SMB_PDB_MISC_SCL")
	)
	(segment
		(start 433.6288 -43.32224)
		(end 433.6288 -43.7134)
		(width 0.17272)
		(layer "F.Cu")
		(net "SMB_PDB_MISC_SCL")
	)
	(segment
		(start 434.7464 -44.27728)
		(end 434.57368 -44.45)
		(width 0.17272)
		(layer "F.Cu")
		(net "SMB_PDB_MISC_SCL")
	)
	(via
		(at 432.0794 -46.228)
		(size 0.508)
		(drill 0.254)
		(layers "F.Cu" "B.Cu")
		(net "SMB_PDB_MISC_SCL")
	)
	(segment
		(start 429.08982 -36.26612)
		(end 429.514 -36.6903)
		(width 0.17272)
		(layer "B.Cu")
		(net "SMB_PDB_MISC_SCL")
	)
	(segment
		(start 431.038 -46.482)
		(end 431.8254 -46.482)
		(width 0.17272)
		(layer "B.Cu")
		(net "SMB_PDB_MISC_SCL")
	)
	(segment
		(start 429.514 -36.6903)
		(end 429.514 -44.958)
		(width 0.17272)
		(layer "B.Cu")
		(net "SMB_PDB_MISC_SCL")
	)
	(segment
		(start 427.68393 -36.26612)
		(end 429.08982 -36.26612)
		(width 0.17272)
		(layer "B.Cu")
		(net "SMB_PDB_MISC_SCL")
	)
	(segment
		(start 431.8254 -46.482)
		(end 432.0794 -46.228)
		(width 0.17272)
		(layer "B.Cu")
		(net "SMB_PDB_MISC_SCL")
	)
	(segment
		(start 429.514 -44.958)
		(end 431.038 -46.482)
		(width 0.17272)
		(layer "B.Cu")
		(net "SMB_PDB_MISC_SCL")
	)
	(segment
		(start 426.99305 -36.957)
		(end 427.68393 -36.26612)
		(width 0.17272)
		(layer "B.Cu")
		(net "SMB_PDB_MISC_SCL")
	)
	(segment
		(start 435.74335 -45.44695)
		(end 436.9054 -46.609)
		(width 0.17272)
		(layer "F.Cu")
		(net "PWRGD_P3V3_AUX_MB_BUF")
	)
	(segment
		(start 436.35295 -42.799)
		(end 435.74335 -42.799)
		(width 0.17272)
		(layer "F.Cu")
		(net "PWRGD_P3V3_AUX_MB_BUF")
	)
	(segment
		(start 437.648096 -46.609)
		(end 437.62295 -46.609)
		(width 0.17272)
		(layer "F.Cu")
		(net "PWRGD_P3V3_AUX_MB_BUF")
	)
	(segment
		(start 436.35295 -38.862)
		(end 435.74335 -38.862)
		(width 0.17272)
		(layer "F.Cu")
		(net "PWRGD_P3V3_AUX_MB_BUF")
	)
	(segment
		(start 438.807098 -47.768002)
		(end 437.648096 -46.609)
		(width 0.17272)
		(layer "F.Cu")
		(net "PWRGD_P3V3_AUX_MB_BUF")
	)
	(segment
		(start 435.74335 -42.799)
		(end 435.74335 -45.44695)
		(width 0.17272)
		(layer "F.Cu")
		(net "PWRGD_P3V3_AUX_MB_BUF")
	)
	(segment
		(start 436.9054 -46.609)
		(end 437.62295 -46.609)
		(width 0.17272)
		(layer "F.Cu")
		(net "PWRGD_P3V3_AUX_MB_BUF")
	)
	(segment
		(start 439.74004 -47.768002)
		(end 438.807098 -47.768002)
		(width 0.17272)
		(layer "F.Cu")
		(net "PWRGD_P3V3_AUX_MB_BUF")
	)
	(via
		(at 457.2254 -47.625)
		(size 0.508)
		(drill 0.254)
		(layers "F.Cu" "B.Cu")
		(net "PWRGD_P3V3_AUX_MB_BUF")
	)
	(via
		(at 435.74335 -38.862)
		(size 0.508)
		(drill 0.254)
		(layers "F.Cu" "B.Cu")
		(net "PWRGD_P3V3_AUX_MB_BUF")
	)
	(via
		(at 435.74335 -42.799)
		(size 0.508)
		(drill 0.254)
		(layers "F.Cu" "B.Cu")
		(net "PWRGD_P3V3_AUX_MB_BUF")
	)
	(segment
		(start 435.1274 -42.18305)
		(end 435.74335 -42.799)
		(width 0.17272)
		(layer "B.Cu")
		(net "PWRGD_P3V3_AUX_MB_BUF")
	)
	(segment
		(start 457.2254 -47.625)
		(end 457.2254 -49.276254)
		(width 0.17272)
		(layer "B.Cu")
		(net "PWRGD_P3V3_AUX_MB_BUF")
	)
	(segment
		(start 457.2254 -49.276254)
		(end 459.69428 -51.745134)
		(width 0.17272)
		(layer "B.Cu")
		(net "PWRGD_P3V3_AUX_MB_BUF")
	)
	(segment
		(start 467.229952 -86.160102)
		(end 468.365078 -86.160102)
		(width 0.17272)
		(layer "B.Cu")
		(net "PWRGD_P3V3_AUX_MB_BUF")
	)
	(segment
		(start 459.69428 -78.62443)
		(end 467.229952 -86.160102)
		(width 0.17272)
		(layer "B.Cu")
		(net "PWRGD_P3V3_AUX_MB_BUF")
	)
	(segment
		(start 435.1274 -39.47795)
		(end 435.1274 -42.18305)
		(width 0.17272)
		(layer "B.Cu")
		(net "PWRGD_P3V3_AUX_MB_BUF")
	)
	(segment
		(start 435.74335 -38.862)
		(end 435.1274 -39.47795)
		(width 0.17272)
		(layer "B.Cu")
		(net "PWRGD_P3V3_AUX_MB_BUF")
	)
	(segment
		(start 459.69428 -51.745134)
		(end 459.69428 -78.62443)
		(width 0.17272)
		(layer "B.Cu")
		(net "PWRGD_P3V3_AUX_MB_BUF")
	)
	(segment
		(start 449.072 -45.466)
		(end 449.834 -45.466)
		(width 0.12954)
		(layer "In2.Cu")
		(net "PWRGD_P3V3_AUX_MB_BUF")
	)
	(segment
		(start 435.74335 -42.799)
		(end 446.405 -42.799)
		(width 0.12954)
		(layer "In2.Cu")
		(net "PWRGD_P3V3_AUX_MB_BUF")
	)
	(segment
		(start 455.8284 -46.228)
		(end 457.2254 -47.625)
		(width 0.12954)
		(layer "In2.Cu")
		(net "PWRGD_P3V3_AUX_MB_BUF")
	)
	(segment
		(start 449.834 -45.466)
		(end 450.596 -46.228)
		(width 0.12954)
		(layer "In2.Cu")
		(net "PWRGD_P3V3_AUX_MB_BUF")
	)
	(segment
		(start 450.596 -46.228)
		(end 455.8284 -46.228)
		(width 0.12954)
		(layer "In2.Cu")
		(net "PWRGD_P3V3_AUX_MB_BUF")
	)
	(segment
		(start 446.405 -42.799)
		(end 449.072 -45.466)
		(width 0.12954)
		(layer "In2.Cu")
		(net "PWRGD_P3V3_AUX_MB_BUF")
	)
	(segment
		(start 450.342 -41.54805)
		(end 449.199 -41.54805)
		(width 0.17272)
		(layer "F.Cu")
		(net "SMB_PDB_MISC_SDA_R")
	)
	(segment
		(start 447.40957 -41.72712)
		(end 447.58864 -41.54805)
		(width 0.17272)
		(layer "F.Cu")
		(net "SMB_PDB_MISC_SDA_R")
	)
	(segment
		(start 449.199 -41.54805)
		(end 448.056 -41.54805)
		(width 0.17272)
		(layer "F.Cu")
		(net "SMB_PDB_MISC_SDA_R")
	)
	(segment
		(start 447.58864 -41.54805)
		(end 448.056 -41.54805)
		(width 0.17272)
		(layer "F.Cu")
		(net "SMB_PDB_MISC_SDA_R")
	)
	(segment
		(start 446.6844 -41.72712)
		(end 447.40957 -41.72712)
		(width 0.17272)
		(layer "F.Cu")
		(net "SMB_PDB_MISC_SDA_R")
	)
	(segment
		(start 444.827406 -41.72712)
		(end 446.6844 -41.72712)
		(width 0.17272)
		(layer "F.Cu")
		(net "SMB_PDB_MISC_SDA_R")
	)
	(via
		(at 446.6844 -41.72712)
		(size 0.762)
		(drill 0.381)
		(layers "F.Cu" "B.Cu")
		(net "SMB_PDB_MISC_SDA_R")
	)
	(segment
		(start 435.991 -41.54805)
		(end 437.134 -41.54805)
		(width 0.17272)
		(layer "F.Cu")
		(net "SMB_PDB_MISC_SCL_R")
	)
	(segment
		(start 437.967374 -41.72712)
		(end 437.788304 -41.54805)
		(width 0.17272)
		(layer "F.Cu")
		(net "SMB_PDB_MISC_SCL_R")
	)
	(segment
		(start 434.848 -41.54805)
		(end 435.991 -41.54805)
		(width 0.17272)
		(layer "F.Cu")
		(net "SMB_PDB_MISC_SCL_R")
	)
	(segment
		(start 437.788304 -41.54805)
		(end 437.134 -41.54805)
		(width 0.17272)
		(layer "F.Cu")
		(net "SMB_PDB_MISC_SCL_R")
	)
	(segment
		(start 438.6834 -41.72712)
		(end 437.967374 -41.72712)
		(width 0.17272)
		(layer "F.Cu")
		(net "SMB_PDB_MISC_SCL_R")
	)
	(segment
		(start 440.362594 -41.72712)
		(end 438.6834 -41.72712)
		(width 0.17272)
		(layer "F.Cu")
		(net "SMB_PDB_MISC_SCL_R")
	)
	(via
		(at 438.6834 -41.72712)
		(size 0.508)
		(drill 0.254)
		(layers "F.Cu" "B.Cu")
		(net "SMB_PDB_MISC_SCL_R")
	)
	(segment
		(start 168.556686 -67.183)
		(end 168.321736 -67.183)
		(width 0.4572)
		(layer "F.Cu")
		(net "P52V_HS2_VCAP")
	)
	(segment
		(start 168.321736 -67.183)
		(end 167.813736 -66.675)
		(width 0.4572)
		(layer "F.Cu")
		(net "P52V_HS2_VCAP")
	)
	(segment
		(start 168.321736 -66.167)
		(end 167.813736 -66.675)
		(width 0.4572)
		(layer "F.Cu")
		(net "P52V_HS2_VCAP")
	)
	(segment
		(start 168.556686 -66.167)
		(end 168.321736 -66.167)
		(width 0.4572)
		(layer "F.Cu")
		(net "P52V_HS2_VCAP")
	)
	(via
		(at 167.813736 -66.675)
		(size 0.508)
		(drill 0.254)
		(layers "F.Cu" "B.Cu")
		(net "P52V_HS2_VCAP")
	)
	(via
		(at 171.3992 -68.4784)
		(size 0.762)
		(drill 0.254)
		(layers "F.Cu" "B.Cu")
		(net "P52V_HS2_VCAP")
	)
	(segment
		(start 168.429686 -66.675)
		(end 167.813736 -66.675)
		(width 0.4572)
		(layer "B.Cu")
		(net "P52V_HS2_VCAP")
	)
	(segment
		(start 171.3992 -68.4784)
		(end 169.5958 -66.675)
		(width 0.381)
		(layer "In2.Cu")
		(net "P52V_HS2_VCAP")
	)
	(segment
		(start 169.5958 -66.675)
		(end 167.813736 -66.675)
		(width 0.381)
		(layer "In2.Cu")
		(net "P52V_HS2_VCAP")
	)
	(segment
		(start 433.405534 -35.10788)
		(end 432.897026 -35.10788)
		(width 0.17272)
		(layer "F.Cu")
		(net "SMB_PDB_MISC_SDA")
	)
	(segment
		(start 427.62805 -47.371)
		(end 428.23765 -47.371)
		(width 0.17272)
		(layer "F.Cu")
		(net "SMB_PDB_MISC_SDA")
	)
	(segment
		(start 433.93868 -36.954206)
		(end 434.18252 -36.710366)
		(width 0.17272)
		(layer "F.Cu")
		(net "SMB_PDB_MISC_SDA")
	)
	(segment
		(start 432.689 -43.3324)
		(end 432.689 -38.747446)
		(width 0.17272)
		(layer "F.Cu")
		(net "SMB_PDB_MISC_SDA")
	)
	(segment
		(start 434.1114 -37.833046)
		(end 433.93868 -37.660326)
		(width 0.17272)
		(layer "F.Cu")
		(net "SMB_PDB_MISC_SDA")
	)
	(segment
		(start 432.897026 -35.10788)
		(end 432.637946 -34.8488)
		(width 0.17272)
		(layer "F.Cu")
		(net "SMB_PDB_MISC_SDA")
	)
	(segment
		(start 433.93868 -38.366446)
		(end 434.1114 -38.193726)
		(width 0.17272)
		(layer "F.Cu")
		(net "SMB_PDB_MISC_SDA")
	)
	(segment
		(start 432.689 -38.747446)
		(end 433.07 -38.366446)
		(width 0.17272)
		(layer "F.Cu")
		(net "SMB_PDB_MISC_SDA")
	)
	(segment
		(start 431.8508 -34.8488)
		(end 430.784 -33.782)
		(width 0.17272)
		(layer "F.Cu")
		(net "SMB_PDB_MISC_SDA")
	)
	(segment
		(start 431.1904 -31.74365)
		(end 431.8254 -31.74365)
		(width 0.17272)
		(layer "F.Cu")
		(net "SMB_PDB_MISC_SDA")
	)
	(segment
		(start 450.93128 -34.09823)
		(end 450.93128 -39.54272)
		(width 0.17272)
		(layer "F.Cu")
		(net "SMB_PDB_MISC_SDA")
	)
	(segment
		(start 434.18252 -36.710366)
		(end 434.18252 -35.884866)
		(width 0.17272)
		(layer "F.Cu")
		(net "SMB_PDB_MISC_SDA")
	)
	(segment
		(start 449.72605 -32.893)
		(end 450.93128 -34.09823)
		(width 0.17272)
		(layer "F.Cu")
		(net "SMB_PDB_MISC_SDA")
	)
	(segment
		(start 431.99812 -36.954206)
		(end 433.93868 -36.954206)
		(width 0.17272)
		(layer "F.Cu")
		(net "SMB_PDB_MISC_SDA")
	)
	(segment
		(start 450.342 -40.74795)
		(end 450.342 -40.132)
		(width 0.17272)
		(layer "F.Cu")
		(net "SMB_PDB_MISC_SDA")
	)
	(segment
		(start 431.8254 -37.126926)
		(end 431.99812 -36.954206)
		(width 0.17272)
		(layer "F.Cu")
		(net "SMB_PDB_MISC_SDA")
	)
	(segment
		(start 432.4604 -43.561)
		(end 432.689 -43.3324)
		(width 0.17272)
		(layer "F.Cu")
		(net "SMB_PDB_MISC_SDA")
	)
	(segment
		(start 433.93868 -37.660326)
		(end 431.99812 -37.660326)
		(width 0.17272)
		(layer "F.Cu")
		(net "SMB_PDB_MISC_SDA")
	)
	(segment
		(start 430.784 -32.15005)
		(end 431.1904 -31.74365)
		(width 0.17272)
		(layer "F.Cu")
		(net "SMB_PDB_MISC_SDA")
	)
	(segment
		(start 431.8254 -37.487606)
		(end 431.8254 -37.126926)
		(width 0.17272)
		(layer "F.Cu")
		(net "SMB_PDB_MISC_SDA")
	)
	(segment
		(start 450.93128 -39.54272)
		(end 450.342 -40.132)
		(width 0.17272)
		(layer "F.Cu")
		(net "SMB_PDB_MISC_SDA")
	)
	(segment
		(start 430.784 -33.782)
		(end 430.784 -32.15005)
		(width 0.17272)
		(layer "F.Cu")
		(net "SMB_PDB_MISC_SDA")
	)
	(segment
		(start 434.18252 -35.884866)
		(end 433.405534 -35.10788)
		(width 0.17272)
		(layer "F.Cu")
		(net "SMB_PDB_MISC_SDA")
	)
	(segment
		(start 434.1114 -38.193726)
		(end 434.1114 -37.833046)
		(width 0.17272)
		(layer "F.Cu")
		(net "SMB_PDB_MISC_SDA")
	)
	(segment
		(start 431.99812 -37.660326)
		(end 431.8254 -37.487606)
		(width 0.17272)
		(layer "F.Cu")
		(net "SMB_PDB_MISC_SDA")
	)
	(segment
		(start 432.637946 -34.8488)
		(end 431.8508 -34.8488)
		(width 0.17272)
		(layer "F.Cu")
		(net "SMB_PDB_MISC_SDA")
	)
	(segment
		(start 433.07 -38.366446)
		(end 433.93868 -38.366446)
		(width 0.17272)
		(layer "F.Cu")
		(net "SMB_PDB_MISC_SDA")
	)
	(via
		(at 428.23765 -47.371)
		(size 0.508)
		(drill 0.254)
		(layers "F.Cu" "B.Cu")
		(net "SMB_PDB_MISC_SDA")
	)
	(via
		(at 450.342 -40.132)
		(size 0.508)
		(drill 0.254)
		(layers "F.Cu" "B.Cu")
		(net "SMB_PDB_MISC_SDA")
	)
	(via
		(at 432.4604 -43.561)
		(size 0.508)
		(drill 0.254)
		(layers "F.Cu" "B.Cu")
		(net "SMB_PDB_MISC_SDA")
	)
	(segment
		(start 429.32985 -35.687)
		(end 427.24705 -35.687)
		(width 0.17272)
		(layer "B.Cu")
		(net "SMB_PDB_MISC_SDA")
	)
	(segment
		(start 430.784 -43.815)
		(end 430.20488 -43.23588)
		(width 0.17272)
		(layer "B.Cu")
		(net "SMB_PDB_MISC_SDA")
	)
	(segment
		(start 432.4604 -43.561)
		(end 432.2064 -43.815)
		(width 0.17272)
		(layer "B.Cu")
		(net "SMB_PDB_MISC_SDA")
	)
	(segment
		(start 427.24705 -35.687)
		(end 426.99305 -35.941)
		(width 0.17272)
		(layer "B.Cu")
		(net "SMB_PDB_MISC_SDA")
	)
	(segment
		(start 430.20488 -43.23588)
		(end 430.20488 -36.56203)
		(width 0.17272)
		(layer "B.Cu")
		(net "SMB_PDB_MISC_SDA")
	)
	(segment
		(start 430.20488 -36.56203)
		(end 429.32985 -35.687)
		(width 0.17272)
		(layer "B.Cu")
		(net "SMB_PDB_MISC_SDA")
	)
	(segment
		(start 432.2064 -43.815)
		(end 430.784 -43.815)
		(width 0.17272)
		(layer "B.Cu")
		(net "SMB_PDB_MISC_SDA")
	)
	(segment
		(start 449.355464 -41.118536)
		(end 437.866282 -41.118536)
		(width 0.12954)
		(layer "In2.Cu")
		(net "SMB_PDB_MISC_SDA")
	)
	(segment
		(start 437.866282 -41.118536)
		(end 436.947818 -42.037)
		(width 0.12954)
		(layer "In2.Cu")
		(net "SMB_PDB_MISC_SDA")
	)
	(segment
		(start 434.584856 -42.681144)
		(end 432.4604 -43.561)
		(width 0.12954)
		(layer "In2.Cu")
		(net "SMB_PDB_MISC_SDA")
	)
	(segment
		(start 435.229 -42.037)
		(end 434.584856 -42.681144)
		(width 0.12954)
		(layer "In2.Cu")
		(net "SMB_PDB_MISC_SDA")
	)
	(segment
		(start 436.947818 -42.037)
		(end 435.229 -42.037)
		(width 0.12954)
		(layer "In2.Cu")
		(net "SMB_PDB_MISC_SDA")
	)
	(segment
		(start 432.4604 -43.561)
		(end 430.509172 -44.369228)
		(width 0.12954)
		(layer "In2.Cu")
		(net "SMB_PDB_MISC_SDA")
	)
	(segment
		(start 450.342 -40.132)
		(end 449.355464 -41.118536)
		(width 0.12954)
		(layer "In2.Cu")
		(net "SMB_PDB_MISC_SDA")
	)
	(segment
		(start 428.23765 -46.64075)
		(end 428.23765 -47.371)
		(width 0.12954)
		(layer "In2.Cu")
		(net "SMB_PDB_MISC_SDA")
	)
	(segment
		(start 430.509172 -44.369228)
		(end 428.23765 -46.64075)
		(width 0.12954)
		(layer "In2.Cu")
		(net "SMB_PDB_MISC_SDA")
	)
	(segment
		(start 169.356786 -66.167)
		(end 169.845736 -66.65595)
		(width 0.17272)
		(layer "F.Cu")
		(net "P52V_HS2_ADR0")
	)
	(segment
		(start 171.740576 -70.08876)
		(end 172.512736 -70.86092)
		(width 0.17272)
		(layer "F.Cu")
		(net "P52V_HS2_ADR0")
	)
	(segment
		(start 166.943786 -66.167)
		(end 166.943786 -66.802)
		(width 0.17272)
		(layer "F.Cu")
		(net "P52V_HS2_ADR0")
	)
	(segment
		(start 169.356786 -66.167)
		(end 168.737026 -65.54724)
		(width 0.17272)
		(layer "F.Cu")
		(net "P52V_HS2_ADR0")
	)
	(segment
		(start 169.845736 -66.65595)
		(end 169.845736 -69.128386)
		(width 0.17272)
		(layer "F.Cu")
		(net "P52V_HS2_ADR0")
	)
	(segment
		(start 170.80611 -70.08876)
		(end 171.740576 -70.08876)
		(width 0.17272)
		(layer "F.Cu")
		(net "P52V_HS2_ADR0")
	)
	(segment
		(start 169.845736 -69.128386)
		(end 170.80611 -70.08876)
		(width 0.17272)
		(layer "F.Cu")
		(net "P52V_HS2_ADR0")
	)
	(segment
		(start 168.737026 -65.54724)
		(end 167.563546 -65.54724)
		(width 0.17272)
		(layer "F.Cu")
		(net "P52V_HS2_ADR0")
	)
	(segment
		(start 167.563546 -65.54724)
		(end 166.943786 -66.167)
		(width 0.17272)
		(layer "F.Cu")
		(net "P52V_HS2_ADR0")
	)
	(via
		(at 166.943786 -66.802)
		(size 0.508)
		(drill 0.254)
		(layers "F.Cu" "B.Cu")
		(net "P52V_HS2_ADR0")
	)
	(via
		(at 172.512736 -70.86092)
		(size 0.508)
		(drill 0.254)
		(layers "F.Cu" "B.Cu")
		(net "P52V_HS2_ADR0")
	)
	(via
		(at 155.621736 -75.438)
		(size 0.762)
		(drill 0.254)
		(layers "F.Cu" "B.Cu")
		(net "P52V_HS2_ADR0")
	)
	(segment
		(start 155.847796 -73.504044)
		(end 155.847796 -75.21194)
		(width 0.17272)
		(layer "B.Cu")
		(net "P52V_HS2_ADR0")
	)
	(segment
		(start 155.847796 -75.21194)
		(end 155.621736 -75.438)
		(width 0.17272)
		(layer "B.Cu")
		(net "P52V_HS2_ADR0")
	)
	(segment
		(start 155.621736 -75.438)
		(end 155.621736 -76.81595)
		(width 0.17272)
		(layer "B.Cu")
		(net "P52V_HS2_ADR0")
	)
	(segment
		(start 155.545282 -76.81595)
		(end 155.001976 -77.359256)
		(width 0.17272)
		(layer "B.Cu")
		(net "P52V_HS2_ADR0")
	)
	(segment
		(start 155.621736 -76.81595)
		(end 155.545282 -76.81595)
		(width 0.17272)
		(layer "B.Cu")
		(net "P52V_HS2_ADR0")
	)
	(segment
		(start 155.001976 -77.359256)
		(end 155.001976 -78.35519)
		(width 0.17272)
		(layer "B.Cu")
		(net "P52V_HS2_ADR0")
	)
	(segment
		(start 173.516036 -70.86092)
		(end 172.512736 -70.86092)
		(width 0.17272)
		(layer "B.Cu")
		(net "P52V_HS2_ADR0")
	)
	(segment
		(start 155.001976 -78.35519)
		(end 155.621736 -78.97495)
		(width 0.17272)
		(layer "B.Cu")
		(net "P52V_HS2_ADR0")
	)
	(segment
		(start 166.943786 -68.170044)
		(end 166.943786 -66.802)
		(width 0.12954)
		(layer "In2.Cu")
		(net "P52V_HS2_ADR0")
	)
	(segment
		(start 159.67583 -75.438)
		(end 166.943786 -68.170044)
		(width 0.12954)
		(layer "In2.Cu")
		(net "P52V_HS2_ADR0")
	)
	(segment
		(start 155.621736 -75.438)
		(end 159.67583 -75.438)
		(width 0.12954)
		(layer "In2.Cu")
		(net "P52V_HS2_ADR0")
	)
	(segment
		(start 380.803912 -16.395192)
		(end 380.803912 -17.507204)
		(width 0.17272)
		(layer "F.Cu")
		(net "RST_SMB_FAN_0_R_N")
	)
	(segment
		(start 380.53772 -16.129)
		(end 380.803912 -16.395192)
		(width 0.17272)
		(layer "F.Cu")
		(net "RST_SMB_FAN_0_R_N")
	)
	(via
		(at 380.53772 -16.129)
		(size 0.762)
		(drill 0.254)
		(layers "F.Cu" "B.Cu")
		(net "RST_SMB_FAN_0_R_N")
	)
	(segment
		(start 374.221502 -6.937502)
		(end 380.53772 -13.25372)
		(width 0.17272)
		(layer "B.Cu")
		(net "RST_SMB_FAN_0_R_N")
	)
	(segment
		(start 374.221502 -5.388102)
		(end 374.221502 -6.937502)
		(width 0.17272)
		(layer "B.Cu")
		(net "RST_SMB_FAN_0_R_N")
	)
	(segment
		(start 380.53772 -13.25372)
		(end 380.53772 -16.129)
		(width 0.17272)
		(layer "B.Cu")
		(net "RST_SMB_FAN_0_R_N")
	)
	(segment
		(start 372.160038 -3.326638)
		(end 374.221502 -5.388102)
		(width 0.17272)
		(layer "B.Cu")
		(net "RST_SMB_FAN_0_R_N")
	)
	(segment
		(start 372.160038 -2.035048)
		(end 372.160038 -3.326638)
		(width 0.17272)
		(layer "B.Cu")
		(net "RST_SMB_FAN_0_R_N")
	)
	(via
		(at 357.18242 -5.353304)
		(size 0.762)
		(drill 0.254)
		(layers "F.Cu" "B.Cu")
		(net "P52V_FAN")
	)
	(via
		(at 83.439 -3.81)
		(size 0.508)
		(drill 0.254)
		(layers "F.Cu" "B.Cu")
		(net "P52V_FAN")
	)
	(via
		(at 84.963 -5.334)
		(size 0.508)
		(drill 0.254)
		(layers "F.Cu" "B.Cu")
		(net "P52V_FAN")
	)
	(via
		(at 356.42042 -3.829304)
		(size 0.508)
		(drill 0.254)
		(layers "F.Cu" "B.Cu")
		(net "P52V_FAN")
	)
	(via
		(at 84.201 -4.572)
		(size 0.508)
		(drill 0.254)
		(layers "F.Cu" "B.Cu")
		(net "P52V_FAN")
	)
	(via
		(at 85.725 -4.572)
		(size 0.508)
		(drill 0.254)
		(layers "F.Cu" "B.Cu")
		(net "P52V_FAN")
	)
	(via
		(at 354.89642 -4.591304)
		(size 0.508)
		(drill 0.254)
		(layers "F.Cu" "B.Cu")
		(net "P52V_FAN")
	)
	(via
		(at 355.65842 -4.591304)
		(size 0.508)
		(drill 0.254)
		(layers "F.Cu" "B.Cu")
		(net "P52V_FAN")
	)
	(via
		(at 355.65842 -3.829304)
		(size 0.762)
		(drill 0.254)
		(layers "F.Cu" "B.Cu")
		(net "P52V_FAN")
	)
	(via
		(at 357.94442 -3.829304)
		(size 0.508)
		(drill 0.254)
		(layers "F.Cu" "B.Cu")
		(net "P52V_FAN")
	)
	(via
		(at 356.42042 -5.353304)
		(size 0.508)
		(drill 0.254)
		(layers "F.Cu" "B.Cu")
		(net "P52V_FAN")
	)
	(via
		(at 86.487 -3.81)
		(size 0.508)
		(drill 0.254)
		(layers "F.Cu" "B.Cu")
		(net "P52V_FAN")
	)
	(via
		(at 357.94442 -4.591304)
		(size 0.508)
		(drill 0.254)
		(layers "F.Cu" "B.Cu")
		(net "P52V_FAN")
	)
	(via
		(at 357.18242 -3.829304)
		(size 0.508)
		(drill 0.254)
		(layers "F.Cu" "B.Cu")
		(net "P52V_FAN")
	)
	(via
		(at 82.677 -5.334)
		(size 0.508)
		(drill 0.254)
		(layers "F.Cu" "B.Cu")
		(net "P52V_FAN")
	)
	(via
		(at 85.725 -3.81)
		(size 0.508)
		(drill 0.254)
		(layers "F.Cu" "B.Cu")
		(net "P52V_FAN")
	)
	(via
		(at 83.439 -5.334)
		(size 0.508)
		(drill 0.254)
		(layers "F.Cu" "B.Cu")
		(net "P52V_FAN")
	)
	(via
		(at 86.487 -5.334)
		(size 0.508)
		(drill 0.254)
		(layers "F.Cu" "B.Cu")
		(net "P52V_FAN")
	)
	(via
		(at 84.201 -3.81)
		(size 0.508)
		(drill 0.254)
		(layers "F.Cu" "B.Cu")
		(net "P52V_FAN")
	)
	(via
		(at 357.18242 -4.591304)
		(size 0.508)
		(drill 0.254)
		(layers "F.Cu" "B.Cu")
		(net "P52V_FAN")
	)
	(via
		(at 84.963 -3.81)
		(size 0.508)
		(drill 0.254)
		(layers "F.Cu" "B.Cu")
		(net "P52V_FAN")
	)
	(via
		(at 86.487 -4.572)
		(size 0.508)
		(drill 0.254)
		(layers "F.Cu" "B.Cu")
		(net "P52V_FAN")
	)
	(via
		(at 356.42042 -4.591304)
		(size 0.508)
		(drill 0.254)
		(layers "F.Cu" "B.Cu")
		(net "P52V_FAN")
	)
	(via
		(at 358.70642 -3.829304)
		(size 0.508)
		(drill 0.254)
		(layers "F.Cu" "B.Cu")
		(net "P52V_FAN")
	)
	(via
		(at 84.201 -5.334)
		(size 0.508)
		(drill 0.254)
		(layers "F.Cu" "B.Cu")
		(net "P52V_FAN")
	)
	(via
		(at 85.725 -5.334)
		(size 0.508)
		(drill 0.254)
		(layers "F.Cu" "B.Cu")
		(net "P52V_FAN")
	)
	(via
		(at 354.89642 -3.829304)
		(size 0.508)
		(drill 0.254)
		(layers "F.Cu" "B.Cu")
		(net "P52V_FAN")
	)
	(via
		(at 355.65842 -5.353304)
		(size 0.508)
		(drill 0.254)
		(layers "F.Cu" "B.Cu")
		(net "P52V_FAN")
	)
	(via
		(at 83.439 -4.572)
		(size 0.508)
		(drill 0.254)
		(layers "F.Cu" "B.Cu")
		(net "P52V_FAN")
	)
	(via
		(at 82.677 -4.572)
		(size 0.508)
		(drill 0.254)
		(layers "F.Cu" "B.Cu")
		(net "P52V_FAN")
	)
	(via
		(at 354.89642 -5.353304)
		(size 0.508)
		(drill 0.254)
		(layers "F.Cu" "B.Cu")
		(net "P52V_FAN")
	)
	(via
		(at 82.677 -3.81)
		(size 0.508)
		(drill 0.254)
		(layers "F.Cu" "B.Cu")
		(net "P52V_FAN")
	)
	(via
		(at 358.70642 -4.591304)
		(size 0.508)
		(drill 0.254)
		(layers "F.Cu" "B.Cu")
		(net "P52V_FAN")
	)
	(via
		(at 358.70642 -5.353304)
		(size 0.508)
		(drill 0.254)
		(layers "F.Cu" "B.Cu")
		(net "P52V_FAN")
	)
	(via
		(at 84.963 -4.572)
		(size 0.508)
		(drill 0.254)
		(layers "F.Cu" "B.Cu")
		(net "P52V_FAN")
	)
	(via
		(at 357.94442 -5.353304)
		(size 0.508)
		(drill 0.254)
		(layers "F.Cu" "B.Cu")
		(net "P52V_FAN")
	)
	(segment
		(start 429.2854 -29.464)
		(end 429.2854 -30.94355)
		(width 0.17272)
		(layer "F.Cu")
		(net "FRU_WP_N")
	)
	(segment
		(start 429.2854 -30.94355)
		(end 429.494696 -30.94355)
		(width 0.17272)
		(layer "F.Cu")
		(net "FRU_WP_N")
	)
	(segment
		(start 429.494696 -30.94355)
		(end 430.022 -31.470854)
		(width 0.17272)
		(layer "F.Cu")
		(net "FRU_WP_N")
	)
	(segment
		(start 429.584104 -33.73755)
		(end 429.2854 -33.73755)
		(width 0.17272)
		(layer "F.Cu")
		(net "FRU_WP_N")
	)
	(segment
		(start 430.8094 -27.2542)
		(end 430.8094 -27.94)
		(width 0.17272)
		(layer "F.Cu")
		(net "FRU_WP_N")
	)
	(segment
		(start 430.022 -33.299654)
		(end 429.584104 -33.73755)
		(width 0.17272)
		(layer "F.Cu")
		(net "FRU_WP_N")
	)
	(segment
		(start 430.8094 -27.94)
		(end 429.2854 -29.464)
		(width 0.17272)
		(layer "F.Cu")
		(net "FRU_WP_N")
	)
	(segment
		(start 430.022 -31.470854)
		(end 430.022 -33.299654)
		(width 0.17272)
		(layer "F.Cu")
		(net "FRU_WP_N")
	)
	(via
		(at 429.2854 -29.464)
		(size 0.762)
		(drill 0.381)
		(layers "F.Cu" "B.Cu")
		(net "FRU_WP_N")
	)
	(segment
		(start 432.0794 -21.971)
		(end 432.0794 -22.987)
		(width 0.17272)
		(layer "F.Cu")
		(net "FRU_ADDR2")
	)
	(segment
		(start 435.13375 -22.352)
		(end 435.75351 -22.97176)
		(width 0.17272)
		(layer "F.Cu")
		(net "FRU_ADDR2")
	)
	(segment
		(start 432.4604 -23.368)
		(end 433.3494 -23.368)
		(width 0.17272)
		(layer "F.Cu")
		(net "FRU_ADDR2")
	)
	(segment
		(start 433.3494 -23.368)
		(end 434.11775 -23.368)
		(width 0.17272)
		(layer "F.Cu")
		(net "FRU_ADDR2")
	)
	(segment
		(start 435.75351 -22.97176)
		(end 437.30799 -22.97176)
		(width 0.17272)
		(layer "F.Cu")
		(net "FRU_ADDR2")
	)
	(segment
		(start 434.11775 -23.368)
		(end 435.13375 -22.352)
		(width 0.17272)
		(layer "F.Cu")
		(net "FRU_ADDR2")
	)
	(segment
		(start 432.0794 -22.987)
		(end 432.4604 -23.368)
		(width 0.17272)
		(layer "F.Cu")
		(net "FRU_ADDR2")
	)
	(segment
		(start 437.30799 -22.97176)
		(end 437.92775 -22.352)
		(width 0.17272)
		(layer "F.Cu")
		(net "FRU_ADDR2")
	)
	(via
		(at 433.3494 -23.368)
		(size 0.508)
		(drill 0.254)
		(layers "F.Cu" "B.Cu")
		(net "FRU_ADDR2")
	)
	(zone
		(layer "F.Cu")
		(hatch none 0.5)
		(connect_pads
			(clearance 0)
		)
		(min_thickness 0.25)
		(keepout
			(tracks allowed)
			(vias allowed)
			(pads allowed)
			(copperpour allowed)
			(footprints not_allowed)
		)
		(placement
			(enabled no)
			(sheetname "")
		)
		(fill
			(thermal_gap 0.5)
			(thermal_bridge_width 0.5)
			(island_removal_mode 0)
		)
		(polygon
			(pts
				(arc
					(start 236.70006 -79.630016)
					(mid 238.810038 -77.520038)
					(end 240.920016 -79.630016)
				)
				(arc
					(start 240.920016 -79.630016)
					(mid 238.810038 -81.739994)
					(end 236.70006 -79.630016)
				)
			)
		)
	)
	(zone
		(layer "F.Cu")
		(hatch none 0.5)
		(connect_pads
			(clearance 0)
		)
		(min_thickness 0.25)
		(keepout
			(tracks allowed)
			(vias allowed)
			(pads allowed)
			(copperpour allowed)
			(footprints not_allowed)
		)
		(placement
			(enabled no)
			(sheetname "")
		)
		(fill
			(thermal_gap 0.5)
			(thermal_bridge_width 0.5)
			(island_removal_mode 0)
		)
		(polygon
			(pts
				(xy 439.999882 -65.099946) (xy 434.999892 -65.099946) (xy 434.999892 -55.099966) (xy 439.999882 -55.099966)
			)
		)
	)
	(zone
		(layer "F.Cu")
		(hatch none 0.5)
		(connect_pads
			(clearance 0)
		)
		(min_thickness 0.25)
		(keepout
			(tracks allowed)
			(vias allowed)
			(pads allowed)
			(copperpour allowed)
			(footprints not_allowed)
		)
		(placement
			(enabled no)
			(sheetname "")
		)
		(fill
			(thermal_gap 0.5)
			(thermal_bridge_width 0.5)
			(island_removal_mode 0)
		)
		(polygon
			(pts
				(xy 194.509898 -16.740124) (xy 215.490044 -16.740124) (xy 215.490044 -85.419946) (xy 194.509898 -85.419946)
			)
		)
	)
	(zone
		(layer "F.Cu")
		(hatch none 0.5)
		(connect_pads
			(clearance 0)
		)
		(min_thickness 0.25)
		(keepout
			(tracks not_allowed)
			(vias allowed)
			(pads allowed)
			(copperpour not_allowed)
			(footprints allowed)
		)
		(placement
			(enabled no)
			(sheetname "")
		)
		(fill
			(thermal_gap 0.5)
			(thermal_bridge_width 0.5)
			(island_removal_mode 0)
		)
		(polygon
			(pts
				(arc
					(start 185.50001 -87.499952)
					(mid 190.000128 -82.999834)
					(end 194.499992 -87.499952)
				)
				(arc
					(start 194.499992 -92.499942)
					(mid 190.000128 -96.999806)
					(end 185.50001 -92.499942)
				)
			)
		)
		(polygon
			(pts
				(arc
					(start 188.500004 -89.03589)
					(mid 188.343076 -90.145338)
					(end 187.884562 -91.167712)
				)
				(arc
					(start 187.884562 -91.167712)
					(mid 190.000196 -95.000423)
					(end 192.11544 -91.167712)
				)
				(arc
					(start 192.11544 -91.167712)
					(mid 191.656975 -90.145324)
					(end 191.499998 -89.03589)
				)
				(arc
					(start 191.499998 -87.499952)
					(mid 190.000128 -86.000082)
					(end 188.500004 -87.499952)
				)
			)
		)
	)
	(zone
		(layer "F.Cu")
		(hatch none 0.5)
		(connect_pads
			(clearance 0)
		)
		(min_thickness 0.25)
		(keepout
			(tracks allowed)
			(vias allowed)
			(pads allowed)
			(copperpour allowed)
			(footprints not_allowed)
		)
		(placement
			(enabled no)
			(sheetname "")
		)
		(fill
			(thermal_gap 0.5)
			(thermal_bridge_width 0.5)
			(island_removal_mode 0)
		)
		(polygon
			(pts
				(arc
					(start 455.099928 -137.500106)
					(mid 431.8 -160.800034)
					(end 408.500072 -137.500106)
				)
				(arc
					(start 408.500072 -137.500106)
					(mid 431.8 -114.200178)
					(end 455.099928 -137.500106)
				)
			)
		)
	)
	(zone
		(layer "F.Cu")
		(hatch none 0.5)
		(connect_pads
			(clearance 0)
		)
		(min_thickness 0.25)
		(keepout
			(tracks allowed)
			(vias allowed)
			(pads allowed)
			(copperpour allowed)
			(footprints not_allowed)
		)
		(placement
			(enabled no)
			(sheetname "")
		)
		(fill
			(thermal_gap 0.5)
			(thermal_bridge_width 0.5)
			(island_removal_mode 0)
		)
		(polygon
			(pts
				(xy 245.49989 -27.500072) (xy 257.50012 -27.500072) (xy 257.50012 -7.500112) (xy 342.49995 -7.500112)
				(xy 342.49995 -16.500094) (xy 360.499914 -16.500094) (xy 360.499914 -27.500072) (xy 368.000026 -27.500072)
				(xy 368.000026 -80.000094) (xy 245.49989 -80.000094)
			)
		)
	)
	(zone
		(layer "F.Cu")
		(hatch none 0.5)
		(connect_pads
			(clearance 0)
		)
		(min_thickness 0.25)
		(keepout
			(tracks allowed)
			(vias allowed)
			(pads allowed)
			(copperpour allowed)
			(footprints not_allowed)
		)
		(placement
			(enabled no)
			(sheetname "")
		)
		(fill
			(thermal_gap 0.5)
			(thermal_bridge_width 0.5)
			(island_removal_mode 0)
		)
		(polygon
			(pts
				(xy 31.500064 -32.500062) (xy 72.00011 -32.500062) (xy 72.00011 -147.500086) (xy 31.500064 -147.500086)
			)
		)
	)
	(zone
		(layer "F.Cu")
		(hatch none 0.5)
		(connect_pads
			(clearance 0)
		)
		(min_thickness 0.25)
		(keepout
			(tracks allowed)
			(vias allowed)
			(pads allowed)
			(copperpour allowed)
			(footprints allowed)
		)
		(placement
			(enabled no)
			(sheetname "")
		)
		(fill
			(thermal_gap 0.5)
			(thermal_bridge_width 0.5)
			(island_removal_mode 0)
		)
		(polygon
			(pts
				(xy 415.798 -29.464) (xy 415.798 -28.0162) (xy 420.497 -28.0162) (xy 420.497 -29.464)
			)
		)
	)
	(zone
		(layer "F.Cu")
		(hatch none 0.5)
		(connect_pads
			(clearance 0)
		)
		(min_thickness 0.25)
		(keepout
			(tracks not_allowed)
			(vias allowed)
			(pads allowed)
			(copperpour not_allowed)
			(footprints allowed)
		)
		(placement
			(enabled no)
			(sheetname "")
		)
		(fill
			(thermal_gap 0.5)
			(thermal_bridge_width 0.5)
			(island_removal_mode 0)
		)
		(polygon
			(pts
				(arc
					(start 7.500112 -84.000086)
					(mid 12.00023 -79.499968)
					(end 16.500094 -84.000086)
				)
				(arc
					(start 16.500094 -89.000076)
					(mid 12.00023 -93.49994)
					(end 7.500112 -89.000076)
				)
			)
		)
		(polygon
			(pts
				(arc
					(start 10.500106 -85.536024)
					(mid 10.343125 -86.645329)
					(end 9.884664 -87.667592)
				)
				(arc
					(start 9.884664 -87.667592)
					(mid 11.999976 -91.499698)
					(end 14.115288 -87.667592)
				)
				(arc
					(start 14.115288 -87.667592)
					(mid 13.65693 -86.645319)
					(end 13.5001 -85.536024)
				)
				(arc
					(start 13.5001 -84.000086)
					(mid 12.00023 -82.500216)
					(end 10.500106 -84.000086)
				)
			)
		)
	)
	(zone
		(layer "F.Cu")
		(hatch none 0.5)
		(connect_pads
			(clearance 0)
		)
		(min_thickness 0.25)
		(keepout
			(tracks not_allowed)
			(vias allowed)
			(pads allowed)
			(copperpour not_allowed)
			(footprints allowed)
		)
		(placement
			(enabled no)
			(sheetname "")
		)
		(fill
			(thermal_gap 0.5)
			(thermal_bridge_width 0.5)
			(island_removal_mode 0)
		)
		(polygon
			(pts
				(arc
					(start 335.499964 -87.499952)
					(mid 340.000082 -82.999834)
					(end 344.499946 -87.499952)
				)
				(arc
					(start 344.499946 -92.499942)
					(mid 340.000082 -96.999806)
					(end 335.499964 -92.499942)
				)
			)
		)
		(polygon
			(pts
				(arc
					(start 338.499958 -89.03589)
					(mid 338.34303 -90.145338)
					(end 337.884516 -91.167712)
				)
				(arc
					(start 337.884516 -91.167712)
					(mid 340.00015 -95.000423)
					(end 342.115394 -91.167712)
				)
				(arc
					(start 342.115394 -91.167712)
					(mid 341.656929 -90.145324)
					(end 341.499952 -89.03589)
				)
				(arc
					(start 341.499952 -87.499952)
					(mid 340.000082 -86.000082)
					(end 338.499958 -87.499952)
				)
			)
		)
	)
	(zone
		(layer "F.Cu")
		(hatch none 0.5)
		(connect_pads
			(clearance 0)
		)
		(min_thickness 0.25)
		(keepout
			(tracks not_allowed)
			(vias allowed)
			(pads allowed)
			(copperpour not_allowed)
			(footprints allowed)
		)
		(placement
			(enabled no)
			(sheetname "")
		)
		(fill
			(thermal_gap 0.5)
			(thermal_bridge_width 0.5)
			(island_removal_mode 0)
		)
		(polygon
			(pts
				(arc
					(start 355.499924 -142.500096)
					(mid 360.000042 -137.999978)
					(end 364.499906 -142.500096)
				)
				(arc
					(start 364.499906 -147.500086)
					(mid 360.000042 -151.99995)
					(end 355.499924 -147.500086)
				)
			)
		)
		(polygon
			(pts
				(arc
					(start 358.499918 -144.03578)
					(mid 358.343065 -145.145186)
					(end 357.88473 -146.167602)
				)
				(arc
					(start 357.88473 -146.167602)
					(mid 360.000042 -149.999708)
					(end 362.115354 -146.167602)
				)
				(arc
					(start 362.115354 -146.167602)
					(mid 361.656889 -145.145214)
					(end 361.499912 -144.03578)
				)
				(arc
					(start 361.499912 -142.500096)
					(mid 360.000042 -141.000226)
					(end 358.499918 -142.500096)
				)
			)
		)
	)
	(zone
		(layer "F.Cu")
		(hatch none 0.5)
		(connect_pads
			(clearance 0)
		)
		(min_thickness 0.25)
		(keepout
			(tracks allowed)
			(vias allowed)
			(pads allowed)
			(copperpour allowed)
			(footprints not_allowed)
		)
		(placement
			(enabled no)
			(sheetname "")
		)
		(fill
			(thermal_gap 0.5)
			(thermal_bridge_width 0.5)
			(island_removal_mode 0)
		)
		(polygon
			(pts
				(arc
					(start 425.172124 -0.999744)
					(mid 423.939575 -2.560515)
					(end 423.500042 -4.500118)
				)
				(arc
					(start 423.500042 -9.500108)
					(mid 428.00016 -14.000226)
					(end 432.500024 -9.500108)
				)
				(arc
					(start 432.500024 -4.500118)
					(mid 432.060676 -2.560734)
					(end 430.82845 -0.999998)
				)
				(arc
					(start 434.999892 -0.999998)
					(mid 437.828313 -2.171569)
					(end 438.999884 -4.99999)
				)
				(arc
					(start 438.999884 -11.770106)
					(mid 440.757404 -16.012754)
					(end 445.000126 -17.770094)
				)
				(xy 452.000112 -17.770094) (xy 452.000112 -55.099966) (xy 408.500072 -55.099966) (xy 408.500072 -32.500062)
				(xy 368.000026 -32.500062) (xy 368.000026 -24.249888) (xy 376.050048 -24.249888) (xy 376.050048 -16.500094)
				(xy 397.171926 -16.500094) (xy 397.171926 -0.999998)
			)
		)
	)
	(zone
		(layer "F.Cu")
		(hatch none 0.5)
		(connect_pads
			(clearance 0)
		)
		(min_thickness 0.25)
		(keepout
			(tracks not_allowed)
			(vias allowed)
			(pads allowed)
			(copperpour not_allowed)
			(footprints allowed)
		)
		(placement
			(enabled no)
			(sheetname "")
		)
		(fill
			(thermal_gap 0.5)
			(thermal_bridge_width 0.5)
			(island_removal_mode 0)
		)
		(polygon
			(pts
				(arc
					(start 452.499984 -24.500078)
					(mid 457.000102 -19.99996)
					(end 461.499966 -24.500078)
				)
				(arc
					(start 461.499966 -29.500068)
					(mid 457.000102 -33.999932)
					(end 452.499984 -29.500068)
				)
			)
		)
		(polygon
			(pts
				(arc
					(start 455.499978 -26.036016)
					(mid 455.342997 -27.145321)
					(end 454.884536 -28.167584)
				)
				(arc
					(start 454.884536 -28.167584)
					(mid 457.00017 -32.000295)
					(end 459.115414 -28.167584)
				)
				(arc
					(start 459.115414 -28.167584)
					(mid 458.656926 -27.145328)
					(end 458.499972 -26.036016)
				)
				(arc
					(start 458.499972 -24.500078)
					(mid 457.000102 -23.000208)
					(end 455.499978 -24.500078)
				)
			)
		)
	)
	(zone
		(layer "F.Cu")
		(hatch none 0.5)
		(connect_pads
			(clearance 0)
		)
		(min_thickness 0.25)
		(keepout
			(tracks not_allowed)
			(vias allowed)
			(pads allowed)
			(copperpour not_allowed)
			(footprints allowed)
		)
		(placement
			(enabled no)
			(sheetname "")
		)
		(fill
			(thermal_gap 0.5)
			(thermal_bridge_width 0.5)
			(island_removal_mode 0)
		)
		(polygon
			(pts
				(arc
					(start 185.50001 -16.500094)
					(mid 190.000128 -11.999976)
					(end 194.499992 -16.500094)
				)
				(arc
					(start 194.499992 -21.500084)
					(mid 190.000128 -25.999948)
					(end 185.50001 -21.500084)
				)
			)
		)
		(polygon
			(pts
				(arc
					(start 188.500004 -18.035778)
					(mid 188.343076 -19.145226)
					(end 187.884562 -20.1676)
				)
				(arc
					(start 187.884562 -20.1676)
					(mid 190.000196 -24.000311)
					(end 192.11544 -20.1676)
				)
				(arc
					(start 192.11544 -20.1676)
					(mid 191.656975 -19.145212)
					(end 191.499998 -18.035778)
				)
				(arc
					(start 191.499998 -16.500094)
					(mid 190.000128 -15.000224)
					(end 188.500004 -16.500094)
				)
			)
		)
	)
	(zone
		(layer "F.Cu")
		(hatch none 0.5)
		(connect_pads
			(clearance 0)
		)
		(min_thickness 0.25)
		(keepout
			(tracks allowed)
			(vias allowed)
			(pads allowed)
			(copperpour allowed)
			(footprints not_allowed)
		)
		(placement
			(enabled no)
			(sheetname "")
		)
		(fill
			(thermal_gap 0.5)
			(thermal_bridge_width 0.5)
			(island_removal_mode 0)
		)
		(polygon
			(pts
				(xy 224.510092 -16.740124) (xy 245.489984 -16.740124) (xy 245.489984 -85.419946) (xy 224.510092 -85.419946)
			)
		)
	)
	(zone
		(layer "F.Cu")
		(hatch none 0.5)
		(connect_pads
			(clearance 0)
		)
		(min_thickness 0.25)
		(keepout
			(tracks allowed)
			(vias allowed)
			(pads allowed)
			(copperpour allowed)
			(footprints not_allowed)
		)
		(placement
			(enabled no)
			(sheetname "")
		)
		(fill
			(thermal_gap 0.5)
			(thermal_bridge_width 0.5)
			(island_removal_mode 0)
		)
		(polygon
			(pts
				(xy 439.999882 -105.000044) (xy 434.999892 -105.000044) (xy 434.999892 -95.000064) (xy 439.999882 -95.000064)
			)
		)
	)
	(zone
		(layer "F.Cu")
		(hatch none 0.5)
		(connect_pads
			(clearance 0)
		)
		(min_thickness 0.25)
		(keepout
			(tracks allowed)
			(vias allowed)
			(pads allowed)
			(copperpour allowed)
			(footprints not_allowed)
		)
		(placement
			(enabled no)
			(sheetname "")
		)
		(fill
			(thermal_gap 0.5)
			(thermal_bridge_width 0.5)
			(island_removal_mode 0)
		)
		(polygon
			(pts
				(xy 471.499946 -109.549946) (xy 465.000086 -109.549946) (xy 465.000086 -105.050082) (xy 471.499946 -105.050082)
			)
		)
	)
	(zone
		(layer "F.Cu")
		(hatch none 0.5)
		(connect_pads
			(clearance 0)
		)
		(min_thickness 0.25)
		(keepout
			(tracks allowed)
			(vias allowed)
			(pads allowed)
			(copperpour allowed)
			(footprints not_allowed)
		)
		(placement
			(enabled no)
			(sheetname "")
		)
		(fill
			(thermal_gap 0.5)
			(thermal_bridge_width 0.5)
			(island_removal_mode 0)
		)
		(polygon
			(pts
				(xy 408.500072 -147.500086) (xy 368.000026 -147.500086) (xy 368.000026 -32.500062) (xy 408.500072 -32.500062)
			)
		)
	)
	(zone
		(layer "F.Cu")
		(hatch none 0.5)
		(connect_pads
			(clearance 0)
		)
		(min_thickness 0.25)
		(keepout
			(tracks not_allowed)
			(vias allowed)
			(pads allowed)
			(copperpour not_allowed)
			(footprints allowed)
		)
		(placement
			(enabled no)
			(sheetname "")
		)
		(fill
			(thermal_gap 0.5)
			(thermal_bridge_width 0.5)
			(island_removal_mode 0)
		)
		(polygon
			(pts
				(arc
					(start 245.49989 -16.500094)
					(mid 250.000008 -11.999976)
					(end 254.500126 -16.500094)
				)
				(arc
					(start 254.500126 -21.500084)
					(mid 250.000008 -26.000202)
					(end 245.49989 -21.500084)
				)
			)
		)
		(polygon
			(pts
				(arc
					(start 248.499884 -18.035778)
					(mid 248.343031 -19.145184)
					(end 247.884696 -20.1676)
				)
				(arc
					(start 247.884696 -20.1676)
					(mid 250.000008 -23.999706)
					(end 252.11532 -20.1676)
				)
				(arc
					(start 252.11532 -20.1676)
					(mid 251.656855 -19.145212)
					(end 251.499878 -18.035778)
				)
				(arc
					(start 251.499878 -16.500094)
					(mid 250.000008 -15.000224)
					(end 248.499884 -16.500094)
				)
			)
		)
	)
	(zone
		(layer "F.Cu")
		(hatch none 0.5)
		(connect_pads
			(clearance 0)
		)
		(min_thickness 0.25)
		(keepout
			(tracks allowed)
			(vias allowed)
			(pads allowed)
			(copperpour allowed)
			(footprints not_allowed)
		)
		(placement
			(enabled no)
			(sheetname "")
		)
		(fill
			(thermal_gap 0.5)
			(thermal_bridge_width 0.5)
			(island_removal_mode 0)
		)
		(polygon
			(pts
				(arc
					(start 236.70006 -22.47011)
					(mid 238.810038 -20.360132)
					(end 240.920016 -22.47011)
				)
				(arc
					(start 240.920016 -22.47011)
					(mid 238.810038 -24.580088)
					(end 236.70006 -22.47011)
				)
			)
		)
	)
	(zone
		(layer "F.Cu")
		(hatch none 0.5)
		(connect_pads
			(clearance 0)
		)
		(min_thickness 0.25)
		(keepout
			(tracks not_allowed)
			(vias allowed)
			(pads allowed)
			(copperpour not_allowed)
			(footprints allowed)
		)
		(placement
			(enabled no)
			(sheetname "")
		)
		(fill
			(thermal_gap 0.5)
			(thermal_bridge_width 0.5)
			(island_removal_mode 0)
		)
		(polygon
			(pts
				(arc
					(start 364.499906 -13.5001)
					(mid 369.000024 -8.999982)
					(end 373.499888 -13.5001)
				)
				(arc
					(start 373.499888 -18.50009)
					(mid 369.000024 -22.999954)
					(end 364.499906 -18.50009)
				)
			)
		)
		(polygon
			(pts
				(arc
					(start 367.4999 -15.035784)
					(mid 367.343047 -16.14519)
					(end 366.884712 -17.167606)
				)
				(arc
					(start 366.884712 -17.167606)
					(mid 369.000024 -20.999712)
					(end 371.115336 -17.167606)
				)
				(arc
					(start 371.115336 -17.167606)
					(mid 370.656871 -16.145218)
					(end 370.499894 -15.035784)
				)
				(arc
					(start 370.499894 -13.5001)
					(mid 369.000024 -12.00023)
					(end 367.4999 -13.5001)
				)
			)
		)
	)
	(zone
		(layer "F.Cu")
		(hatch none 0.5)
		(connect_pads
			(clearance 0)
		)
		(min_thickness 0.25)
		(keepout
			(tracks allowed)
			(vias allowed)
			(pads allowed)
			(copperpour allowed)
			(footprints not_allowed)
		)
		(placement
			(enabled no)
			(sheetname "")
		)
		(fill
			(thermal_gap 0.5)
			(thermal_bridge_width 0.5)
			(island_removal_mode 0)
		)
		(polygon
			(pts
				(xy 456.000104 -109.549946) (xy 439.999882 -109.549946) (xy 439.999882 -55.099966) (xy 456.000104 -55.099966)
			)
		)
	)
	(zone
		(layer "F.Cu")
		(hatch none 0.5)
		(connect_pads
			(clearance 0)
		)
		(min_thickness 0.25)
		(keepout
			(tracks allowed)
			(vias allowed)
			(pads allowed)
			(copperpour allowed)
			(footprints not_allowed)
		)
		(placement
			(enabled no)
			(sheetname "")
		)
		(fill
			(thermal_gap 0.5)
			(thermal_bridge_width 0.5)
			(island_removal_mode 0)
		)
		(polygon
			(pts
				(arc
					(start 31.500064 -137.500106)
					(mid 8.200136 -160.800034)
					(end -15.100046 -137.500106)
				)
				(arc
					(start -15.100046 -137.500106)
					(mid 8.200136 -114.199924)
					(end 31.500064 -137.500106)
				)
			)
		)
	)
	(zone
		(layer "F.Cu")
		(hatch none 0.5)
		(connect_pads
			(clearance 0)
		)
		(min_thickness 0.25)
		(keepout
			(tracks not_allowed)
			(vias allowed)
			(pads allowed)
			(copperpour not_allowed)
			(footprints allowed)
		)
		(placement
			(enabled no)
			(sheetname "")
		)
		(fill
			(thermal_gap 0.5)
			(thermal_bridge_width 0.5)
			(island_removal_mode 0)
		)
		(polygon
			(pts
				(arc
					(start 73.594976 -147.500086)
					(mid 80.000094 -153.905204)
					(end 86.404958 -147.500086)
				)
				(arc
					(start 86.404958 -142.500096)
					(mid 80.000094 -136.095232)
					(end 73.594976 -142.500096)
				)
			)
		)
	)
	(zone
		(layer "F.Cu")
		(hatch none 0.5)
		(connect_pads
			(clearance 0)
		)
		(min_thickness 0.25)
		(keepout
			(tracks not_allowed)
			(vias allowed)
			(pads allowed)
			(copperpour not_allowed)
			(footprints allowed)
		)
		(placement
			(enabled no)
			(sheetname "")
		)
		(fill
			(thermal_gap 0.5)
			(thermal_bridge_width 0.5)
			(island_removal_mode 0)
		)
		(polygon
			(pts
				(arc
					(start 20.100036 -126.499874)
					(mid 14.99997 -131.59994)
					(end 9.899904 -126.499874)
				)
				(arc
					(start 9.899904 -126.499874)
					(mid 14.99997 -121.399808)
					(end 20.100036 -126.499874)
				)
			)
		)
		(polygon
			(pts
				(arc
					(start 18.200116 -126.499874)
					(mid 15.000224 -123.299982)
					(end 11.800078 -126.499874)
				)
				(arc
					(start 11.800078 -126.499874)
					(mid 15.000224 -129.70002)
					(end 18.200116 -126.499874)
				)
			)
		)
	)
	(zone
		(layer "F.Cu")
		(hatch none 0.5)
		(connect_pads
			(clearance 0)
		)
		(min_thickness 0.25)
		(keepout
			(tracks allowed)
			(vias allowed)
			(pads allowed)
			(copperpour allowed)
			(footprints not_allowed)
		)
		(placement
			(enabled no)
			(sheetname "")
		)
		(fill
			(thermal_gap 0.5)
			(thermal_bridge_width 0.5)
			(island_removal_mode 0)
		)
		(polygon
			(pts
				(arc
					(start 210.920076 -22.47011)
					(mid 208.810098 -24.580088)
					(end 206.70012 -22.47011)
				)
				(arc
					(start 206.70012 -22.47011)
					(mid 208.810098 -20.360132)
					(end 210.920076 -22.47011)
				)
			)
		)
	)
	(zone
		(layer "F.Cu")
		(hatch none 0.5)
		(connect_pads
			(clearance 0)
		)
		(min_thickness 0.25)
		(keepout
			(tracks allowed)
			(vias allowed)
			(pads allowed)
			(copperpour allowed)
			(footprints not_allowed)
		)
		(placement
			(enabled no)
			(sheetname "")
		)
		(fill
			(thermal_gap 0.5)
			(thermal_bridge_width 0.5)
			(island_removal_mode 0)
		)
		(polygon
			(pts
				(xy -1.500124 -109.549946) (xy 31.500064 -109.549946) (xy 31.500064 -55.099966) (xy -1.500124 -55.099966)
			)
		)
	)
	(zone
		(layer "F.Cu")
		(hatch none 0.5)
		(connect_pads
			(clearance 0)
		)
		(min_thickness 0.25)
		(keepout
			(tracks not_allowed)
			(vias allowed)
			(pads allowed)
			(copperpour not_allowed)
			(footprints allowed)
		)
		(placement
			(enabled no)
			(sheetname "")
		)
		(fill
			(thermal_gap 0.5)
			(thermal_bridge_width 0.5)
			(island_removal_mode 0)
		)
		(polygon
			(pts
				(arc
					(start 95.499936 -87.499952)
					(mid 100.000054 -82.999834)
					(end 104.499918 -87.499952)
				)
				(arc
					(start 104.499918 -92.499942)
					(mid 100.000054 -96.999806)
					(end 95.499936 -92.499942)
				)
			)
		)
		(polygon
			(pts
				(arc
					(start 98.49993 -89.03589)
					(mid 98.343077 -90.145296)
					(end 97.884742 -91.167712)
				)
				(arc
					(start 97.884742 -91.167712)
					(mid 100.000054 -94.999818)
					(end 102.115366 -91.167712)
				)
				(arc
					(start 102.115366 -91.167712)
					(mid 101.656901 -90.145324)
					(end 101.499924 -89.03589)
				)
				(arc
					(start 101.499924 -87.499952)
					(mid 100.000054 -86.000082)
					(end 98.49993 -87.499952)
				)
			)
		)
	)
	(zone
		(layer "F.Cu")
		(hatch none 0.5)
		(connect_pads
			(clearance 0)
		)
		(min_thickness 0.25)
		(keepout
			(tracks allowed)
			(vias allowed)
			(pads allowed)
			(copperpour allowed)
			(footprints not_allowed)
		)
		(placement
			(enabled no)
			(sheetname "")
		)
		(fill
			(thermal_gap 0.5)
			(thermal_bridge_width 0.5)
			(island_removal_mode 0)
		)
		(polygon
			(pts
				(arc
					(start 16.999966 -60.099956)
					(mid 14.99997 -62.099952)
					(end 12.999974 -60.099956)
				)
				(arc
					(start 12.999974 -60.099956)
					(mid 14.99997 -58.09996)
					(end 16.999966 -60.099956)
				)
			)
		)
	)
	(zone
		(layer "F.Cu")
		(hatch none 0.5)
		(connect_pads
			(clearance 0)
		)
		(min_thickness 0.25)
		(keepout
			(tracks allowed)
			(vias allowed)
			(pads allowed)
			(copperpour allowed)
			(footprints not_allowed)
		)
		(placement
			(enabled no)
			(sheetname "")
		)
		(fill
			(thermal_gap 0.5)
			(thermal_bridge_width 0.5)
			(island_removal_mode 0)
		)
		(polygon
			(pts
				(xy 182.500016 -27.500072) (xy 182.500016 -7.500112) (xy 97.499932 -7.500112) (xy 97.499932 -16.500094)
				(xy 79.499968 -16.500094) (xy 79.499968 -27.500072) (xy 72.00011 -27.500072) (xy 72.00011 -24.249888)
				(xy 63.950088 -24.249888) (xy 63.950088 -16.500094) (xy 42.827956 -16.500094) (xy 42.827956 -0.999998)
				(xy 397.171926 -0.999998) (xy 397.171926 -16.500094) (xy 376.050048 -16.500094) (xy 376.050048 -24.249888)
				(xy 368.000026 -24.249888) (xy 368.000026 -27.500072) (xy 360.499914 -27.500072) (xy 360.499914 -16.500094)
				(xy 342.49995 -16.500094) (xy 342.49995 -7.500112) (xy 257.50012 -7.500112) (xy 257.50012 -27.500072)
				(xy 245.49989 -27.500072) (xy 245.49989 -80.000094) (xy 314.999878 -80.000094) (xy 314.999878 -87.00008)
				(xy 325.000112 -87.00008) (xy 325.000112 -80.000094) (xy 368.000026 -80.000094) (xy 368.000026 -147.500086)
				(xy 408.500072 -147.500086) (xy 408.500072 -55.099966) (xy 434.999892 -55.099966) (xy 434.999892 -65.099946)
				(xy 439.999882 -65.099946) (xy 439.999882 -95.000064) (xy 434.999892 -95.000064) (xy 434.999892 -105.000044)
				(xy 439.999882 -105.000044) (xy 439.999882 -109.549946) (xy 456.000104 -109.549946) (xy 456.000104 -55.099966)
				(xy 452.000112 -55.099966) (xy 452.000112 -17.770094)
				(arc
					(start 471.000074 -17.770094)
					(mid 473.828495 -18.941665)
					(end 475.000066 -21.770086)
				)
				(xy 475.000066 -107.050078) (xy 471.499946 -107.050078) (xy 471.499946 -105.050082) (xy 465.000086 -105.050082)
				(xy 465.000086 -109.549946) (xy 471.499946 -109.549946) (xy 471.499946 -107.54995) (xy 475.000066 -107.54995)
				(arc
					(start 475.000066 -126.769876)
					(mid 473.828511 -129.598387)
					(end 471.000074 -130.770122)
				)
				(arc
					(start 445.000126 -130.770122)
					(mid 440.757404 -132.527462)
					(end 438.999884 -136.77011)
				)
				(arc
					(start 438.999884 -153.299922)
					(mid 437.828313 -156.128343)
					(end 434.999892 -157.299914)
				)
				(arc
					(start 413.999934 -157.299914)
					(mid 409.757302 -159.05727)
					(end 407.999946 -163.299902)
				)
				(arc
					(start 407.999946 -166.649908)
					(mid 406.828375 -169.478329)
					(end 403.999954 -170.6499)
				)
				(arc
					(start 365.000032 -170.6499)
					(mid 362.171611 -169.478329)
					(end 361.00004 -166.649908)
				)
				(arc
					(start 361.00004 -161.299906)
					(mid 359.828469 -158.471485)
					(end 357.000048 -157.299914)
				)
				(arc
					(start 356.499922 -157.299914)
					(mid 353.671501 -156.128343)
					(end 352.49993 -153.299922)
				)
				(arc
					(start 352.49993 -110.499906)
					(mid 350.01038 -104.4896)
					(end 344.000074 -102.00005)
				)
				(xy 220.050106 -102.00005) (xy 220.050106 -98.49993) (xy 238.000032 -98.49993) (xy 238.000032 -90.499946)
				(xy 202.000104 -90.499946) (xy 202.000104 -98.49993) (xy 219.95003 -98.49993) (xy 219.95003 -102.00005)
				(arc
					(start 96.000062 -102.00005)
					(mid 89.989666 -104.489585)
					(end 87.499952 -110.499906)
				)
				(arc
					(start 87.499952 -153.299922)
					(mid 86.328381 -156.128343)
					(end 83.49996 -157.299914)
				)
				(arc
					(start 83.000088 -157.299914)
					(mid 80.171667 -158.471485)
					(end 79.000096 -161.299906)
				)
				(arc
					(start 79.000096 -166.649908)
					(mid 77.828525 -169.478329)
					(end 75.000104 -170.6499)
				)
				(arc
					(start 35.999928 -170.6499)
					(mid 33.171507 -169.478329)
					(end 31.999936 -166.649908)
				)
				(arc
					(start 31.999936 -163.299902)
					(mid 30.24258 -159.05727)
					(end 25.999948 -157.299914)
				)
				(arc
					(start 4.99999 -157.299914)
					(mid 2.171569 -156.128343)
					(end 0.999998 -153.299922)
				)
				(xy 0.999998 -55.099966) (xy 31.500064 -55.099966) (xy 31.500064 -147.500086) (xy 72.00011 -147.500086)
				(xy 72.00011 -80.000094) (xy 120.000014 -80.000094) (xy 120.000014 -87.00008) (xy 174.999904 -87.00008)
				(xy 174.999904 -80.000094) (xy 194.499992 -80.000094) (xy 194.499992 -27.500072)
			)
		)
	)
	(zone
		(layer "F.Cu")
		(hatch none 0.5)
		(connect_pads
			(clearance 0)
		)
		(min_thickness 0.25)
		(keepout
			(tracks allowed)
			(vias allowed)
			(pads allowed)
			(copperpour allowed)
			(footprints not_allowed)
		)
		(placement
			(enabled no)
			(sheetname "")
		)
		(fill
			(thermal_gap 0.5)
			(thermal_bridge_width 0.5)
			(island_removal_mode 0)
		)
		(polygon
			(pts
				(arc
					(start 426.999908 -60.099956)
					(mid 424.999912 -62.099952)
					(end 422.999916 -60.099956)
				)
				(arc
					(start 422.999916 -60.099956)
					(mid 424.999912 -58.09996)
					(end 426.999908 -60.099956)
				)
			)
		)
	)
	(zone
		(layer "F.Cu")
		(hatch none 0.5)
		(connect_pads
			(clearance 0)
		)
		(min_thickness 0.25)
		(keepout
			(tracks not_allowed)
			(vias allowed)
			(pads allowed)
			(copperpour not_allowed)
			(footprints allowed)
		)
		(placement
			(enabled no)
			(sheetname "")
		)
		(fill
			(thermal_gap 0.5)
			(thermal_bridge_width 0.5)
			(island_removal_mode 0)
		)
		(polygon
			(pts
				(arc
					(start 12.02055 0)
					(mid 15.189339 -1.325303)
					(end 16.500094 -4.500118)
				)
				(arc
					(start 16.500094 -9.500108)
					(mid 12.00023 -13.999972)
					(end 7.500112 -9.500108)
				)
				(arc
					(start 7.500112 -4.500118)
					(mid 8.810811 -1.325426)
					(end 11.979402 0)
				)
			)
		)
		(polygon
			(pts
				(arc
					(start 10.500106 -6.035802)
					(mid 10.343178 -7.14525)
					(end 9.884664 -8.167624)
				)
				(arc
					(start 9.884664 -8.167624)
					(mid 11.999976 -11.99973)
					(end 14.115288 -8.167624)
				)
				(arc
					(start 14.115288 -8.167624)
					(mid 13.656888 -7.145227)
					(end 13.5001 -6.035802)
				)
				(arc
					(start 13.5001 -4.500118)
					(mid 12.00023 -3.000248)
					(end 10.500106 -4.500118)
				)
			)
		)
	)
	(zone
		(layer "F.Cu")
		(hatch none 0.5)
		(connect_pads
			(clearance 0)
		)
		(min_thickness 0.25)
		(keepout
			(tracks allowed)
			(vias allowed)
			(pads allowed)
			(copperpour allowed)
			(footprints not_allowed)
		)
		(placement
			(enabled no)
			(sheetname "")
		)
		(fill
			(thermal_gap 0.5)
			(thermal_bridge_width 0.5)
			(island_removal_mode 0)
		)
		(polygon
			(pts
				(arc
					(start 12.999974 -104.549956)
					(mid 14.99997 -102.54996)
					(end 16.999966 -104.549956)
				)
				(arc
					(start 16.999966 -104.549956)
					(mid 14.99997 -106.549952)
					(end 12.999974 -104.549956)
				)
			)
		)
	)
	(zone
		(layer "F.Cu")
		(hatch none 0.5)
		(connect_pads
			(clearance 0)
		)
		(min_thickness 0.25)
		(keepout
			(tracks not_allowed)
			(vias allowed)
			(pads allowed)
			(copperpour not_allowed)
			(footprints allowed)
		)
		(placement
			(enabled no)
			(sheetname "")
		)
		(fill
			(thermal_gap 0.5)
			(thermal_bridge_width 0.5)
			(island_removal_mode 0)
		)
		(polygon
			(pts
				(arc
					(start 66.499994 -13.5001)
					(mid 71.000112 -8.999982)
					(end 75.499976 -13.5001)
				)
				(arc
					(start 75.499976 -18.50009)
					(mid 71.000112 -22.999954)
					(end 66.499994 -18.50009)
				)
			)
		)
		(polygon
			(pts
				(arc
					(start 69.499988 -15.035784)
					(mid 69.34306 -16.145232)
					(end 68.884546 -17.167606)
				)
				(arc
					(start 68.884546 -17.167606)
					(mid 71.00018 -21.000317)
					(end 73.115424 -17.167606)
				)
				(arc
					(start 73.115424 -17.167606)
					(mid 72.656959 -16.145218)
					(end 72.499982 -15.035784)
				)
				(arc
					(start 72.499982 -13.5001)
					(mid 71.000112 -12.00023)
					(end 69.499988 -13.5001)
				)
			)
		)
	)
	(zone
		(layer "F.Cu")
		(hatch none 0.5)
		(connect_pads
			(clearance 0)
		)
		(min_thickness 0.25)
		(keepout
			(tracks not_allowed)
			(vias allowed)
			(pads allowed)
			(copperpour not_allowed)
			(footprints allowed)
		)
		(placement
			(enabled no)
			(sheetname "")
		)
		(fill
			(thermal_gap 0.5)
			(thermal_bridge_width 0.5)
			(island_removal_mode 0)
		)
		(polygon
			(pts
				(arc
					(start 245.49989 -87.499952)
					(mid 250.000008 -82.999834)
					(end 254.500126 -87.499952)
				)
				(arc
					(start 254.500126 -92.499942)
					(mid 250.000008 -97.00006)
					(end 245.49989 -92.499942)
				)
			)
		)
		(polygon
			(pts
				(arc
					(start 248.499884 -89.03589)
					(mid 248.343031 -90.145296)
					(end 247.884696 -91.167712)
				)
				(arc
					(start 247.884696 -91.167712)
					(mid 250.000008 -94.999818)
					(end 252.11532 -91.167712)
				)
				(arc
					(start 252.11532 -91.167712)
					(mid 251.656855 -90.145324)
					(end 251.499878 -89.03589)
				)
				(arc
					(start 251.499878 -87.499952)
					(mid 250.000008 -86.000082)
					(end 248.499884 -87.499952)
				)
			)
		)
	)
	(zone
		(layer "F.Cu")
		(hatch none 0.5)
		(connect_pads
			(clearance 0)
		)
		(min_thickness 0.25)
		(keepout
			(tracks not_allowed)
			(vias allowed)
			(pads allowed)
			(copperpour not_allowed)
			(footprints allowed)
		)
		(placement
			(enabled no)
			(sheetname "")
		)
		(fill
			(thermal_gap 0.5)
			(thermal_bridge_width 0.5)
			(island_removal_mode 0)
		)
		(polygon
			(pts
				(arc
					(start 356.135432 -147.500086)
					(mid 360.00055 -151.365204)
					(end 363.865414 -147.500086)
				)
				(arc
					(start 363.865414 -142.500096)
					(mid 360.00055 -138.635232)
					(end 356.135432 -142.500096)
				)
			)
		)
	)
	(zone
		(layer "F.Cu")
		(hatch none 0.5)
		(connect_pads
			(clearance 0)
		)
		(min_thickness 0.25)
		(keepout
			(tracks allowed)
			(vias allowed)
			(pads allowed)
			(copperpour allowed)
			(footprints not_allowed)
		)
		(placement
			(enabled no)
			(sheetname "")
		)
		(fill
			(thermal_gap 0.5)
			(thermal_bridge_width 0.5)
			(island_removal_mode 0)
		)
		(polygon
			(pts
				(xy 238.000032 -98.49993) (xy 202.000104 -98.49993) (xy 202.000104 -90.499946) (xy 238.000032 -90.499946)
			)
		)
	)
	(zone
		(layer "F.Cu")
		(hatch none 0.5)
		(connect_pads
			(clearance 0)
		)
		(min_thickness 0.25)
		(keepout
			(tracks not_allowed)
			(vias allowed)
			(pads allowed)
			(copperpour not_allowed)
			(footprints allowed)
		)
		(placement
			(enabled no)
			(sheetname "")
		)
		(fill
			(thermal_gap 0.5)
			(thermal_bridge_width 0.5)
			(island_removal_mode 0)
		)
		(polygon
			(pts
				(arc
					(start 428.02048 0)
					(mid 431.189269 -1.325303)
					(end 432.500024 -4.500118)
				)
				(arc
					(start 432.500024 -9.500108)
					(mid 428.00016 -13.999972)
					(end 423.500042 -9.500108)
				)
				(arc
					(start 423.500042 -4.500118)
					(mid 424.810741 -1.325426)
					(end 427.979332 0)
				)
			)
		)
		(polygon
			(pts
				(arc
					(start 426.500036 -6.035802)
					(mid 426.343108 -7.14525)
					(end 425.884594 -8.167624)
				)
				(arc
					(start 425.884594 -8.167624)
					(mid 428.000228 -12.000335)
					(end 430.115472 -8.167624)
				)
				(arc
					(start 430.115472 -8.167624)
					(mid 429.657007 -7.145236)
					(end 429.50003 -6.035802)
				)
				(arc
					(start 429.50003 -4.500118)
					(mid 428.00016 -3.000248)
					(end 426.500036 -4.500118)
				)
			)
		)
	)
	(zone
		(layer "F.Cu")
		(hatch none 0.5)
		(connect_pads
			(clearance 0)
		)
		(min_thickness 0.25)
		(keepout
			(tracks allowed)
			(vias allowed)
			(pads allowed)
			(copperpour allowed)
			(footprints not_allowed)
		)
		(placement
			(enabled no)
			(sheetname "")
		)
		(fill
			(thermal_gap 0.5)
			(thermal_bridge_width 0.5)
			(island_removal_mode 0)
		)
		(polygon
			(pts
				(xy 325.000112 -87.00008) (xy 314.999878 -87.00008) (xy 314.999878 -80.000094) (xy 325.000112 -80.000094)
			)
		)
	)
	(zone
		(layer "F.Cu")
		(hatch none 0.5)
		(connect_pads
			(clearance 0)
		)
		(min_thickness 0.25)
		(keepout
			(tracks allowed)
			(vias allowed)
			(pads allowed)
			(copperpour allowed)
			(footprints not_allowed)
		)
		(placement
			(enabled no)
			(sheetname "")
		)
		(fill
			(thermal_gap 0.5)
			(thermal_bridge_width 0.5)
			(island_removal_mode 0)
		)
		(polygon
			(pts
				(xy 174.999904 -87.00008) (xy 120.000014 -87.00008) (xy 120.000014 -80.000094) (xy 174.999904 -80.000094)
			)
		)
	)
	(zone
		(layer "F.Cu")
		(hatch none 0.5)
		(connect_pads
			(clearance 0)
		)
		(min_thickness 0.25)
		(keepout
			(tracks allowed)
			(vias allowed)
			(pads allowed)
			(copperpour allowed)
			(footprints not_allowed)
		)
		(placement
			(enabled no)
			(sheetname "")
		)
		(fill
			(thermal_gap 0.5)
			(thermal_bridge_width 0.5)
			(island_removal_mode 0)
		)
		(polygon
			(pts
				(xy 439.999882 -55.099966) (xy 408.500072 -55.099966) (xy 408.500072 -109.549946) (xy 439.999882 -109.549946)
			)
		)
	)
	(zone
		(layer "F.Cu")
		(hatch none 0.5)
		(connect_pads
			(clearance 0)
		)
		(min_thickness 0.25)
		(keepout
			(tracks allowed)
			(vias allowed)
			(pads allowed)
			(copperpour allowed)
			(footprints not_allowed)
		)
		(placement
			(enabled no)
			(sheetname "")
		)
		(fill
			(thermal_gap 0.5)
			(thermal_bridge_width 0.5)
			(island_removal_mode 0)
		)
		(polygon
			(pts
				(arc
					(start 422.999916 -104.549956)
					(mid 424.999912 -102.54996)
					(end 426.999908 -104.549956)
				)
				(arc
					(start 426.999908 -104.549956)
					(mid 424.999912 -106.549952)
					(end 422.999916 -104.549956)
				)
			)
		)
	)
	(zone
		(layer "F.Cu")
		(hatch none 0.5)
		(connect_pads
			(clearance 0)
		)
		(min_thickness 0.25)
		(keepout
			(tracks allowed)
			(vias allowed)
			(pads allowed)
			(copperpour allowed)
			(footprints not_allowed)
		)
		(placement
			(enabled no)
			(sheetname "")
		)
		(fill
			(thermal_gap 0.5)
			(thermal_bridge_width 0.5)
			(island_removal_mode 0)
		)
		(polygon
			(pts
				(xy 97.499932 -7.500112) (xy 182.500016 -7.500112) (xy 182.500016 -27.500072) (xy 194.499992 -27.500072)
				(xy 194.499992 -80.000094) (xy 72.00011 -80.000094) (xy 72.00011 -27.500072) (xy 79.499968 -27.500072)
				(xy 79.499968 -16.500094) (xy 97.499932 -16.500094)
			)
		)
	)
	(zone
		(layer "F.Cu")
		(hatch none 0.5)
		(connect_pads
			(clearance 0)
		)
		(min_thickness 0.25)
		(keepout
			(tracks not_allowed)
			(vias allowed)
			(pads allowed)
			(copperpour not_allowed)
			(footprints allowed)
		)
		(placement
			(enabled no)
			(sheetname "")
		)
		(fill
			(thermal_gap 0.5)
			(thermal_bridge_width 0.5)
			(island_removal_mode 0)
		)
		(polygon
			(pts
				(arc
					(start 353.594924 -147.500086)
					(mid 360.000042 -153.905204)
					(end 366.404906 -147.500086)
				)
				(arc
					(start 366.404906 -142.500096)
					(mid 360.000042 -136.095232)
					(end 353.594924 -142.500096)
				)
			)
		)
	)
	(zone
		(layer "F.Cu")
		(hatch none 0.5)
		(connect_pads
			(clearance 0)
		)
		(min_thickness 0.25)
		(keepout
			(tracks not_allowed)
			(vias allowed)
			(pads allowed)
			(copperpour not_allowed)
			(footprints allowed)
		)
		(placement
			(enabled no)
			(sheetname "")
		)
		(fill
			(thermal_gap 0.5)
			(thermal_bridge_width 0.5)
			(island_removal_mode 0)
		)
		(polygon
			(pts
				(arc
					(start 75.499976 -142.500096)
					(mid 80.000094 -137.999978)
					(end 84.499958 -142.500096)
				)
				(arc
					(start 84.499958 -147.500086)
					(mid 80.000094 -151.99995)
					(end 75.499976 -147.500086)
				)
			)
		)
		(polygon
			(pts
				(arc
					(start 78.49997 -144.03578)
					(mid 78.343042 -145.145228)
					(end 77.884528 -146.167602)
				)
				(arc
					(start 77.884528 -146.167602)
					(mid 80.000162 -150.000313)
					(end 82.115406 -146.167602)
				)
				(arc
					(start 82.115406 -146.167602)
					(mid 81.656941 -145.145214)
					(end 81.499964 -144.03578)
				)
				(arc
					(start 81.499964 -142.500096)
					(mid 80.000094 -141.000226)
					(end 78.49997 -142.500096)
				)
			)
		)
	)
	(zone
		(layer "F.Cu")
		(hatch none 0.5)
		(connect_pads
			(clearance 0)
		)
		(min_thickness 0.25)
		(keepout
			(tracks allowed)
			(vias allowed)
			(pads allowed)
			(copperpour allowed)
			(footprints not_allowed)
		)
		(placement
			(enabled no)
			(sheetname "")
		)
		(fill
			(thermal_gap 0.5)
			(thermal_bridge_width 0.5)
			(island_removal_mode 0)
		)
		(polygon
			(pts
				(arc
					(start 206.70012 -79.630016)
					(mid 208.810098 -77.520038)
					(end 210.920076 -79.630016)
				)
				(arc
					(start 210.920076 -79.630016)
					(mid 208.810098 -81.739994)
					(end 206.70012 -79.630016)
				)
			)
		)
	)
	(zone
		(layer "F.Cu")
		(hatch none 0.5)
		(connect_pads
			(clearance 0)
		)
		(min_thickness 0.25)
		(keepout
			(tracks allowed)
			(vias allowed)
			(pads allowed)
			(copperpour allowed)
			(footprints not_allowed)
		)
		(placement
			(enabled no)
			(sheetname "")
		)
		(fill
			(thermal_gap 0.5)
			(thermal_bridge_width 0.5)
			(island_removal_mode 0)
		)
		(polygon
			(pts
				(arc
					(start 16.500094 -4.500118)
					(mid 16.060626 -2.560484)
					(end 14.828012 -0.999744)
				)
				(xy 42.827956 -0.999998) (xy 42.827956 -16.500094) (xy 63.950088 -16.500094) (xy 63.950088 -24.249888)
				(xy 72.00011 -24.249888) (xy 72.00011 -32.500062) (xy 31.500064 -32.500062) (xy 31.500064 -55.099966)
				(xy 0.999998 -55.099966)
				(arc
					(start 0.999998 -4.99999)
					(mid 2.171569 -2.171569)
					(end 4.99999 -0.999998)
				)
				(arc
					(start 9.171686 -0.999998)
					(mid 7.939416 -2.560713)
					(end 7.500112 -4.500118)
				)
				(arc
					(start 7.500112 -9.500108)
					(mid 12.00023 -14.000226)
					(end 16.500094 -9.500108)
				)
			)
		)
	)
	(zone
		(layer "F.Cu")
		(hatch none 0.5)
		(connect_pads
			(clearance 0)
		)
		(min_thickness 0.25)
		(keepout
			(tracks not_allowed)
			(vias allowed)
			(pads allowed)
			(copperpour not_allowed)
			(footprints allowed)
		)
		(placement
			(enabled no)
			(sheetname "")
		)
		(fill
			(thermal_gap 0.5)
			(thermal_bridge_width 0.5)
			(island_removal_mode 0)
		)
		(polygon
			(pts
				(arc
					(start 452.499984 -121.499884)
					(mid 457.000102 -116.999766)
					(end 461.499966 -121.499884)
				)
				(arc
					(start 461.499966 -126.499874)
					(mid 457.000102 -130.999738)
					(end 452.499984 -126.499874)
				)
			)
		)
		(polygon
			(pts
				(arc
					(start 455.499978 -123.035822)
					(mid 455.34305 -124.14527)
					(end 454.884536 -125.167644)
				)
				(arc
					(start 454.884536 -125.167644)
					(mid 457.00017 -129.000355)
					(end 459.115414 -125.167644)
				)
				(arc
					(start 459.115414 -125.167644)
					(mid 458.656949 -124.145256)
					(end 458.499972 -123.035822)
				)
				(arc
					(start 458.499972 -121.499884)
					(mid 457.000102 -120.000014)
					(end 455.499978 -121.499884)
				)
			)
		)
	)
	(zone
		(layer "F.Cu")
		(hatch none 0.5)
		(connect_pads
			(clearance 0)
		)
		(min_thickness 0.25)
		(keepout
			(tracks not_allowed)
			(vias allowed)
			(pads allowed)
			(copperpour not_allowed)
			(footprints allowed)
		)
		(placement
			(enabled no)
			(sheetname "")
		)
		(fill
			(thermal_gap 0.5)
			(thermal_bridge_width 0.5)
			(island_removal_mode 0)
		)
		(polygon
			(pts
				(arc
					(start 423.500042 -84.000086)
					(mid 428.00016 -79.499968)
					(end 432.500024 -84.000086)
				)
				(arc
					(start 432.500024 -89.000076)
					(mid 428.00016 -93.49994)
					(end 423.500042 -89.000076)
				)
			)
		)
		(polygon
			(pts
				(arc
					(start 426.500036 -85.536024)
					(mid 426.343055 -86.645329)
					(end 425.884594 -87.667592)
				)
				(arc
					(start 425.884594 -87.667592)
					(mid 428.000228 -91.500303)
					(end 430.115472 -87.667592)
				)
				(arc
					(start 430.115472 -87.667592)
					(mid 429.656984 -86.645336)
					(end 429.50003 -85.536024)
				)
				(arc
					(start 429.50003 -84.000086)
					(mid 428.00016 -82.500216)
					(end 426.500036 -84.000086)
				)
			)
		)
	)
	(zone
		(layers "F.Cu" "B.Cu" "In1.Cu" "In2.Cu" "In3.Cu" "In4.Cu" "In5.Cu" "In6.Cu"
			"In7.Cu" "In8.Cu"
		)
		(name "Route Keepin")
		(hatch none 0.5)
		(connect_pads
			(clearance 0)
		)
		(min_thickness 0.25)
		(keepout
			(tracks allowed)
			(vias allowed)
			(pads allowed)
			(copperpour allowed)
			(footprints allowed)
		)
		(placement
			(enabled no)
			(sheetname "")
		)
		(fill
			(thermal_gap 0.5)
			(thermal_bridge_width 0.5)
			(island_removal_mode 0)
		)
		(polygon
			(pts
				(arc
					(start 87.99195 -110.499906)
					(mid 90.337472 -104.83757)
					(end 95.999808 -102.492048)
				)
				(xy 318.105282 -102.492048) (xy 318.364362 -102.751128) (xy 318.364362 -104.824022) (xy 318.023748 -105.164636)
				(xy 292.692074 -105.164636) (xy 291.640768 -106.215942) (xy 291.640768 -121.953274) (xy 289.957256 -124.01169)
				(xy 288.457894 -125.136148) (xy 139.606274 -125.136148) (xy 139.26058 -124.790454) (xy 138.46937 -124.790454)
				(xy 136.793224 -123.114308) (xy 136.793224 -122.323098) (xy 136.793224 -106.644186) (xy 135.363204 -105.214166)
				(xy 95.623126 -105.214166) (xy 93.112844 -106.101388) (xy 91.576652 -107.63758) (xy 90.711528 -110.517686)
				(xy 90.711528 -188.38291) (xy 89.172288 -189.92215) (xy 27.744928 -189.92215) (xy 26.18994 -188.367162)
				(xy 26.18994 -162.339782) (xy 24.42083 -160.570672) (xy 1.354074 -160.570672) (xy 0.273558 -161.651188)
				(xy 0.273558 -198.175626) (xy 1.472438 -199.374506) (xy 474.558106 -199.374506) (xy 475.831154 -198.101458)
				(xy 475.831154 -135.349234) (xy 474.557598 -134.075678) (xy 444.488824 -134.075678) (xy 443.719966 -134.259574)
				(xy 442.58357 -135.39597) (xy 442.0235 -137.411714) (xy 442.0235 -154.965654) (xy 441.934346 -155.518104)
				(xy 441.35675 -157.04312) (xy 439.254392 -159.130492) (xy 436.78729 -160.201864) (xy 436.115714 -160.517332)
				(xy 415.729166 -160.517332) (xy 413.848804 -162.397694) (xy 413.848804 -188.33592) (xy 412.339028 -189.845696)
				(xy 350.734122 -189.845696) (xy 349.278194 -188.389768) (xy 349.278194 -109.66069) (xy 348.657672 -107.884976)
				(xy 347.08719 -106.314748) (xy 345.153234 -105.411524) (xy 319.275206 -105.411524) (xy 318.934592 -105.07091)
				(xy 318.934592 -102.610666) (xy 319.05321 -102.492048)
				(arc
					(start 344.000074 -102.492048)
					(mid 349.662485 -104.837495)
					(end 352.007932 -110.499906)
				)
				(arc
					(start 352.007932 -153.299922)
					(mid 353.323605 -156.476239)
					(end 356.499922 -157.791912)
				)
				(arc
					(start 357.000048 -157.791912)
					(mid 359.480574 -158.81938)
					(end 360.508042 -161.299906)
				)
				(arc
					(start 360.508042 -166.649908)
					(mid 361.823715 -169.826225)
					(end 365.000032 -171.141898)
				)
				(arc
					(start 403.999954 -171.141898)
					(mid 407.176271 -169.826225)
					(end 408.491944 -166.649908)
				)
				(arc
					(start 408.491944 -163.299902)
					(mid 410.105197 -159.405165)
					(end 413.999934 -157.791912)
				)
				(arc
					(start 434.999892 -157.791912)
					(mid 438.176209 -156.476239)
					(end 439.491882 -153.299922)
				)
				(arc
					(start 439.491882 -136.77011)
					(mid 441.105209 -132.875447)
					(end 444.999872 -131.26212)
				)
				(arc
					(start 471.000074 -131.26212)
					(mid 474.176391 -129.946447)
					(end 475.492064 -126.77013)
				)
				(arc
					(start 475.492064 -21.770086)
					(mid 474.176391 -18.593769)
					(end 471.000074 -17.278096)
				)
				(arc
					(start 444.999872 -17.278096)
					(mid 441.105209 -15.664769)
					(end 439.491882 -11.770106)
				)
				(arc
					(start 439.491882 -4.99999)
					(mid 438.176209 -1.823673)
					(end 434.999892 -0.508)
				)
				(arc
					(start 4.99999 -0.508)
					(mid 1.823673 -1.823673)
					(end 0.508 -4.99999)
				)
				(arc
					(start 0.508 -153.299922)
					(mid 1.823673 -156.476239)
					(end 4.99999 -157.791912)
				)
				(arc
					(start 25.999948 -157.791912)
					(mid 29.894685 -159.405165)
					(end 31.507938 -163.299902)
				)
				(arc
					(start 31.507938 -166.649908)
					(mid 32.823611 -169.826225)
					(end 35.999928 -171.141898)
				)
				(arc
					(start 75.000104 -171.141898)
					(mid 78.176421 -169.826225)
					(end 79.492094 -166.649908)
				)
				(arc
					(start 79.492094 -161.28111)
					(mid 80.585981 -158.885799)
					(end 82.981292 -157.791912)
				)
				(arc
					(start 83.49996 -157.791912)
					(mid 86.676277 -156.476239)
					(end 87.99195 -153.299922)
				)
			)
		)
	)
	(zone
		(layers "F.Cu" "B.Cu" "In1.Cu" "In2.Cu" "In3.Cu" "In4.Cu" "In5.Cu" "In6.Cu"
			"In7.Cu" "In8.Cu"
		)
		(name "Package Keepin")
		(hatch none 0.5)
		(connect_pads
			(clearance 0)
		)
		(min_thickness 0.25)
		(keepout
			(tracks allowed)
			(vias allowed)
			(pads allowed)
			(copperpour allowed)
			(footprints allowed)
		)
		(placement
			(enabled no)
			(sheetname "")
		)
		(fill
			(thermal_gap 0.5)
			(thermal_bridge_width 0.5)
			(island_removal_mode 0)
		)
		(polygon
			(pts
				(arc
					(start 344.000074 -101.984048)
					(mid 350.021695 -104.478285)
					(end 352.515932 -110.499906)
				)
				(arc
					(start 352.515932 -153.299922)
					(mid 353.682816 -156.117028)
					(end 356.499922 -157.283912)
				)
				(arc
					(start 357.000048 -157.283912)
					(mid 359.839785 -158.460169)
					(end 361.016042 -161.299906)
				)
				(arc
					(start 361.016042 -166.649908)
					(mid 362.182926 -169.467014)
					(end 365.000032 -170.633898)
				)
				(arc
					(start 403.999954 -170.633898)
					(mid 406.81706 -169.467014)
					(end 407.983944 -166.649908)
				)
				(arc
					(start 407.983944 -163.299902)
					(mid 409.745987 -159.045955)
					(end 413.999934 -157.283912)
				)
				(arc
					(start 434.999892 -157.283912)
					(mid 437.816998 -156.117028)
					(end 438.983882 -153.299922)
				)
				(arc
					(start 438.983882 -136.77011)
					(mid 440.745999 -132.516237)
					(end 444.999872 -130.75412)
				)
				(arc
					(start 471.000074 -130.75412)
					(mid 473.81718 -129.587236)
					(end 474.984064 -126.77013)
				)
				(arc
					(start 474.984064 -21.770086)
					(mid 473.81718 -18.95298)
					(end 471.000074 -17.786096)
				)
				(arc
					(start 444.999872 -17.786096)
					(mid 440.745999 -16.023979)
					(end 438.983882 -11.770106)
				)
				(arc
					(start 438.983882 -4.99999)
					(mid 437.816998 -2.182884)
					(end 434.999892 -1.016)
				)
				(arc
					(start 4.99999 -1.016)
					(mid 2.182884 -2.182884)
					(end 1.016 -4.99999)
				)
				(arc
					(start 1.016 -153.299922)
					(mid 2.182884 -156.117028)
					(end 4.99999 -157.283912)
				)
				(arc
					(start 25.999948 -157.283912)
					(mid 30.253895 -159.045955)
					(end 32.015938 -163.299902)
				)
				(arc
					(start 32.015938 -166.649908)
					(mid 33.182822 -169.467014)
					(end 35.999928 -170.633898)
				)
				(arc
					(start 75.000104 -170.633898)
					(mid 77.81721 -169.467014)
					(end 78.984094 -166.649908)
				)
				(arc
					(start 78.984094 -161.263584)
					(mid 80.226772 -158.52659)
					(end 82.963766 -157.283912)
				)
				(arc
					(start 83.49996 -157.283912)
					(mid 86.317066 -156.117028)
					(end 87.48395 -153.299922)
				)
				(arc
					(start 87.48395 -110.499906)
					(mid 89.978261 -104.478359)
					(end 95.999808 -101.984048)
				)
				(xy 318.540384 -101.984048) (xy 318.74206 -102.185724) (xy 318.74206 -139.157964) (xy 318.646302 -139.253722)
				(xy 147.57146 -139.253722) (xy 145.202656 -141.622526) (xy 145.202656 -180.471572) (xy 147.097496 -182.366412)
				(xy 316.469268 -182.366412) (xy 318.800988 -180.034692) (xy 318.800988 -102.17658) (xy 318.99352 -101.984048)
			)
		)
	)
	(zone
		(layer "B.Cu")
		(hatch none 0.5)
		(connect_pads
			(clearance 0)
		)
		(min_thickness 0.25)
		(keepout
			(tracks allowed)
			(vias allowed)
			(pads allowed)
			(copperpour allowed)
			(footprints not_allowed)
		)
		(placement
			(enabled no)
			(sheetname "")
		)
		(fill
			(thermal_gap 0.5)
			(thermal_bridge_width 0.5)
			(island_removal_mode 0)
		)
		(polygon
			(pts
				(arc
					(start 372.400068 -147.500086)
					(mid 360.000042 -135.10006)
					(end 347.600016 -147.500086)
				)
				(arc
					(start 347.600016 -147.500086)
					(mid 360.000042 -159.900112)
					(end 372.400068 -147.500086)
				)
			)
		)
	)
	(zone
		(layer "B.Cu")
		(hatch none 0.5)
		(connect_pads
			(clearance 0)
		)
		(min_thickness 0.25)
		(keepout
			(tracks not_allowed)
			(vias allowed)
			(pads allowed)
			(copperpour not_allowed)
			(footprints allowed)
		)
		(placement
			(enabled no)
			(sheetname "")
		)
		(fill
			(thermal_gap 0.5)
			(thermal_bridge_width 0.5)
			(island_removal_mode 0)
		)
		(polygon
			(pts
				(arc
					(start 83.404964 -142.500096)
					(mid 80.000094 -139.095226)
					(end 76.59497 -142.500096)
				)
				(arc
					(start 76.59497 -144.03578)
					(mid 76.512779 -144.61687)
					(end 76.272644 -145.152364)
				)
				(arc
					(start 76.272644 -145.152364)
					(mid 80.000162 -151.905274)
					(end 83.72729 -145.152364)
				)
				(arc
					(start 83.72729 -145.152364)
					(mid 83.487167 -144.616867)
					(end 83.404964 -144.03578)
				)
			)
		)
	)
	(zone
		(layer "B.Cu")
		(hatch none 0.5)
		(connect_pads
			(clearance 0)
		)
		(min_thickness 0.25)
		(keepout
			(tracks allowed)
			(vias allowed)
			(pads allowed)
			(copperpour allowed)
			(footprints not_allowed)
		)
		(placement
			(enabled no)
			(sheetname "")
		)
		(fill
			(thermal_gap 0.5)
			(thermal_bridge_width 0.5)
			(island_removal_mode 0)
		)
		(polygon
			(pts
				(arc
					(start 234.810046 -22.47011)
					(mid 238.810038 -26.470102)
					(end 242.81003 -22.47011)
				)
				(arc
					(start 242.81003 -22.47011)
					(mid 238.810038 -18.470118)
					(end 234.810046 -22.47011)
				)
			)
		)
		(polygon
			(pts
				(arc
					(start 236.70006 -22.47011)
					(mid 238.810038 -24.580088)
					(end 240.920016 -22.47011)
				)
				(arc
					(start 240.920016 -22.47011)
					(mid 238.810038 -20.360132)
					(end 236.70006 -22.47011)
				)
			)
		)
	)
	(zone
		(layer "B.Cu")
		(hatch none 0.5)
		(connect_pads
			(clearance 0)
		)
		(min_thickness 0.25)
		(keepout
			(tracks allowed)
			(vias allowed)
			(pads allowed)
			(copperpour allowed)
			(footprints not_allowed)
		)
		(placement
			(enabled no)
			(sheetname "")
		)
		(fill
			(thermal_gap 0.5)
			(thermal_bridge_width 0.5)
			(island_removal_mode 0)
		)
		(polygon
			(pts
				(arc
					(start 444.502286 -29.262832)
					(mid 448.077831 -38.254506)
					(end 457.000102 -41.999916)
				)
				(xy 457.000102 -51.900074) (xy 408.200098 -51.900074) (xy 408.200098 -0.999998) (xy 404.999952 -0.999998)
				(xy 404.999952 -152.500076)
				(arc
					(start 371.347238 -152.500076)
					(mid 367.682087 -137.766385)
					(end 352.49993 -137.625328)
				)
				(arc
					(start 352.49993 -153.299922)
					(mid 353.671501 -156.128343)
					(end 356.499922 -157.299914)
				)
				(arc
					(start 357.000048 -157.299914)
					(mid 359.828469 -158.471485)
					(end 361.00004 -161.299906)
				)
				(arc
					(start 361.00004 -166.649908)
					(mid 362.171611 -169.478329)
					(end 365.000032 -170.6499)
				)
				(arc
					(start 403.999954 -170.6499)
					(mid 406.828375 -169.478329)
					(end 407.999946 -166.649908)
				)
				(arc
					(start 407.999946 -163.299902)
					(mid 409.757302 -159.05727)
					(end 413.999934 -157.299914)
				)
				(arc
					(start 434.999892 -157.299914)
					(mid 437.828313 -156.128343)
					(end 438.999884 -153.299922)
				)
				(arc
					(start 438.999884 -136.77011)
					(mid 440.757404 -132.527462)
					(end 445.000126 -130.770122)
				)
				(arc
					(start 471.000074 -130.770122)
					(mid 473.828511 -129.598387)
					(end 475.000066 -126.769876)
				)
				(xy 475.000066 -77.600048) (xy 465.000086 -77.600048) (xy 465.000086 -97.499932) (xy 455.000106 -97.499932)
				(xy 455.000106 -77.499972) (xy 475.000066 -77.499972)
				(arc
					(start 475.000066 -21.770086)
					(mid 473.828495 -18.941665)
					(end 471.000074 -17.770094)
				)
				(arc
					(start 445.000126 -17.770094)
					(mid 440.757494 -16.012738)
					(end 438.999884 -11.770106)
				)
				(arc
					(start 438.999884 -4.99999)
					(mid 437.828313 -2.171569)
					(end 434.999892 -0.999998)
				)
				(xy 408.29992 -0.999998) (xy 408.29992 -17.259554)
				(arc
					(start 418.200078 -17.259554)
					(mid 423.767027 -21.261536)
					(end 430.60747 -21.725128)
				)
				(arc
					(start 430.60747 -21.725128)
					(mid 436.655278 -27.152285)
					(end 444.502286 -29.262832)
				)
			)
		)
	)
	(zone
		(layer "B.Cu")
		(hatch none 0.5)
		(connect_pads
			(clearance 0)
		)
		(min_thickness 0.25)
		(keepout
			(tracks not_allowed)
			(vias allowed)
			(pads allowed)
			(copperpour not_allowed)
			(footprints allowed)
		)
		(placement
			(enabled no)
			(sheetname "")
		)
		(fill
			(thermal_gap 0.5)
			(thermal_bridge_width 0.5)
			(island_removal_mode 0)
		)
		(polygon
			(pts
				(arc
					(start 366.023906 -142.500096)
					(mid 360.000042 -136.476232)
					(end 353.975924 -142.500096)
				)
				(arc
					(start 353.975924 -147.500086)
					(mid 360.000042 -153.524204)
					(end 366.023906 -147.500086)
				)
			)
		)
	)
	(zone
		(layer "B.Cu")
		(hatch none 0.5)
		(connect_pads
			(clearance 0)
		)
		(min_thickness 0.25)
		(keepout
			(tracks allowed)
			(vias allowed)
			(pads allowed)
			(copperpour allowed)
			(footprints not_allowed)
		)
		(placement
			(enabled no)
			(sheetname "")
		)
		(fill
			(thermal_gap 0.5)
			(thermal_bridge_width 0.5)
			(island_removal_mode 0)
		)
		(polygon
			(pts
				(arc
					(start 92.40012 -147.500086)
					(mid 80.000094 -135.10006)
					(end 67.600068 -147.500086)
				)
				(arc
					(start 67.600068 -147.500086)
					(mid 80.000094 -159.900112)
					(end 92.40012 -147.500086)
				)
			)
		)
	)
	(zone
		(layer "B.Cu")
		(hatch none 0.5)
		(connect_pads
			(clearance 0)
		)
		(min_thickness 0.25)
		(keepout
			(tracks not_allowed)
			(vias allowed)
			(pads allowed)
			(copperpour not_allowed)
			(footprints allowed)
		)
		(placement
			(enabled no)
			(sheetname "")
		)
		(fill
			(thermal_gap 0.5)
			(thermal_bridge_width 0.5)
			(island_removal_mode 0)
		)
		(polygon
			(pts
				(arc
					(start 423.500042 -84.000086)
					(mid 428.00016 -79.499968)
					(end 432.500024 -84.000086)
				)
				(arc
					(start 432.500024 -89.000076)
					(mid 428.00016 -93.49994)
					(end 423.500042 -89.000076)
				)
			)
		)
		(polygon
			(pts
				(arc
					(start 430.115472 -87.667592)
					(mid 428.000228 -91.500088)
					(end 425.884594 -87.667592)
				)
				(arc
					(start 425.884594 -87.667592)
					(mid 426.343082 -86.645336)
					(end 426.500036 -85.536024)
				)
				(arc
					(start 426.500036 -84.000086)
					(mid 428.00016 -82.499962)
					(end 429.50003 -84.000086)
				)
				(arc
					(start 429.50003 -85.536024)
					(mid 429.657011 -86.645329)
					(end 430.115472 -87.667592)
				)
			)
		)
	)
	(zone
		(layer "B.Cu")
		(hatch none 0.5)
		(connect_pads
			(clearance 0)
		)
		(min_thickness 0.25)
		(keepout
			(tracks allowed)
			(vias allowed)
			(pads allowed)
			(copperpour allowed)
			(footprints not_allowed)
		)
		(placement
			(enabled no)
			(sheetname "")
		)
		(fill
			(thermal_gap 0.5)
			(thermal_bridge_width 0.5)
			(island_removal_mode 0)
		)
		(polygon
			(pts
				(arc
					(start 212.81009 -79.630016)
					(mid 208.810098 -75.630024)
					(end 204.810106 -79.630016)
				)
				(arc
					(start 204.810106 -79.630016)
					(mid 208.810098 -83.630008)
					(end 212.81009 -79.630016)
				)
			)
		)
		(polygon
			(pts
				(arc
					(start 210.920076 -79.630016)
					(mid 208.810098 -77.520038)
					(end 206.70012 -79.630016)
				)
				(arc
					(start 206.70012 -79.630016)
					(mid 208.810098 -81.739994)
					(end 210.920076 -79.630016)
				)
			)
		)
	)
	(zone
		(layer "B.Cu")
		(hatch none 0.5)
		(connect_pads
			(clearance 0)
		)
		(min_thickness 0.25)
		(keepout
			(tracks allowed)
			(vias allowed)
			(pads allowed)
			(copperpour allowed)
			(footprints not_allowed)
		)
		(placement
			(enabled no)
			(sheetname "")
		)
		(fill
			(thermal_gap 0.5)
			(thermal_bridge_width 0.5)
			(island_removal_mode 0)
		)
		(polygon
			(pts
				(arc
					(start 199.82053 -13.929106)
					(mid 177.616747 -20.861052)
					(end 198.989442 -30.040834)
				)
				(arc
					(start 198.989442 -30.040834)
					(mid 221.193225 -23.108888)
					(end 199.82053 -13.929106)
				)
			)
		)
	)
	(zone
		(layer "B.Cu")
		(hatch none 0.5)
		(connect_pads
			(clearance 0)
		)
		(min_thickness 0.25)
		(keepout
			(tracks not_allowed)
			(vias allowed)
			(pads allowed)
			(copperpour not_allowed)
			(footprints allowed)
		)
		(placement
			(enabled no)
			(sheetname "")
		)
		(fill
			(thermal_gap 0.5)
			(thermal_bridge_width 0.5)
			(island_removal_mode 0)
		)
		(polygon
			(pts
				(arc
					(start 452.499984 -121.499884)
					(mid 457.000102 -116.999766)
					(end 461.499966 -121.499884)
				)
				(arc
					(start 461.499966 -126.499874)
					(mid 457.000102 -130.999738)
					(end 452.499984 -126.499874)
				)
			)
		)
		(polygon
			(pts
				(arc
					(start 459.115414 -125.167644)
					(mid 457.00017 -129.00014)
					(end 454.884536 -125.167644)
				)
				(arc
					(start 454.884536 -125.167644)
					(mid 455.343001 -124.145256)
					(end 455.499978 -123.035822)
				)
				(arc
					(start 455.499978 -121.499884)
					(mid 457.000102 -119.99976)
					(end 458.499972 -121.499884)
				)
				(arc
					(start 458.499972 -123.035822)
					(mid 458.6569 -124.14527)
					(end 459.115414 -125.167644)
				)
			)
		)
	)
	(zone
		(layer "B.Cu")
		(hatch none 0.5)
		(connect_pads
			(clearance 0)
		)
		(min_thickness 0.25)
		(keepout
			(tracks allowed)
			(vias allowed)
			(pads allowed)
			(copperpour allowed)
			(footprints not_allowed)
		)
		(placement
			(enabled no)
			(sheetname "")
		)
		(fill
			(thermal_gap 0.5)
			(thermal_bridge_width 0.5)
			(island_removal_mode 0)
		)
		(polygon
			(pts
				(arc
					(start 2.600198 -126.436374)
					(mid 1.679552 -148.047519)
					(end 20.599908 -137.563606)
				)
				(arc
					(start 20.599908 -137.563606)
					(mid 21.520554 -115.952461)
					(end 2.600198 -126.436374)
				)
			)
		)
	)
	(zone
		(layer "B.Cu")
		(hatch none 0.5)
		(connect_pads
			(clearance 0)
		)
		(min_thickness 0.25)
		(keepout
			(tracks allowed)
			(vias allowed)
			(pads allowed)
			(copperpour allowed)
			(footprints not_allowed)
		)
		(placement
			(enabled no)
			(sheetname "")
		)
		(fill
			(thermal_gap 0.5)
			(thermal_bridge_width 0.5)
			(island_removal_mode 0)
		)
		(polygon
			(pts
				(arc
					(start 24.400002 -9.500108)
					(mid 11.999976 2.899918)
					(end -0.40005 -9.500108)
				)
				(arc
					(start -0.40005 -9.500108)
					(mid 11.999976 -21.900134)
					(end 24.400002 -9.500108)
				)
			)
		)
	)
	(zone
		(layer "B.Cu")
		(hatch none 0.5)
		(connect_pads
			(clearance 0)
		)
		(min_thickness 0.25)
		(keepout
			(tracks allowed)
			(vias allowed)
			(pads allowed)
			(copperpour allowed)
			(footprints not_allowed)
		)
		(placement
			(enabled no)
			(sheetname "")
		)
		(fill
			(thermal_gap 0.5)
			(thermal_bridge_width 0.5)
			(island_removal_mode 0)
		)
		(polygon
			(pts
				(arc
					(start 12.999974 -104.549956)
					(mid 14.99997 -106.549952)
					(end 16.999966 -104.549956)
				)
				(arc
					(start 16.999966 -104.549956)
					(mid 14.99997 -102.54996)
					(end 12.999974 -104.549956)
				)
			)
		)
	)
	(zone
		(layer "B.Cu")
		(hatch none 0.5)
		(connect_pads
			(clearance 0)
		)
		(min_thickness 0.25)
		(keepout
			(tracks allowed)
			(vias allowed)
			(pads allowed)
			(copperpour allowed)
			(footprints not_allowed)
		)
		(placement
			(enabled no)
			(sheetname "")
		)
		(fill
			(thermal_gap 0.5)
			(thermal_bridge_width 0.5)
			(island_removal_mode 0)
		)
		(polygon
			(pts
				(arc
					(start 16.999966 -60.099956)
					(mid 14.99997 -58.09996)
					(end 12.999974 -60.099956)
				)
				(arc
					(start 12.999974 -60.099956)
					(mid 14.99997 -62.099952)
					(end 16.999966 -60.099956)
				)
			)
		)
	)
	(zone
		(layer "B.Cu")
		(hatch none 0.5)
		(connect_pads
			(clearance 0)
		)
		(min_thickness 0.25)
		(keepout
			(tracks not_allowed)
			(vias allowed)
			(pads allowed)
			(copperpour not_allowed)
			(footprints allowed)
		)
		(placement
			(enabled no)
			(sheetname "")
		)
		(fill
			(thermal_gap 0.5)
			(thermal_bridge_width 0.5)
			(island_removal_mode 0)
		)
		(polygon
			(pts
				(arc
					(start 245.49989 -87.499952)
					(mid 250.000008 -82.999834)
					(end 254.500126 -87.499952)
				)
				(arc
					(start 254.500126 -92.499942)
					(mid 250.000008 -97.00006)
					(end 245.49989 -92.499942)
				)
			)
		)
		(polygon
			(pts
				(arc
					(start 252.11532 -91.167712)
					(mid 250.000008 -94.999818)
					(end 247.884696 -91.167712)
				)
				(arc
					(start 247.884696 -91.167712)
					(mid 248.343096 -90.145315)
					(end 248.499884 -89.03589)
				)
				(arc
					(start 248.499884 -87.499952)
					(mid 250.000008 -85.999828)
					(end 251.499878 -87.499952)
				)
				(arc
					(start 251.499878 -89.03589)
					(mid 251.656806 -90.145338)
					(end 252.11532 -91.167712)
				)
			)
		)
	)
	(zone
		(layer "B.Cu")
		(hatch none 0.5)
		(connect_pads
			(clearance 0)
		)
		(min_thickness 0.25)
		(keepout
			(tracks allowed)
			(vias allowed)
			(pads allowed)
			(copperpour allowed)
			(footprints not_allowed)
		)
		(placement
			(enabled no)
			(sheetname "")
		)
		(fill
			(thermal_gap 0.5)
			(thermal_bridge_width 0.5)
			(island_removal_mode 0)
		)
		(polygon
			(pts
				(arc
					(start 240.920016 -79.630016)
					(mid 238.810038 -77.520038)
					(end 236.70006 -79.630016)
				)
				(arc
					(start 236.70006 -79.630016)
					(mid 238.810038 -81.739994)
					(end 240.920016 -79.630016)
				)
			)
		)
	)
	(zone
		(layer "B.Cu")
		(hatch none 0.5)
		(connect_pads
			(clearance 0)
		)
		(min_thickness 0.25)
		(keepout
			(tracks allowed)
			(vias allowed)
			(pads allowed)
			(copperpour allowed)
			(footprints not_allowed)
		)
		(placement
			(enabled no)
			(sheetname "")
		)
		(fill
			(thermal_gap 0.5)
			(thermal_bridge_width 0.5)
			(island_removal_mode 0)
		)
		(polygon
			(pts
				(arc
					(start 428.600108 -137.500106)
					(mid 431.8 -140.699998)
					(end 434.999892 -137.500106)
				)
				(arc
					(start 434.999892 -137.500106)
					(mid 431.8 -134.300214)
					(end 428.600108 -137.500106)
				)
			)
		)
	)
	(zone
		(layer "B.Cu")
		(hatch none 0.5)
		(connect_pads
			(clearance 0)
		)
		(min_thickness 0.25)
		(keepout
			(tracks allowed)
			(vias allowed)
			(pads allowed)
			(copperpour allowed)
			(footprints not_allowed)
		)
		(placement
			(enabled no)
			(sheetname "")
		)
		(fill
			(thermal_gap 0.5)
			(thermal_bridge_width 0.5)
			(island_removal_mode 0)
		)
		(polygon
			(pts
				(arc
					(start 83.399884 -18.50009)
					(mid 71.000112 -6.100318)
					(end 58.600086 -18.50009)
				)
				(arc
					(start 58.600086 -18.50009)
					(mid 71.000112 -30.900116)
					(end 83.399884 -18.50009)
				)
			)
		)
	)
	(zone
		(layer "B.Cu")
		(hatch none 0.5)
		(connect_pads
			(clearance 0)
		)
		(min_thickness 0.25)
		(keepout
			(tracks allowed)
			(vias allowed)
			(pads allowed)
			(copperpour allowed)
			(footprints not_allowed)
		)
		(placement
			(enabled no)
			(sheetname "")
		)
		(fill
			(thermal_gap 0.5)
			(thermal_bridge_width 0.5)
			(island_removal_mode 0)
		)
		(polygon
			(pts
				(arc
					(start 4.99999 -137.500106)
					(mid 8.200136 -140.700252)
					(end 11.400028 -137.500106)
				)
				(arc
					(start 11.400028 -137.500106)
					(mid 8.200136 -134.300214)
					(end 4.99999 -137.500106)
				)
			)
		)
	)
	(zone
		(layer "B.Cu")
		(hatch none 0.5)
		(connect_pads
			(clearance 0)
		)
		(min_thickness 0.25)
		(keepout
			(tracks allowed)
			(vias allowed)
			(pads allowed)
			(copperpour allowed)
			(footprints allowed)
		)
		(placement
			(enabled no)
			(sheetname "")
		)
		(fill
			(thermal_gap 0.5)
			(thermal_bridge_width 0.5)
			(island_removal_mode 0)
		)
		(polygon
			(pts
				(xy 161.235644 -78.131416) (xy 161.235644 -69.174106) (xy 171.235116 -69.174106) (xy 171.235116 -78.131416)
			)
		)
	)
	(zone
		(layer "B.Cu")
		(hatch none 0.5)
		(connect_pads
			(clearance 0)
		)
		(min_thickness 0.25)
		(keepout
			(tracks not_allowed)
			(vias allowed)
			(pads allowed)
			(copperpour not_allowed)
			(footprints allowed)
		)
		(placement
			(enabled no)
			(sheetname "")
		)
		(fill
			(thermal_gap 0.5)
			(thermal_bridge_width 0.5)
			(island_removal_mode 0)
		)
		(polygon
			(pts
				(arc
					(start 7.500112 -84.000086)
					(mid 12.00023 -79.499968)
					(end 16.500094 -84.000086)
				)
				(arc
					(start 16.500094 -89.000076)
					(mid 12.00023 -93.49994)
					(end 7.500112 -89.000076)
				)
			)
		)
		(polygon
			(pts
				(arc
					(start 14.115288 -87.667592)
					(mid 11.999976 -91.499698)
					(end 9.884664 -87.667592)
				)
				(arc
					(start 9.884664 -87.667592)
					(mid 10.343152 -86.645336)
					(end 10.500106 -85.536024)
				)
				(arc
					(start 10.500106 -84.000086)
					(mid 12.00023 -82.499962)
					(end 13.5001 -84.000086)
				)
				(arc
					(start 13.5001 -85.536024)
					(mid 13.656941 -86.645316)
					(end 14.115288 -87.667592)
				)
			)
		)
	)
	(zone
		(layer "B.Cu")
		(hatch none 0.5)
		(connect_pads
			(clearance 0)
		)
		(min_thickness 0.25)
		(keepout
			(tracks allowed)
			(vias allowed)
			(pads allowed)
			(copperpour allowed)
			(footprints not_allowed)
		)
		(placement
			(enabled no)
			(sheetname "")
		)
		(fill
			(thermal_gap 0.5)
			(thermal_bridge_width 0.5)
			(island_removal_mode 0)
		)
		(polygon
			(pts
				(arc
					(start 196.644514 -82.03057)
					(mid 179.766437 -99.502518)
					(end 202.165458 -90.099388)
				)
				(arc
					(start 202.165458 -90.099388)
					(mid 219.043535 -72.62744)
					(end 196.644514 -82.03057)
				)
			)
		)
	)
	(zone
		(layer "B.Cu")
		(hatch none 0.5)
		(connect_pads
			(clearance 0)
		)
		(min_thickness 0.25)
		(keepout
			(tracks allowed)
			(vias allowed)
			(pads allowed)
			(copperpour allowed)
			(footprints not_allowed)
		)
		(placement
			(enabled no)
			(sheetname "")
		)
		(fill
			(thermal_gap 0.5)
			(thermal_bridge_width 0.5)
			(island_removal_mode 0)
		)
		(polygon
			(pts
				(arc
					(start 237.611158 -91.971876)
					(mid 258.13568 -101.857445)
					(end 251.198634 -80.158082)
				)
				(arc
					(start 251.198634 -80.158082)
					(mid 230.674112 -70.272513)
					(end 237.611158 -91.971876)
				)
			)
		)
	)
	(zone
		(layer "B.Cu")
		(hatch none 0.5)
		(connect_pads
			(clearance 0)
		)
		(min_thickness 0.25)
		(keepout
			(tracks allowed)
			(vias allowed)
			(pads allowed)
			(copperpour allowed)
			(footprints not_allowed)
		)
		(placement
			(enabled no)
			(sheetname "")
		)
		(fill
			(thermal_gap 0.5)
			(thermal_bridge_width 0.5)
			(island_removal_mode 0)
		)
		(polygon
			(pts
				(arc
					(start 420.99992 -104.549956)
					(mid 424.999912 -108.549948)
					(end 428.999904 -104.549956)
				)
				(arc
					(start 428.999904 -104.549956)
					(mid 424.999912 -100.549964)
					(end 420.99992 -104.549956)
				)
			)
		)
		(polygon
			(pts
				(arc
					(start 422.999916 -104.549956)
					(mid 424.999912 -106.549952)
					(end 426.999908 -104.549956)
				)
				(arc
					(start 426.999908 -104.549956)
					(mid 424.999912 -102.54996)
					(end 422.999916 -104.549956)
				)
			)
		)
	)
	(zone
		(layer "B.Cu")
		(hatch none 0.5)
		(connect_pads
			(clearance 0)
		)
		(min_thickness 0.25)
		(keepout
			(tracks not_allowed)
			(vias allowed)
			(pads allowed)
			(copperpour not_allowed)
			(footprints allowed)
		)
		(placement
			(enabled no)
			(sheetname "")
		)
		(fill
			(thermal_gap 0.5)
			(thermal_bridge_width 0.5)
			(island_removal_mode 0)
		)
		(polygon
			(pts
				(arc
					(start 3.10007 -144.500092)
					(mid 8.200136 -149.600158)
					(end 13.299948 -144.500092)
				)
				(arc
					(start 13.299948 -138.308334)
					(mid 17.94438 -137.664187)
					(end 20.100036 -133.500114)
				)
				(arc
					(start 20.100036 -126.499874)
					(mid 14.99997 -121.399808)
					(end 9.899904 -126.499874)
				)
				(arc
					(start 9.899904 -132.691632)
					(mid 5.255573 -133.335991)
					(end 3.10007 -137.500106)
				)
			)
		)
		(polygon
			(pts
				(arc
					(start 4.99999 -137.500106)
					(mid 8.200136 -134.29996)
					(end 11.400028 -137.500106)
				)
				(arc
					(start 11.400028 -137.500106)
					(mid 8.200136 -140.699998)
					(end 4.99999 -137.500106)
				)
			)
		)
	)
	(zone
		(layer "B.Cu")
		(hatch none 0.5)
		(connect_pads
			(clearance 0)
		)
		(min_thickness 0.25)
		(keepout
			(tracks allowed)
			(vias allowed)
			(pads allowed)
			(copperpour allowed)
			(footprints not_allowed)
		)
		(placement
			(enabled no)
			(sheetname "")
		)
		(fill
			(thermal_gap 0.5)
			(thermal_bridge_width 0.5)
			(island_removal_mode 0)
		)
		(polygon
			(pts
				(arc
					(start 31.500064 -137.500106)
					(mid 8.200136 -114.200178)
					(end -15.100046 -137.500106)
				)
				(arc
					(start -15.100046 -137.500106)
					(mid 8.200136 -160.800288)
					(end 31.500064 -137.500106)
				)
			)
		)
	)
	(zone
		(layer "B.Cu")
		(hatch none 0.5)
		(connect_pads
			(clearance 0)
		)
		(min_thickness 0.25)
		(keepout
			(tracks allowed)
			(vias allowed)
			(pads allowed)
			(copperpour allowed)
			(footprints not_allowed)
		)
		(placement
			(enabled no)
			(sheetname "")
		)
		(fill
			(thermal_gap 0.5)
			(thermal_bridge_width 0.5)
			(island_removal_mode 0)
		)
		(polygon
			(pts
				(arc
					(start 440.399932 -9.500108)
					(mid 427.999906 2.899918)
					(end 415.59988 -9.500108)
				)
				(arc
					(start 415.59988 -9.500108)
					(mid 427.999906 -21.900134)
					(end 440.399932 -9.500108)
				)
			)
		)
	)
	(zone
		(layer "B.Cu")
		(hatch none 0.5)
		(connect_pads
			(clearance 0)
		)
		(min_thickness 0.25)
		(keepout
			(tracks not_allowed)
			(vias allowed)
			(pads allowed)
			(copperpour not_allowed)
			(footprints allowed)
		)
		(placement
			(enabled no)
			(sheetname "")
		)
		(fill
			(thermal_gap 0.5)
			(thermal_bridge_width 0.5)
			(island_removal_mode 0)
		)
		(polygon
			(pts
				(arc
					(start 86.023958 -142.500096)
					(mid 80.000094 -136.476232)
					(end 73.975976 -142.500096)
				)
				(arc
					(start 73.975976 -147.500086)
					(mid 80.000094 -153.524204)
					(end 86.023958 -147.500086)
				)
			)
		)
	)
	(zone
		(layer "B.Cu")
		(hatch none 0.5)
		(connect_pads
			(clearance 0)
		)
		(min_thickness 0.25)
		(keepout
			(tracks allowed)
			(vias allowed)
			(pads allowed)
			(copperpour allowed)
			(footprints not_allowed)
		)
		(placement
			(enabled no)
			(sheetname "")
		)
		(fill
			(thermal_gap 0.5)
			(thermal_bridge_width 0.5)
			(island_removal_mode 0)
		)
		(polygon
			(pts
				(arc
					(start 469.399874 -29.500068)
					(mid 457.000102 -17.100296)
					(end 444.600076 -29.500068)
				)
				(arc
					(start 444.600076 -29.500068)
					(mid 457.000102 -41.900094)
					(end 469.399874 -29.500068)
				)
			)
		)
	)
	(zone
		(layer "B.Cu")
		(hatch none 0.5)
		(connect_pads
			(clearance 0)
		)
		(min_thickness 0.25)
		(keepout
			(tracks allowed)
			(vias allowed)
			(pads allowed)
			(copperpour allowed)
			(footprints not_allowed)
		)
		(placement
			(enabled no)
			(sheetname "")
		)
		(fill
			(thermal_gap 0.5)
			(thermal_bridge_width 0.5)
			(island_removal_mode 0)
		)
		(polygon
			(pts
				(xy 455.000106 -97.499932) (xy 465.000086 -97.499932) (xy 465.000086 -77.499972) (xy 455.000106 -77.499972)
			)
		)
	)
	(zone
		(layer "B.Cu")
		(hatch none 0.5)
		(connect_pads
			(clearance 0)
		)
		(min_thickness 0.25)
		(keepout
			(tracks not_allowed)
			(vias allowed)
			(pads allowed)
			(copperpour not_allowed)
			(footprints allowed)
		)
		(placement
			(enabled no)
			(sheetname "")
		)
		(fill
			(thermal_gap 0.5)
			(thermal_bridge_width 0.5)
			(island_removal_mode 0)
		)
		(polygon
			(pts
				(arc
					(start 452.499984 -29.500068)
					(mid 457.000102 -34.000186)
					(end 461.499966 -29.500068)
				)
				(arc
					(start 461.499966 -24.500078)
					(mid 457.000102 -20.000214)
					(end 452.499984 -24.500078)
				)
			)
		)
		(polygon
			(pts
				(arc
					(start 458.499972 -24.500078)
					(mid 457.000102 -23.000208)
					(end 455.499978 -24.500078)
				)
				(arc
					(start 455.499978 -26.036016)
					(mid 455.342997 -27.145321)
					(end 454.884536 -28.167584)
				)
				(arc
					(start 454.884536 -28.167584)
					(mid 457.00017 -32.000295)
					(end 459.115414 -28.167584)
				)
				(arc
					(start 459.115414 -28.167584)
					(mid 458.656926 -27.145328)
					(end 458.499972 -26.036016)
				)
			)
		)
	)
	(zone
		(layer "B.Cu")
		(hatch none 0.5)
		(connect_pads
			(clearance 0)
		)
		(min_thickness 0.25)
		(keepout
			(tracks allowed)
			(vias allowed)
			(pads allowed)
			(copperpour allowed)
			(footprints not_allowed)
		)
		(placement
			(enabled no)
			(sheetname "")
		)
		(fill
			(thermal_gap 0.5)
			(thermal_bridge_width 0.5)
			(island_removal_mode 0)
		)
		(polygon
			(pts
				(arc
					(start 422.999916 -60.099956)
					(mid 424.999912 -62.099952)
					(end 426.999908 -60.099956)
				)
				(arc
					(start 426.999908 -60.099956)
					(mid 424.999912 -58.09996)
					(end 422.999916 -60.099956)
				)
			)
		)
	)
	(zone
		(layer "B.Cu")
		(hatch none 0.5)
		(connect_pads
			(clearance 0)
		)
		(min_thickness 0.25)
		(keepout
			(tracks allowed)
			(vias allowed)
			(pads allowed)
			(copperpour allowed)
			(footprints not_allowed)
		)
		(placement
			(enabled no)
			(sheetname "")
		)
		(fill
			(thermal_gap 0.5)
			(thermal_bridge_width 0.5)
			(island_removal_mode 0)
		)
		(polygon
			(pts
				(arc
					(start 10.999978 -60.099956)
					(mid 14.99997 -64.099948)
					(end 18.999962 -60.099956)
				)
				(arc
					(start 18.999962 -60.099956)
					(mid 14.99997 -56.099964)
					(end 10.999978 -60.099956)
				)
			)
		)
		(polygon
			(pts
				(arc
					(start 16.999966 -60.099956)
					(mid 14.99997 -58.09996)
					(end 12.999974 -60.099956)
				)
				(arc
					(start 12.999974 -60.099956)
					(mid 14.99997 -62.099952)
					(end 16.999966 -60.099956)
				)
			)
		)
	)
	(zone
		(layer "B.Cu")
		(hatch none 0.5)
		(connect_pads
			(clearance 0)
		)
		(min_thickness 0.25)
		(keepout
			(tracks not_allowed)
			(vias allowed)
			(pads allowed)
			(copperpour not_allowed)
			(footprints allowed)
		)
		(placement
			(enabled no)
			(sheetname "")
		)
		(fill
			(thermal_gap 0.5)
			(thermal_bridge_width 0.5)
			(island_removal_mode 0)
		)
		(polygon
			(pts
				(arc
					(start 185.50001 -16.500094)
					(mid 190.000128 -11.999976)
					(end 194.499992 -16.500094)
				)
				(arc
					(start 194.499992 -21.500084)
					(mid 190.000128 -25.999948)
					(end 185.50001 -21.500084)
				)
			)
		)
		(polygon
			(pts
				(arc
					(start 192.11544 -20.1676)
					(mid 190.000196 -24.000096)
					(end 187.884562 -20.1676)
				)
				(arc
					(start 187.884562 -20.1676)
					(mid 188.343027 -19.145212)
					(end 188.500004 -18.035778)
				)
				(arc
					(start 188.500004 -16.500094)
					(mid 190.000128 -14.99997)
					(end 191.499998 -16.500094)
				)
				(arc
					(start 191.499998 -18.035778)
					(mid 191.656926 -19.145226)
					(end 192.11544 -20.1676)
				)
			)
		)
	)
	(zone
		(layer "B.Cu")
		(hatch none 0.5)
		(connect_pads
			(clearance 0)
		)
		(min_thickness 0.25)
		(keepout
			(tracks allowed)
			(vias allowed)
			(pads allowed)
			(copperpour allowed)
			(footprints not_allowed)
		)
		(placement
			(enabled no)
			(sheetname "")
		)
		(fill
			(thermal_gap 0.5)
			(thermal_bridge_width 0.5)
			(island_removal_mode 0)
		)
		(polygon
			(pts
				(arc
					(start 242.81003 -79.630016)
					(mid 238.810038 -75.630024)
					(end 234.810046 -79.630016)
				)
				(arc
					(start 234.810046 -79.630016)
					(mid 238.810038 -83.630008)
					(end 242.81003 -79.630016)
				)
			)
		)
		(polygon
			(pts
				(arc
					(start 240.920016 -79.630016)
					(mid 238.810038 -77.520038)
					(end 236.70006 -79.630016)
				)
				(arc
					(start 236.70006 -79.630016)
					(mid 238.810038 -81.739994)
					(end 240.920016 -79.630016)
				)
			)
		)
	)
	(zone
		(layer "B.Cu")
		(hatch none 0.5)
		(connect_pads
			(clearance 0)
		)
		(min_thickness 0.25)
		(keepout
			(tracks not_allowed)
			(vias allowed)
			(pads allowed)
			(copperpour not_allowed)
			(footprints allowed)
		)
		(placement
			(enabled no)
			(sheetname "")
		)
		(fill
			(thermal_gap 0.5)
			(thermal_bridge_width 0.5)
			(island_removal_mode 0)
		)
		(polygon
			(pts
				(arc
					(start 355.499924 -147.500086)
					(mid 360.000042 -152.000204)
					(end 364.499906 -147.500086)
				)
				(arc
					(start 364.499906 -142.500096)
					(mid 360.000042 -138.000232)
					(end 355.499924 -142.500096)
				)
			)
		)
		(polygon
			(pts
				(arc
					(start 361.499912 -142.500096)
					(mid 360.000042 -141.000226)
					(end 358.499918 -142.500096)
				)
				(arc
					(start 358.499918 -144.03578)
					(mid 358.343065 -145.145186)
					(end 357.88473 -146.167602)
				)
				(arc
					(start 357.88473 -146.167602)
					(mid 360.000042 -149.999708)
					(end 362.115354 -146.167602)
				)
				(arc
					(start 362.115354 -146.167602)
					(mid 361.656889 -145.145214)
					(end 361.499912 -144.03578)
				)
			)
		)
	)
	(zone
		(layer "B.Cu")
		(hatch none 0.5)
		(connect_pads
			(clearance 0)
		)
		(min_thickness 0.25)
		(keepout
			(tracks allowed)
			(vias allowed)
			(pads allowed)
			(copperpour allowed)
			(footprints not_allowed)
		)
		(placement
			(enabled no)
			(sheetname "")
		)
		(fill
			(thermal_gap 0.5)
			(thermal_bridge_width 0.5)
			(island_removal_mode 0)
		)
		(polygon
			(pts
				(arc
					(start 422.999916 -104.549956)
					(mid 424.999912 -106.549952)
					(end 426.999908 -104.549956)
				)
				(arc
					(start 426.999908 -104.549956)
					(mid 424.999912 -102.54996)
					(end 422.999916 -104.549956)
				)
			)
		)
	)
	(zone
		(layer "B.Cu")
		(hatch none 0.5)
		(connect_pads
			(clearance 0)
		)
		(min_thickness 0.25)
		(keepout
			(tracks not_allowed)
			(vias allowed)
			(pads allowed)
			(copperpour not_allowed)
			(footprints allowed)
		)
		(placement
			(enabled no)
			(sheetname "")
		)
		(fill
			(thermal_gap 0.5)
			(thermal_bridge_width 0.5)
			(island_removal_mode 0)
		)
		(polygon
			(pts
				(arc
					(start 73.975976 -147.500086)
					(mid 80.000094 -153.524204)
					(end 86.023958 -147.500086)
				)
				(arc
					(start 86.023958 -142.500096)
					(mid 80.000094 -136.476232)
					(end 73.975976 -142.500096)
				)
			)
		)
	)
	(zone
		(layer "B.Cu")
		(hatch none 0.5)
		(connect_pads
			(clearance 0)
		)
		(min_thickness 0.25)
		(keepout
			(tracks not_allowed)
			(vias allowed)
			(pads allowed)
			(copperpour not_allowed)
			(footprints allowed)
		)
		(placement
			(enabled no)
			(sheetname "")
		)
		(fill
			(thermal_gap 0.5)
			(thermal_bridge_width 0.5)
			(island_removal_mode 0)
		)
		(polygon
			(pts
				(arc
					(start 185.50001 -87.499952)
					(mid 190.000128 -82.999834)
					(end 194.499992 -87.499952)
				)
				(arc
					(start 194.499992 -92.499942)
					(mid 190.000128 -96.999806)
					(end 185.50001 -92.499942)
				)
			)
		)
		(polygon
			(pts
				(arc
					(start 192.11544 -91.167712)
					(mid 190.000196 -95.000208)
					(end 187.884562 -91.167712)
				)
				(arc
					(start 187.884562 -91.167712)
					(mid 188.343027 -90.145324)
					(end 188.500004 -89.03589)
				)
				(arc
					(start 188.500004 -87.499952)
					(mid 190.000128 -85.999828)
					(end 191.499998 -87.499952)
				)
				(arc
					(start 191.499998 -89.03589)
					(mid 191.656926 -90.145338)
					(end 192.11544 -91.167712)
				)
			)
		)
	)
	(zone
		(layer "B.Cu")
		(hatch none 0.5)
		(connect_pads
			(clearance 0)
		)
		(min_thickness 0.25)
		(keepout
			(tracks allowed)
			(vias allowed)
			(pads allowed)
			(copperpour allowed)
			(footprints not_allowed)
		)
		(placement
			(enabled no)
			(sheetname "")
		)
		(fill
			(thermal_gap 0.5)
			(thermal_bridge_width 0.5)
			(island_removal_mode 0)
		)
		(polygon
			(pts
				(arc
					(start 236.70006 -22.47011)
					(mid 238.810038 -24.580088)
					(end 240.920016 -22.47011)
				)
				(arc
					(start 240.920016 -22.47011)
					(mid 238.810038 -20.360132)
					(end 236.70006 -22.47011)
				)
			)
		)
	)
	(zone
		(layer "B.Cu")
		(hatch none 0.5)
		(connect_pads
			(clearance 0)
		)
		(min_thickness 0.25)
		(keepout
			(tracks allowed)
			(vias allowed)
			(pads allowed)
			(copperpour allowed)
			(footprints not_allowed)
		)
		(placement
			(enabled no)
			(sheetname "")
		)
		(fill
			(thermal_gap 0.5)
			(thermal_bridge_width 0.5)
			(island_removal_mode 0)
		)
		(polygon
			(pts
				(arc
					(start 455.099928 -137.500106)
					(mid 431.8 -114.200178)
					(end 408.500072 -137.500106)
				)
				(arc
					(start 408.500072 -137.500106)
					(mid 431.8 -160.800034)
					(end 455.099928 -137.500106)
				)
			)
		)
	)
	(zone
		(layer "B.Cu")
		(hatch none 0.5)
		(connect_pads
			(clearance 0)
		)
		(min_thickness 0.25)
		(keepout
			(tracks allowed)
			(vias allowed)
			(pads allowed)
			(copperpour allowed)
			(footprints not_allowed)
		)
		(placement
			(enabled no)
			(sheetname "")
		)
		(fill
			(thermal_gap 0.5)
			(thermal_bridge_width 0.5)
			(island_removal_mode 0)
		)
		(polygon
			(pts
				(arc
					(start 469.399874 -126.499874)
					(mid 457.000102 -114.100102)
					(end 444.600076 -126.499874)
				)
				(arc
					(start 444.600076 -126.499874)
					(mid 457.000102 -138.8999)
					(end 469.399874 -126.499874)
				)
			)
		)
	)
	(zone
		(layer "B.Cu")
		(hatch none 0.5)
		(connect_pads
			(clearance 0)
		)
		(min_thickness 0.25)
		(keepout
			(tracks allowed)
			(vias allowed)
			(pads allowed)
			(copperpour allowed)
			(footprints not_allowed)
		)
		(placement
			(enabled no)
			(sheetname "")
		)
		(fill
			(thermal_gap 0.5)
			(thermal_bridge_width 0.5)
			(island_removal_mode 0)
		)
		(polygon
			(pts
				(arc
					(start 440.399932 -89.000076)
					(mid 427.999906 -76.60005)
					(end 415.59988 -89.000076)
				)
				(arc
					(start 415.59988 -89.000076)
					(mid 427.999906 -101.400102)
					(end 440.399932 -89.000076)
				)
			)
		)
	)
	(zone
		(layer "B.Cu")
		(hatch none 0.5)
		(connect_pads
			(clearance 0)
		)
		(min_thickness 0.25)
		(keepout
			(tracks allowed)
			(vias allowed)
			(pads allowed)
			(copperpour allowed)
			(footprints not_allowed)
		)
		(placement
			(enabled no)
			(sheetname "")
		)
		(fill
			(thermal_gap 0.5)
			(thermal_bridge_width 0.5)
			(island_removal_mode 0)
		)
		(polygon
			(pts
				(arc
					(start 206.70012 -22.47011)
					(mid 208.810098 -24.580088)
					(end 210.920076 -22.47011)
				)
				(arc
					(start 210.920076 -22.47011)
					(mid 208.810098 -20.360132)
					(end 206.70012 -22.47011)
				)
			)
		)
	)
	(zone
		(layer "B.Cu")
		(hatch none 0.5)
		(connect_pads
			(clearance 0)
		)
		(min_thickness 0.25)
		(keepout
			(tracks allowed)
			(vias allowed)
			(pads allowed)
			(copperpour allowed)
			(footprints not_allowed)
		)
		(placement
			(enabled no)
			(sheetname "")
		)
		(fill
			(thermal_gap 0.5)
			(thermal_bridge_width 0.5)
			(island_removal_mode 0)
		)
		(polygon
			(pts
				(arc
					(start 112.40008 -92.499942)
					(mid 100.000054 -80.099916)
					(end 87.600028 -92.499942)
				)
				(arc
					(start 87.600028 -92.499942)
					(mid 100.000054 -104.899968)
					(end 112.40008 -92.499942)
				)
			)
		)
	)
	(zone
		(layer "B.Cu")
		(hatch none 0.5)
		(connect_pads
			(clearance 0)
		)
		(min_thickness 0.25)
		(keepout
			(tracks allowed)
			(vias allowed)
			(pads allowed)
			(copperpour allowed)
			(footprints not_allowed)
		)
		(placement
			(enabled no)
			(sheetname "")
		)
		(fill
			(thermal_gap 0.5)
			(thermal_bridge_width 0.5)
			(island_removal_mode 0)
		)
		(polygon
			(pts
				(arc
					(start 381.40005 -18.50009)
					(mid 369.000024 -6.100064)
					(end 356.599998 -18.50009)
				)
				(arc
					(start 356.599998 -18.50009)
					(mid 369.000024 -30.900116)
					(end 381.40005 -18.50009)
				)
			)
		)
	)
	(zone
		(layer "B.Cu")
		(hatch none 0.5)
		(connect_pads
			(clearance 0)
		)
		(min_thickness 0.25)
		(keepout
			(tracks not_allowed)
			(vias allowed)
			(pads allowed)
			(copperpour not_allowed)
			(footprints allowed)
		)
		(placement
			(enabled no)
			(sheetname "")
		)
		(fill
			(thermal_gap 0.5)
			(thermal_bridge_width 0.5)
			(island_removal_mode 0)
		)
		(polygon
			(pts
				(arc
					(start 73.97623 -147.500086)
					(mid 80.000348 -153.524204)
					(end 86.024212 -147.500086)
				)
				(arc
					(start 86.024212 -142.500096)
					(mid 80.000348 -136.476232)
					(end 73.97623 -142.500096)
				)
			)
		)
	)
	(zone
		(layer "B.Cu")
		(hatch none 0.5)
		(connect_pads
			(clearance 0)
		)
		(min_thickness 0.25)
		(keepout
			(tracks not_allowed)
			(vias allowed)
			(pads allowed)
			(copperpour not_allowed)
			(footprints allowed)
		)
		(placement
			(enabled no)
			(sheetname "")
		)
		(fill
			(thermal_gap 0.5)
			(thermal_bridge_width 0.5)
			(island_removal_mode 0)
		)
		(polygon
			(pts
				(arc
					(start 95.499936 -87.499952)
					(mid 100.000054 -82.999834)
					(end 104.499918 -87.499952)
				)
				(arc
					(start 104.499918 -92.499942)
					(mid 100.000054 -96.999806)
					(end 95.499936 -92.499942)
				)
			)
		)
		(polygon
			(pts
				(arc
					(start 102.115366 -91.167712)
					(mid 100.000054 -94.999818)
					(end 97.884742 -91.167712)
				)
				(arc
					(start 97.884742 -91.167712)
					(mid 98.343142 -90.145315)
					(end 98.49993 -89.03589)
				)
				(arc
					(start 98.49993 -87.499952)
					(mid 100.000054 -85.999828)
					(end 101.499924 -87.499952)
				)
				(arc
					(start 101.499924 -89.03589)
					(mid 101.656852 -90.145338)
					(end 102.115366 -91.167712)
				)
			)
		)
	)
	(zone
		(layer "B.Cu")
		(hatch none 0.5)
		(connect_pads
			(clearance 0)
		)
		(min_thickness 0.25)
		(keepout
			(tracks allowed)
			(vias allowed)
			(pads allowed)
			(copperpour allowed)
			(footprints not_allowed)
		)
		(placement
			(enabled no)
			(sheetname "")
		)
		(fill
			(thermal_gap 0.5)
			(thermal_bridge_width 0.5)
			(island_removal_mode 0)
		)
		(polygon
			(pts
				(arc
					(start 4.99999 -157.299914)
					(mid 2.171569 -156.128343)
					(end 0.999998 -153.299922)
				)
				(arc
					(start 0.999998 -4.99999)
					(mid 2.171569 -2.171569)
					(end 4.99999 -0.999998)
				)
				(xy 34.99993 -0.999998) (xy 34.99993 -152.500076)
				(arc
					(start 68.652644 -152.500076)
					(mid 72.317795 -137.766385)
					(end 87.499952 -137.625328)
				)
				(arc
					(start 87.499952 -153.299922)
					(mid 86.328381 -156.128343)
					(end 83.49996 -157.299914)
				)
				(arc
					(start 83.000088 -157.299914)
					(mid 80.171667 -158.471485)
					(end 79.000096 -161.299906)
				)
				(arc
					(start 79.000096 -166.649908)
					(mid 77.828525 -169.478329)
					(end 75.000104 -170.6499)
				)
				(arc
					(start 35.999928 -170.6499)
					(mid 33.171507 -169.478329)
					(end 31.999936 -166.649908)
				)
				(arc
					(start 31.999936 -163.299902)
					(mid 30.24258 -159.05727)
					(end 25.999948 -157.299914)
				)
			)
		)
	)
	(zone
		(layer "B.Cu")
		(hatch none 0.5)
		(connect_pads
			(clearance 0)
		)
		(min_thickness 0.25)
		(keepout
			(tracks allowed)
			(vias allowed)
			(pads allowed)
			(copperpour allowed)
			(footprints allowed)
		)
		(placement
			(enabled no)
			(sheetname "")
		)
		(fill
			(thermal_gap 0.5)
			(thermal_bridge_width 0.5)
			(island_removal_mode 0)
		)
		(polygon
			(pts
				(xy 267.988796 -78.621128) (xy 267.988796 -69.256402) (xy 278.807164 -69.256402) (xy 278.807164 -78.621128)
			)
		)
	)
	(zone
		(layer "B.Cu")
		(hatch none 0.5)
		(connect_pads
			(clearance 0)
		)
		(min_thickness 0.25)
		(keepout
			(tracks allowed)
			(vias allowed)
			(pads allowed)
			(copperpour allowed)
			(footprints not_allowed)
		)
		(placement
			(enabled no)
			(sheetname "")
		)
		(fill
			(thermal_gap 0.5)
			(thermal_bridge_width 0.5)
			(island_removal_mode 0)
		)
		(polygon
			(pts
				(arc
					(start 24.400002 -89.000076)
					(mid 11.999976 -76.60005)
					(end -0.40005 -89.000076)
				)
				(arc
					(start -0.40005 -89.000076)
					(mid 11.999976 -101.400102)
					(end 24.400002 -89.000076)
				)
			)
		)
	)
	(zone
		(layer "B.Cu")
		(hatch none 0.5)
		(connect_pads
			(clearance 0)
		)
		(min_thickness 0.25)
		(keepout
			(tracks not_allowed)
			(vias allowed)
			(pads allowed)
			(copperpour not_allowed)
			(footprints allowed)
		)
		(placement
			(enabled no)
			(sheetname "")
		)
		(fill
			(thermal_gap 0.5)
			(thermal_bridge_width 0.5)
			(island_removal_mode 0)
		)
		(polygon
			(pts
				(arc
					(start 423.500042 -4.500118)
					(mid 424.810741 -1.325426)
					(end 427.979332 0)
				)
				(arc
					(start 428.02048 0)
					(mid 431.189269 -1.325303)
					(end 432.500024 -4.500118)
				)
				(arc
					(start 432.500024 -9.500108)
					(mid 428.00016 -13.999972)
					(end 423.500042 -9.500108)
				)
			)
		)
		(polygon
			(pts
				(arc
					(start 430.115472 -8.167624)
					(mid 428.000228 -12.00012)
					(end 425.884594 -8.167624)
				)
				(arc
					(start 425.884594 -8.167624)
					(mid 426.343059 -7.145236)
					(end 426.500036 -6.035802)
				)
				(arc
					(start 426.500036 -4.500118)
					(mid 428.00016 -2.999994)
					(end 429.50003 -4.500118)
				)
				(arc
					(start 429.50003 -6.035802)
					(mid 429.656958 -7.14525)
					(end 430.115472 -8.167624)
				)
			)
		)
	)
	(zone
		(layer "B.Cu")
		(hatch none 0.5)
		(connect_pads
			(clearance 0)
		)
		(min_thickness 0.25)
		(keepout
			(tracks allowed)
			(vias allowed)
			(pads allowed)
			(copperpour allowed)
			(footprints not_allowed)
		)
		(placement
			(enabled no)
			(sheetname "")
		)
		(fill
			(thermal_gap 0.5)
			(thermal_bridge_width 0.5)
			(island_removal_mode 0)
		)
		(polygon
			(pts
				(arc
					(start 210.920076 -79.630016)
					(mid 208.810098 -77.520038)
					(end 206.70012 -79.630016)
				)
				(arc
					(start 206.70012 -79.630016)
					(mid 208.810098 -81.739994)
					(end 210.920076 -79.630016)
				)
			)
		)
	)
	(zone
		(layer "B.Cu")
		(hatch none 0.5)
		(connect_pads
			(clearance 0)
		)
		(min_thickness 0.25)
		(keepout
			(tracks allowed)
			(vias allowed)
			(pads allowed)
			(copperpour allowed)
			(footprints not_allowed)
		)
		(placement
			(enabled no)
			(sheetname "")
		)
		(fill
			(thermal_gap 0.5)
			(thermal_bridge_width 0.5)
			(island_removal_mode 0)
		)
		(polygon
			(pts
				(arc
					(start 352.400108 -92.499942)
					(mid 340.000082 -80.099916)
					(end 327.600056 -92.499942)
				)
				(arc
					(start 327.600056 -92.499942)
					(mid 340.000082 -104.899968)
					(end 352.400108 -92.499942)
				)
			)
		)
	)
	(zone
		(layer "B.Cu")
		(hatch none 0.5)
		(connect_pads
			(clearance 0)
		)
		(min_thickness 0.25)
		(keepout
			(tracks not_allowed)
			(vias allowed)
			(pads allowed)
			(copperpour not_allowed)
			(footprints allowed)
		)
		(placement
			(enabled no)
			(sheetname "")
		)
		(fill
			(thermal_gap 0.5)
			(thermal_bridge_width 0.5)
			(island_removal_mode 0)
		)
		(polygon
			(pts
				(arc
					(start 66.499994 -13.5001)
					(mid 71.000112 -8.999982)
					(end 75.499976 -13.5001)
				)
				(arc
					(start 75.499976 -18.50009)
					(mid 71.000112 -22.999954)
					(end 66.499994 -18.50009)
				)
			)
		)
		(polygon
			(pts
				(arc
					(start 73.115424 -17.167606)
					(mid 71.00018 -21.000102)
					(end 68.884546 -17.167606)
				)
				(arc
					(start 68.884546 -17.167606)
					(mid 69.343011 -16.145218)
					(end 69.499988 -15.035784)
				)
				(arc
					(start 69.499988 -13.5001)
					(mid 71.000112 -11.999976)
					(end 72.499982 -13.5001)
				)
				(arc
					(start 72.499982 -15.035784)
					(mid 72.65691 -16.145232)
					(end 73.115424 -17.167606)
				)
			)
		)
	)
	(zone
		(layer "B.Cu")
		(hatch none 0.5)
		(connect_pads
			(clearance 0)
		)
		(min_thickness 0.25)
		(keepout
			(tracks not_allowed)
			(vias allowed)
			(pads allowed)
			(copperpour not_allowed)
			(footprints allowed)
		)
		(placement
			(enabled no)
			(sheetname "")
		)
		(fill
			(thermal_gap 0.5)
			(thermal_bridge_width 0.5)
			(island_removal_mode 0)
		)
		(polygon
			(pts
				(arc
					(start 3.10007 -144.500092)
					(mid 8.200136 -149.600158)
					(end 13.299948 -144.500092)
				)
				(arc
					(start 13.299948 -137.500106)
					(mid 8.200136 -132.400294)
					(end 3.10007 -137.500106)
				)
			)
		)
	)
	(zone
		(layer "B.Cu")
		(hatch none 0.5)
		(connect_pads
			(clearance 0)
		)
		(min_thickness 0.25)
		(keepout
			(tracks allowed)
			(vias allowed)
			(pads allowed)
			(copperpour allowed)
			(footprints not_allowed)
		)
		(placement
			(enabled no)
			(sheetname "")
		)
		(fill
			(thermal_gap 0.5)
			(thermal_bridge_width 0.5)
			(island_removal_mode 0)
		)
		(polygon
			(pts
				(xy 408.200098 -51.900074) (xy 457.000102 -51.900074)
				(arc
					(start 457.000102 -41.999916)
					(mid 448.077802 -38.254534)
					(end 444.502286 -29.262832)
				)
				(arc
					(start 444.502286 -29.262832)
					(mid 436.655286 -27.152269)
					(end 430.60747 -21.725128)
				)
				(arc
					(start 430.60747 -21.725128)
					(mid 423.767047 -21.261483)
					(end 418.200078 -17.259554)
				)
				(xy 408.200098 -17.259554)
			)
		)
	)
	(zone
		(layer "B.Cu")
		(hatch none 0.5)
		(connect_pads
			(clearance 0)
		)
		(min_thickness 0.25)
		(keepout
			(tracks allowed)
			(vias allowed)
			(pads allowed)
			(copperpour allowed)
			(footprints not_allowed)
		)
		(placement
			(enabled no)
			(sheetname "")
		)
		(fill
			(thermal_gap 0.5)
			(thermal_bridge_width 0.5)
			(island_removal_mode 0)
		)
		(polygon
			(pts
				(arc
					(start 10.999978 -104.549956)
					(mid 14.99997 -108.549948)
					(end 18.999962 -104.549956)
				)
				(arc
					(start 18.999962 -104.549956)
					(mid 14.99997 -100.549964)
					(end 10.999978 -104.549956)
				)
			)
		)
		(polygon
			(pts
				(arc
					(start 12.999974 -104.549956)
					(mid 14.99997 -106.549952)
					(end 16.999966 -104.549956)
				)
				(arc
					(start 16.999966 -104.549956)
					(mid 14.99997 -102.54996)
					(end 12.999974 -104.549956)
				)
			)
		)
	)
	(zone
		(layer "B.Cu")
		(hatch none 0.5)
		(connect_pads
			(clearance 0)
		)
		(min_thickness 0.25)
		(keepout
			(tracks not_allowed)
			(vias allowed)
			(pads allowed)
			(copperpour not_allowed)
			(footprints allowed)
		)
		(placement
			(enabled no)
			(sheetname "")
		)
		(fill
			(thermal_gap 0.5)
			(thermal_bridge_width 0.5)
			(island_removal_mode 0)
		)
		(polygon
			(pts
				(arc
					(start 366.404906 -142.500096)
					(mid 360.000042 -136.095232)
					(end 353.594924 -142.500096)
				)
				(arc
					(start 353.594924 -147.500086)
					(mid 360.000042 -153.905204)
					(end 366.404906 -147.500086)
				)
			)
		)
	)
	(zone
		(layer "B.Cu")
		(hatch none 0.5)
		(connect_pads
			(clearance 0)
		)
		(min_thickness 0.25)
		(keepout
			(tracks allowed)
			(vias allowed)
			(pads allowed)
			(copperpour allowed)
			(footprints not_allowed)
		)
		(placement
			(enabled no)
			(sheetname "")
		)
		(fill
			(thermal_gap 0.5)
			(thermal_bridge_width 0.5)
			(island_removal_mode 0)
		)
		(polygon
			(pts
				(arc
					(start 419.400228 -137.563606)
					(mid 438.320627 -148.047589)
					(end 437.399938 -126.436374)
				)
				(arc
					(start 437.399938 -126.436374)
					(mid 418.479539 -115.952391)
					(end 419.400228 -137.563606)
				)
			)
		)
	)
	(zone
		(layer "B.Cu")
		(hatch none 0.5)
		(connect_pads
			(clearance 0)
		)
		(min_thickness 0.25)
		(keepout
			(tracks allowed)
			(vias allowed)
			(pads allowed)
			(copperpour allowed)
			(footprints not_allowed)
		)
		(placement
			(enabled no)
			(sheetname "")
		)
		(fill
			(thermal_gap 0.5)
			(thermal_bridge_width 0.5)
			(island_removal_mode 0)
		)
		(polygon
			(pts
				(xy 404.999952 -152.500076) (xy 404.999952 -0.999998) (xy 369.499896 -0.999998)
				(arc
					(start 369.499896 -6.10997)
					(mid 369.000151 -30.899782)
					(end 368.499898 -6.10997)
				)
				(xy 368.499898 -0.999998) (xy 262.400034 -0.999998)
				(arc
					(start 262.400034 -21.500084)
					(mid 256.936169 -31.778718)
					(end 245.359682 -32.999172)
				)
				(arc
					(start 245.359682 -32.999172)
					(mid 226.4564 -23.540905)
					(end 243.450364 -10.971022)
				)
				(arc
					(start 243.450364 -10.971022)
					(mid 253.847566 -9.711931)
					(end 261.500112 -16.862044)
				)
				(xy 261.500112 -0.999998) (xy 178.500024 -0.999998)
				(arc
					(start 178.500024 -16.862044)
					(mid 188.310182 -9.215627)
					(end 199.82053 -13.929106)
				)
				(arc
					(start 199.82053 -13.929106)
					(mid 221.193239 -23.108889)
					(end 198.989442 -30.040834)
				)
				(arc
					(start 198.989442 -30.040834)
					(mid 185.401653 -33.01586)
					(end 177.600102 -21.500084)
				)
				(xy 177.600102 -0.999998) (xy 71.499984 -0.999998)
				(arc
					(start 71.499984 -6.10997)
					(mid 71.000239 -30.899782)
					(end 70.499986 -6.10997)
				)
				(xy 70.499986 -0.999998) (xy 34.99993 -0.999998) (xy 34.99993 -152.500076)
				(arc
					(start 68.652644 -152.500076)
					(mid 72.317795 -137.766385)
					(end 87.499952 -137.625328)
				)
				(arc
					(start 87.499952 -110.499906)
					(mid 88.956543 -105.741935)
					(end 92.82684 -102.614476)
				)
				(arc
					(start 92.82684 -102.614476)
					(mid 99.497266 -80.110649)
					(end 107.969304 -102.00005)
				)
				(arc
					(start 182.030624 -102.00005)
					(mid 179.99316 -85.176919)
					(end 196.644514 -82.03057)
				)
				(arc
					(start 196.644514 -82.03057)
					(mid 219.043475 -72.627481)
					(end 202.165458 -90.099388)
				)
				(arc
					(start 202.165458 -90.099388)
					(mid 201.694379 -96.623367)
					(end 197.969378 -102.00005)
				)
				(arc
					(start 242.030758 -102.00005)
					(mid 238.653047 -97.50069)
					(end 237.611158 -91.971876)
				)
				(arc
					(start 237.611158 -91.971876)
					(mid 230.674041 -70.272432)
					(end 251.198634 -80.158082)
				)
				(arc
					(start 251.198634 -80.158082)
					(mid 261.843956 -88.828552)
					(end 257.969258 -102.00005)
				)
				(arc
					(start 332.030578 -102.00005)
					(mid 340.502517 -80.110095)
					(end 347.173296 -102.614476)
				)
				(arc
					(start 347.173296 -102.614476)
					(mid 351.043568 -105.741909)
					(end 352.49993 -110.499906)
				)
				(arc
					(start 352.49993 -137.625328)
					(mid 367.682182 -137.766266)
					(end 371.347238 -152.500076)
				)
			)
		)
	)
	(zone
		(layer "B.Cu")
		(hatch none 0.5)
		(connect_pads
			(clearance 0)
		)
		(min_thickness 0.25)
		(keepout
			(tracks allowed)
			(vias allowed)
			(pads allowed)
			(copperpour allowed)
			(footprints not_allowed)
		)
		(placement
			(enabled no)
			(sheetname "")
		)
		(fill
			(thermal_gap 0.5)
			(thermal_bridge_width 0.5)
			(island_removal_mode 0)
		)
		(polygon
			(pts
				(arc
					(start 204.810106 -22.47011)
					(mid 208.810098 -26.470102)
					(end 212.81009 -22.47011)
				)
				(arc
					(start 212.81009 -22.47011)
					(mid 208.810098 -18.470118)
					(end 204.810106 -22.47011)
				)
			)
		)
		(polygon
			(pts
				(arc
					(start 206.70012 -22.47011)
					(mid 208.810098 -24.580088)
					(end 210.920076 -22.47011)
				)
				(arc
					(start 210.920076 -22.47011)
					(mid 208.810098 -20.360132)
					(end 206.70012 -22.47011)
				)
			)
		)
	)
	(zone
		(layer "B.Cu")
		(hatch none 0.5)
		(connect_pads
			(clearance 0)
		)
		(min_thickness 0.25)
		(keepout
			(tracks not_allowed)
			(vias allowed)
			(pads allowed)
			(copperpour not_allowed)
			(footprints allowed)
		)
		(placement
			(enabled no)
			(sheetname "")
		)
		(fill
			(thermal_gap 0.5)
			(thermal_bridge_width 0.5)
			(island_removal_mode 0)
		)
		(polygon
			(pts
				(arc
					(start 364.499906 -13.5001)
					(mid 369.000024 -8.999982)
					(end 373.499888 -13.5001)
				)
				(arc
					(start 373.499888 -18.50009)
					(mid 369.000024 -22.999954)
					(end 364.499906 -18.50009)
				)
			)
		)
		(polygon
			(pts
				(arc
					(start 371.115336 -17.167606)
					(mid 369.000024 -20.999712)
					(end 366.884712 -17.167606)
				)
				(arc
					(start 366.884712 -17.167606)
					(mid 367.343112 -16.145209)
					(end 367.4999 -15.035784)
				)
				(arc
					(start 367.4999 -13.5001)
					(mid 369.000024 -11.999976)
					(end 370.499894 -13.5001)
				)
				(arc
					(start 370.499894 -15.035784)
					(mid 370.656822 -16.145232)
					(end 371.115336 -17.167606)
				)
			)
		)
	)
	(zone
		(layer "B.Cu")
		(hatch none 0.5)
		(connect_pads
			(clearance 0)
		)
		(min_thickness 0.25)
		(keepout
			(tracks not_allowed)
			(vias allowed)
			(pads allowed)
			(copperpour not_allowed)
			(footprints allowed)
		)
		(placement
			(enabled no)
			(sheetname "")
		)
		(fill
			(thermal_gap 0.5)
			(thermal_bridge_width 0.5)
			(island_removal_mode 0)
		)
		(polygon
			(pts
				(arc
					(start 335.499964 -87.499952)
					(mid 340.000082 -82.999834)
					(end 344.499946 -87.499952)
				)
				(arc
					(start 344.499946 -92.499942)
					(mid 340.000082 -96.999806)
					(end 335.499964 -92.499942)
				)
			)
		)
		(polygon
			(pts
				(arc
					(start 342.115394 -91.167712)
					(mid 340.00015 -95.000208)
					(end 337.884516 -91.167712)
				)
				(arc
					(start 337.884516 -91.167712)
					(mid 338.342981 -90.145324)
					(end 338.499958 -89.03589)
				)
				(arc
					(start 338.499958 -87.499952)
					(mid 340.000082 -85.999828)
					(end 341.499952 -87.499952)
				)
				(arc
					(start 341.499952 -89.03589)
					(mid 341.65688 -90.145338)
					(end 342.115394 -91.167712)
				)
			)
		)
	)
	(zone
		(layer "B.Cu")
		(hatch none 0.5)
		(connect_pads
			(clearance 0)
		)
		(min_thickness 0.25)
		(keepout
			(tracks allowed)
			(vias allowed)
			(pads allowed)
			(copperpour allowed)
			(footprints not_allowed)
		)
		(placement
			(enabled no)
			(sheetname "")
		)
		(fill
			(thermal_gap 0.5)
			(thermal_bridge_width 0.5)
			(island_removal_mode 0)
		)
		(polygon
			(pts
				(arc
					(start 420.99992 -60.099956)
					(mid 424.999912 -64.099948)
					(end 428.999904 -60.099956)
				)
				(arc
					(start 428.999904 -60.099956)
					(mid 424.999912 -56.099964)
					(end 420.99992 -60.099956)
				)
			)
		)
		(polygon
			(pts
				(arc
					(start 422.999916 -60.099956)
					(mid 424.999912 -62.099952)
					(end 426.999908 -60.099956)
				)
				(arc
					(start 426.999908 -60.099956)
					(mid 424.999912 -58.09996)
					(end 422.999916 -60.099956)
				)
			)
		)
	)
	(zone
		(layer "B.Cu")
		(hatch none 0.5)
		(connect_pads
			(clearance 0)
		)
		(min_thickness 0.25)
		(keepout
			(tracks not_allowed)
			(vias allowed)
			(pads allowed)
			(copperpour not_allowed)
			(footprints allowed)
		)
		(placement
			(enabled no)
			(sheetname "")
		)
		(fill
			(thermal_gap 0.5)
			(thermal_bridge_width 0.5)
			(island_removal_mode 0)
		)
		(polygon
			(pts
				(arc
					(start 75.499976 -147.500086)
					(mid 80.000094 -152.000204)
					(end 84.499958 -147.500086)
				)
				(arc
					(start 84.499958 -142.500096)
					(mid 80.000094 -138.000232)
					(end 75.499976 -142.500096)
				)
			)
		)
		(polygon
			(pts
				(arc
					(start 81.499964 -142.500096)
					(mid 80.000094 -141.000226)
					(end 78.49997 -142.500096)
				)
				(arc
					(start 78.49997 -144.03578)
					(mid 78.343042 -145.145228)
					(end 77.884528 -146.167602)
				)
				(arc
					(start 77.884528 -146.167602)
					(mid 80.000162 -150.000313)
					(end 82.115406 -146.167602)
				)
				(arc
					(start 82.115406 -146.167602)
					(mid 81.656941 -145.145214)
					(end 81.499964 -144.03578)
				)
			)
		)
	)
	(zone
		(layer "B.Cu")
		(hatch none 0.5)
		(connect_pads
			(clearance 0)
		)
		(min_thickness 0.25)
		(keepout
			(tracks not_allowed)
			(vias allowed)
			(pads allowed)
			(copperpour not_allowed)
			(footprints allowed)
		)
		(placement
			(enabled no)
			(sheetname "")
		)
		(fill
			(thermal_gap 0.5)
			(thermal_bridge_width 0.5)
			(island_removal_mode 0)
		)
		(polygon
			(pts
				(arc
					(start 245.49989 -16.500094)
					(mid 250.000008 -11.999976)
					(end 254.500126 -16.500094)
				)
				(arc
					(start 254.500126 -21.500084)
					(mid 250.000008 -26.000202)
					(end 245.49989 -21.500084)
				)
			)
		)
		(polygon
			(pts
				(arc
					(start 252.11532 -20.1676)
					(mid 250.000008 -23.999706)
					(end 247.884696 -20.1676)
				)
				(arc
					(start 247.884696 -20.1676)
					(mid 248.343096 -19.145203)
					(end 248.499884 -18.035778)
				)
				(arc
					(start 248.499884 -16.500094)
					(mid 250.000008 -14.99997)
					(end 251.499878 -16.500094)
				)
				(arc
					(start 251.499878 -18.035778)
					(mid 251.656806 -19.145226)
					(end 252.11532 -20.1676)
				)
			)
		)
	)
	(zone
		(layer "B.Cu")
		(hatch none 0.5)
		(connect_pads
			(clearance 0)
		)
		(min_thickness 0.25)
		(keepout
			(tracks allowed)
			(vias allowed)
			(pads allowed)
			(copperpour allowed)
			(footprints not_allowed)
		)
		(placement
			(enabled no)
			(sheetname "")
		)
		(fill
			(thermal_gap 0.5)
			(thermal_bridge_width 0.5)
			(island_removal_mode 0)
		)
		(polygon
			(pts
				(arc
					(start 245.359682 -32.999172)
					(mid 262.353754 -20.42928)
					(end 243.450364 -10.971022)
				)
				(arc
					(start 243.450364 -10.971022)
					(mid 226.456292 -23.540914)
					(end 245.359682 -32.999172)
				)
			)
		)
	)
	(zone
		(layer "B.Cu")
		(hatch none 0.5)
		(connect_pads
			(clearance 0)
		)
		(min_thickness 0.25)
		(keepout
			(tracks not_allowed)
			(vias allowed)
			(pads allowed)
			(copperpour not_allowed)
			(footprints allowed)
		)
		(placement
			(enabled no)
			(sheetname "")
		)
		(fill
			(thermal_gap 0.5)
			(thermal_bridge_width 0.5)
			(island_removal_mode 0)
		)
		(polygon
			(pts
				(arc
					(start 7.500112 -4.500118)
					(mid 8.810811 -1.325426)
					(end 11.979402 0)
				)
				(arc
					(start 12.02055 0)
					(mid 15.189339 -1.325303)
					(end 16.500094 -4.500118)
				)
				(arc
					(start 16.500094 -9.500108)
					(mid 12.00023 -13.999972)
					(end 7.500112 -9.500108)
				)
			)
		)
		(polygon
			(pts
				(arc
					(start 14.115288 -8.167624)
					(mid 11.999976 -11.99973)
					(end 9.884664 -8.167624)
				)
				(arc
					(start 9.884664 -8.167624)
					(mid 10.343129 -7.145236)
					(end 10.500106 -6.035802)
				)
				(arc
					(start 10.500106 -4.500118)
					(mid 12.00023 -2.999994)
					(end 13.5001 -4.500118)
				)
				(arc
					(start 13.5001 -6.035802)
					(mid 13.656953 -7.145208)
					(end 14.115288 -8.167624)
				)
			)
		)
	)
	(zone
		(layer "B.Cu")
		(hatch none 0.5)
		(connect_pads
			(clearance 0)
		)
		(min_thickness 0.25)
		(keepout
			(tracks not_allowed)
			(vias allowed)
			(pads allowed)
			(copperpour not_allowed)
			(footprints allowed)
		)
		(placement
			(enabled no)
			(sheetname "")
		)
		(fill
			(thermal_gap 0.5)
			(thermal_bridge_width 0.5)
			(island_removal_mode 0)
		)
		(polygon
			(pts
				(arc
					(start 434.405024 -4.500118)
					(mid 428.00016 1.904746)
					(end 421.595042 -4.500118)
				)
				(arc
					(start 421.595042 -9.500108)
					(mid 428.00016 -15.905226)
					(end 434.405024 -9.500108)
				)
			)
		)
	)
	(zone
		(layer "B.Cu")
		(hatch none 0.5)
		(connect_pads
			(clearance 0)
		)
		(min_thickness 0.25)
		(keepout
			(tracks not_allowed)
			(vias allowed)
			(pads allowed)
			(copperpour not_allowed)
			(footprints allowed)
		)
		(placement
			(enabled no)
			(sheetname "")
		)
		(fill
			(thermal_gap 0.5)
			(thermal_bridge_width 0.5)
			(island_removal_mode 0)
		)
		(polygon
			(pts
				(arc
					(start 423.500042 -9.500108)
					(mid 428.00016 -14.000226)
					(end 432.500024 -9.500108)
				)
				(arc
					(start 432.500024 -4.500118)
					(mid 428.00016 -0.000254)
					(end 423.500042 -4.500118)
				)
			)
		)
		(polygon
			(pts
				(arc
					(start 429.50003 -4.500118)
					(mid 428.00016 -3.000248)
					(end 426.500036 -4.500118)
				)
				(arc
					(start 426.500036 -6.035802)
					(mid 426.343108 -7.14525)
					(end 425.884594 -8.167624)
				)
				(arc
					(start 425.884594 -8.167624)
					(mid 428.000228 -12.000335)
					(end 430.115472 -8.167624)
				)
				(arc
					(start 430.115472 -8.167624)
					(mid 429.657007 -7.145236)
					(end 429.50003 -6.035802)
				)
			)
		)
	)
	(zone
		(layer "B.Cu")
		(hatch none 0.5)
		(connect_pads
			(clearance 0)
		)
		(min_thickness 0.25)
		(keepout
			(tracks not_allowed)
			(vias allowed)
			(pads allowed)
			(copperpour not_allowed)
			(footprints allowed)
		)
		(placement
			(enabled no)
			(sheetname "")
		)
		(fill
			(thermal_gap 0.5)
			(thermal_bridge_width 0.5)
			(island_removal_mode 0)
		)
		(polygon
			(pts
				(arc
					(start 436.900066 -137.500106)
					(mid 431.8 -132.40004)
					(end 426.699934 -137.500106)
				)
				(arc
					(start 426.699934 -144.500092)
					(mid 431.8 -149.600158)
					(end 436.900066 -144.500092)
				)
			)
		)
	)
	(zone
		(layer "In1.Cu")
		(hatch none 0.5)
		(connect_pads
			(clearance 0)
		)
		(min_thickness 0.25)
		(keepout
			(tracks not_allowed)
			(vias allowed)
			(pads allowed)
			(copperpour not_allowed)
			(footprints allowed)
		)
		(placement
			(enabled no)
			(sheetname "")
		)
		(fill
			(thermal_gap 0.5)
			(thermal_bridge_width 0.5)
			(island_removal_mode 0)
		)
		(polygon
			(pts
				(arc
					(start 37.072062 -165.769798)
					(mid 34.645854 -165.769798)
					(end 37.072062 -165.769798)
				)
			)
		)
	)
	(zone
		(layer "In1.Cu")
		(hatch none 0.5)
		(connect_pads
			(clearance 0)
		)
		(min_thickness 0.25)
		(keepout
			(tracks not_allowed)
			(vias allowed)
			(pads allowed)
			(copperpour not_allowed)
			(footprints allowed)
		)
		(placement
			(enabled no)
			(sheetname "")
		)
		(fill
			(thermal_gap 0.5)
			(thermal_bridge_width 0.5)
			(island_removal_mode 0)
		)
		(polygon
			(pts
				(arc
					(start 391.295382 -159.74441)
					(mid 388.869174 -159.74441)
					(end 391.295382 -159.74441)
				)
			)
		)
	)
	(zone
		(layer "In1.Cu")
		(hatch none 0.5)
		(connect_pads
			(clearance 0)
		)
		(min_thickness 0.25)
		(keepout
			(tracks not_allowed)
			(vias allowed)
			(pads allowed)
			(copperpour not_allowed)
			(footprints allowed)
		)
		(placement
			(enabled no)
			(sheetname "")
		)
		(fill
			(thermal_gap 0.5)
			(thermal_bridge_width 0.5)
			(island_removal_mode 0)
		)
		(polygon
			(pts
				(arc
					(start 371.254782 -159.84601)
					(mid 368.828574 -159.84601)
					(end 371.254782 -159.84601)
				)
			)
		)
	)
	(zone
		(layer "In1.Cu")
		(hatch none 0.5)
		(connect_pads
			(clearance 0)
		)
		(min_thickness 0.25)
		(keepout
			(tracks not_allowed)
			(vias allowed)
			(pads allowed)
			(copperpour not_allowed)
			(footprints allowed)
		)
		(placement
			(enabled no)
			(sheetname "")
		)
		(fill
			(thermal_gap 0.5)
			(thermal_bridge_width 0.5)
			(island_removal_mode 0)
		)
		(polygon
			(pts
				(arc
					(start 400.546824 -153.871422)
					(mid 398.120616 -153.871422)
					(end 400.546824 -153.871422)
				)
			)
		)
	)
	(zone
		(layer "In1.Cu")
		(hatch none 0.5)
		(connect_pads
			(clearance 0)
		)
		(min_thickness 0.25)
		(keepout
			(tracks not_allowed)
			(vias allowed)
			(pads allowed)
			(copperpour not_allowed)
			(footprints allowed)
		)
		(placement
			(enabled no)
			(sheetname "")
		)
		(fill
			(thermal_gap 0.5)
			(thermal_bridge_width 0.5)
			(island_removal_mode 0)
		)
		(polygon
			(pts
				(arc
					(start 377.045982 -157.896814)
					(mid 374.619774 -157.896814)
					(end 377.045982 -157.896814)
				)
			)
		)
	)
	(zone
		(layer "In1.Cu")
		(hatch none 0.5)
		(connect_pads
			(clearance 0)
		)
		(min_thickness 0.25)
		(keepout
			(tracks not_allowed)
			(vias allowed)
			(pads allowed)
			(copperpour not_allowed)
			(footprints allowed)
		)
		(placement
			(enabled no)
			(sheetname "")
		)
		(fill
			(thermal_gap 0.5)
			(thermal_bridge_width 0.5)
			(island_removal_mode 0)
		)
		(polygon
			(pts
				(arc
					(start 400.546824 -157.871414)
					(mid 398.120616 -157.871414)
					(end 400.546824 -157.871414)
				)
			)
		)
	)
	(zone
		(layer "In1.Cu")
		(hatch none 0.5)
		(connect_pads
			(clearance 0)
		)
		(min_thickness 0.25)
		(keepout
			(tracks not_allowed)
			(vias allowed)
			(pads allowed)
			(copperpour not_allowed)
			(footprints allowed)
		)
		(placement
			(enabled no)
			(sheetname "")
		)
		(fill
			(thermal_gap 0.5)
			(thermal_bridge_width 0.5)
			(island_removal_mode 0)
		)
		(polygon
			(pts
				(arc
					(start 56.920892 -157.795214)
					(mid 54.494684 -157.795214)
					(end 56.920892 -157.795214)
				)
			)
		)
	)
	(zone
		(layer "In1.Cu")
		(hatch none 0.5)
		(connect_pads
			(clearance 0)
		)
		(min_thickness 0.25)
		(keepout
			(tracks not_allowed)
			(vias allowed)
			(pads allowed)
			(copperpour not_allowed)
			(footprints allowed)
		)
		(placement
			(enabled no)
			(sheetname "")
		)
		(fill
			(thermal_gap 0.5)
			(thermal_bridge_width 0.5)
			(island_removal_mode 0)
		)
		(polygon
			(pts
				(arc
					(start 56.920892 -159.79521)
					(mid 54.494684 -159.79521)
					(end 56.920892 -159.79521)
				)
			)
		)
	)
	(zone
		(layer "In1.Cu")
		(hatch none 0.5)
		(connect_pads
			(clearance 0)
		)
		(min_thickness 0.25)
		(keepout
			(tracks not_allowed)
			(vias allowed)
			(pads allowed)
			(copperpour not_allowed)
			(footprints allowed)
		)
		(placement
			(enabled no)
			(sheetname "")
		)
		(fill
			(thermal_gap 0.5)
			(thermal_bridge_width 0.5)
			(island_removal_mode 0)
		)
		(polygon
			(pts
				(arc
					(start 37.072062 -153.769822)
					(mid 34.645854 -153.769822)
					(end 37.072062 -153.769822)
				)
			)
		)
	)
	(zone
		(layer "In1.Cu")
		(hatch none 0.5)
		(connect_pads
			(clearance 0)
		)
		(min_thickness 0.25)
		(keepout
			(tracks not_allowed)
			(vias allowed)
			(pads allowed)
			(copperpour not_allowed)
			(footprints allowed)
		)
		(placement
			(enabled no)
			(sheetname "")
		)
		(fill
			(thermal_gap 0.5)
			(thermal_bridge_width 0.5)
			(island_removal_mode 0)
		)
		(polygon
			(pts
				(arc
					(start 365.209582 -157.896814)
					(mid 362.783374 -157.896814)
					(end 365.209582 -157.896814)
				)
			)
		)
	)
	(zone
		(layer "In1.Cu")
		(hatch none 0.5)
		(connect_pads
			(clearance 0)
		)
		(min_thickness 0.25)
		(keepout
			(tracks not_allowed)
			(vias allowed)
			(pads allowed)
			(copperpour not_allowed)
			(footprints allowed)
		)
		(placement
			(enabled no)
			(sheetname "")
		)
		(fill
			(thermal_gap 0.5)
			(thermal_bridge_width 0.5)
			(island_removal_mode 0)
		)
		(polygon
			(pts
				(arc
					(start 400.546824 -163.871402)
					(mid 398.120616 -163.871402)
					(end 400.546824 -163.871402)
				)
			)
		)
	)
	(zone
		(layer "In1.Cu")
		(hatch none 0.5)
		(connect_pads
			(clearance 0)
		)
		(min_thickness 0.25)
		(keepout
			(tracks not_allowed)
			(vias allowed)
			(pads allowed)
			(copperpour not_allowed)
			(footprints allowed)
		)
		(placement
			(enabled no)
			(sheetname "")
		)
		(fill
			(thermal_gap 0.5)
			(thermal_bridge_width 0.5)
			(island_removal_mode 0)
		)
		(polygon
			(pts
				(arc
					(start 37.072062 -159.76981)
					(mid 34.645854 -159.76981)
					(end 37.072062 -159.76981)
				)
			)
		)
	)
	(zone
		(layer "In1.Cu")
		(hatch none 0.5)
		(connect_pads
			(clearance 0)
		)
		(min_thickness 0.25)
		(keepout
			(tracks not_allowed)
			(vias allowed)
			(pads allowed)
			(copperpour not_allowed)
			(footprints allowed)
		)
		(placement
			(enabled no)
			(sheetname "")
		)
		(fill
			(thermal_gap 0.5)
			(thermal_bridge_width 0.5)
			(island_removal_mode 0)
		)
		(polygon
			(pts
				(arc
					(start 37.072062 -155.769818)
					(mid 34.645854 -155.769818)
					(end 37.072062 -155.769818)
				)
			)
		)
	)
	(zone
		(layer "In1.Cu")
		(hatch none 0.5)
		(connect_pads
			(clearance 0)
		)
		(min_thickness 0.25)
		(keepout
			(tracks not_allowed)
			(vias allowed)
			(pads allowed)
			(copperpour not_allowed)
			(footprints allowed)
		)
		(placement
			(enabled no)
			(sheetname "")
		)
		(fill
			(thermal_gap 0.5)
			(thermal_bridge_width 0.5)
			(island_removal_mode 0)
		)
		(polygon
			(pts
				(arc
					(start 37.072062 -167.769794)
					(mid 34.645854 -167.769794)
					(end 37.072062 -167.769794)
				)
			)
		)
	)
	(zone
		(layer "In1.Cu")
		(hatch none 0.5)
		(connect_pads
			(clearance 0)
		)
		(min_thickness 0.25)
		(keepout
			(tracks not_allowed)
			(vias allowed)
			(pads allowed)
			(copperpour not_allowed)
			(footprints allowed)
		)
		(placement
			(enabled no)
			(sheetname "")
		)
		(fill
			(thermal_gap 0.5)
			(thermal_bridge_width 0.5)
			(island_removal_mode 0)
		)
		(polygon
			(pts
				(arc
					(start 377.045982 -159.89681)
					(mid 374.619774 -159.89681)
					(end 377.045982 -159.89681)
				)
			)
		)
	)
	(zone
		(layer "In1.Cu")
		(hatch none 0.5)
		(connect_pads
			(clearance 0)
		)
		(min_thickness 0.25)
		(keepout
			(tracks not_allowed)
			(vias allowed)
			(pads allowed)
			(copperpour not_allowed)
			(footprints allowed)
		)
		(placement
			(enabled no)
			(sheetname "")
		)
		(fill
			(thermal_gap 0.5)
			(thermal_bridge_width 0.5)
			(island_removal_mode 0)
		)
		(polygon
			(pts
				(arc
					(start 65.099692 -157.896814)
					(mid 62.673484 -157.896814)
					(end 65.099692 -157.896814)
				)
			)
		)
	)
	(zone
		(layer "In1.Cu")
		(hatch none 0.5)
		(connect_pads
			(clearance 0)
		)
		(min_thickness 0.25)
		(keepout
			(tracks not_allowed)
			(vias allowed)
			(pads allowed)
			(copperpour not_allowed)
			(footprints allowed)
		)
		(placement
			(enabled no)
			(sheetname "")
		)
		(fill
			(thermal_gap 0.5)
			(thermal_bridge_width 0.5)
			(island_removal_mode 0)
		)
		(polygon
			(pts
				(arc
					(start 37.072062 -157.769814)
					(mid 34.645854 -157.769814)
					(end 37.072062 -157.769814)
				)
			)
		)
	)
	(zone
		(layer "In1.Cu")
		(hatch none 0.5)
		(connect_pads
			(clearance 0)
		)
		(min_thickness 0.25)
		(keepout
			(tracks not_allowed)
			(vias allowed)
			(pads allowed)
			(copperpour not_allowed)
			(footprints allowed)
		)
		(placement
			(enabled no)
			(sheetname "")
		)
		(fill
			(thermal_gap 0.5)
			(thermal_bridge_width 0.5)
			(island_removal_mode 0)
		)
		(polygon
			(pts
				(arc
					(start 400.546824 -159.87141)
					(mid 398.120616 -159.87141)
					(end 400.546824 -159.87141)
				)
			)
		)
	)
	(zone
		(layer "In1.Cu")
		(hatch none 0.5)
		(connect_pads
			(clearance 0)
		)
		(min_thickness 0.25)
		(keepout
			(tracks not_allowed)
			(vias allowed)
			(pads allowed)
			(copperpour not_allowed)
			(footprints allowed)
		)
		(placement
			(enabled no)
			(sheetname "")
		)
		(fill
			(thermal_gap 0.5)
			(thermal_bridge_width 0.5)
			(island_removal_mode 0)
		)
		(polygon
			(pts
				(arc
					(start 65.099692 -159.89681)
					(mid 62.673484 -159.89681)
					(end 65.099692 -159.89681)
				)
			)
		)
	)
	(zone
		(layer "In1.Cu")
		(hatch none 0.5)
		(connect_pads
			(clearance 0)
		)
		(min_thickness 0.25)
		(keepout
			(tracks not_allowed)
			(vias allowed)
			(pads allowed)
			(copperpour not_allowed)
			(footprints allowed)
		)
		(placement
			(enabled no)
			(sheetname "")
		)
		(fill
			(thermal_gap 0.5)
			(thermal_bridge_width 0.5)
			(island_removal_mode 0)
		)
		(polygon
			(pts
				(arc
					(start 37.072062 -161.769806)
					(mid 34.645854 -161.769806)
					(end 37.072062 -161.769806)
				)
			)
		)
	)
	(zone
		(layer "In1.Cu")
		(hatch none 0.5)
		(connect_pads
			(clearance 0)
		)
		(min_thickness 0.25)
		(keepout
			(tracks not_allowed)
			(vias allowed)
			(pads allowed)
			(copperpour not_allowed)
			(footprints allowed)
		)
		(placement
			(enabled no)
			(sheetname "")
		)
		(fill
			(thermal_gap 0.5)
			(thermal_bridge_width 0.5)
			(island_removal_mode 0)
		)
		(polygon
			(pts
				(arc
					(start 400.546824 -165.871398)
					(mid 398.120616 -165.871398)
					(end 400.546824 -165.871398)
				)
			)
		)
	)
	(zone
		(layer "In1.Cu")
		(hatch none 0.5)
		(connect_pads
			(clearance 0)
		)
		(min_thickness 0.25)
		(keepout
			(tracks not_allowed)
			(vias allowed)
			(pads allowed)
			(copperpour not_allowed)
			(footprints allowed)
		)
		(placement
			(enabled no)
			(sheetname "")
		)
		(fill
			(thermal_gap 0.5)
			(thermal_bridge_width 0.5)
			(island_removal_mode 0)
		)
		(polygon
			(pts
				(arc
					(start 71.246492 -157.795214)
					(mid 68.820284 -157.795214)
					(end 71.246492 -157.795214)
				)
			)
		)
	)
	(zone
		(layer "In1.Cu")
		(hatch none 0.5)
		(connect_pads
			(clearance 0)
		)
		(min_thickness 0.25)
		(keepout
			(tracks not_allowed)
			(vias allowed)
			(pads allowed)
			(copperpour not_allowed)
			(footprints allowed)
		)
		(placement
			(enabled no)
			(sheetname "")
		)
		(fill
			(thermal_gap 0.5)
			(thermal_bridge_width 0.5)
			(island_removal_mode 0)
		)
		(polygon
			(pts
				(arc
					(start 471.734388 -75.065382)
					(mid 468.914988 -75.065382)
					(end 471.734388 -75.065382)
				)
			)
		)
	)
	(zone
		(layer "In1.Cu")
		(hatch none 0.5)
		(connect_pads
			(clearance 0)
		)
		(min_thickness 0.25)
		(keepout
			(tracks not_allowed)
			(vias allowed)
			(pads allowed)
			(copperpour not_allowed)
			(footprints allowed)
		)
		(placement
			(enabled no)
			(sheetname "")
		)
		(fill
			(thermal_gap 0.5)
			(thermal_bridge_width 0.5)
			(island_removal_mode 0)
		)
		(polygon
			(pts
				(arc
					(start 50.997104 -157.820614)
					(mid 48.570896 -157.820614)
					(end 50.997104 -157.820614)
				)
			)
		)
	)
	(zone
		(layer "In1.Cu")
		(hatch none 0.5)
		(connect_pads
			(clearance 0)
		)
		(min_thickness 0.25)
		(keepout
			(tracks not_allowed)
			(vias allowed)
			(pads allowed)
			(copperpour not_allowed)
			(footprints allowed)
		)
		(placement
			(enabled no)
			(sheetname "")
		)
		(fill
			(thermal_gap 0.5)
			(thermal_bridge_width 0.5)
			(island_removal_mode 0)
		)
		(polygon
			(pts
				(arc
					(start 400.546824 -167.871394)
					(mid 398.120616 -167.871394)
					(end 400.546824 -167.871394)
				)
			)
		)
	)
	(zone
		(layer "In1.Cu")
		(hatch none 0.5)
		(connect_pads
			(clearance 0)
		)
		(min_thickness 0.25)
		(keepout
			(tracks not_allowed)
			(vias allowed)
			(pads allowed)
			(copperpour not_allowed)
			(footprints allowed)
		)
		(placement
			(enabled no)
			(sheetname "")
		)
		(fill
			(thermal_gap 0.5)
			(thermal_bridge_width 0.5)
			(island_removal_mode 0)
		)
		(polygon
			(pts
				(arc
					(start 77.215492 -159.87141)
					(mid 74.789284 -159.87141)
					(end 77.215492 -159.87141)
				)
			)
		)
	)
	(zone
		(layer "In1.Cu")
		(hatch none 0.5)
		(connect_pads
			(clearance 0)
		)
		(min_thickness 0.25)
		(keepout
			(tracks not_allowed)
			(vias allowed)
			(pads allowed)
			(copperpour not_allowed)
			(footprints allowed)
		)
		(placement
			(enabled no)
			(sheetname "")
		)
		(fill
			(thermal_gap 0.5)
			(thermal_bridge_width 0.5)
			(island_removal_mode 0)
		)
		(polygon
			(pts
				(arc
					(start 385.326382 -159.97301)
					(mid 382.900174 -159.97301)
					(end 385.326382 -159.97301)
				)
			)
		)
	)
	(zone
		(layer "In1.Cu")
		(hatch none 0.5)
		(connect_pads
			(clearance 0)
		)
		(min_thickness 0.25)
		(keepout
			(tracks not_allowed)
			(vias allowed)
			(pads allowed)
			(copperpour not_allowed)
			(footprints allowed)
		)
		(placement
			(enabled no)
			(sheetname "")
		)
		(fill
			(thermal_gap 0.5)
			(thermal_bridge_width 0.5)
			(island_removal_mode 0)
		)
		(polygon
			(pts
				(arc
					(start 371.254782 -157.846014)
					(mid 368.828574 -157.846014)
					(end 371.254782 -157.846014)
				)
			)
		)
	)
	(zone
		(layer "In1.Cu")
		(hatch none 0.5)
		(connect_pads
			(clearance 0)
		)
		(min_thickness 0.25)
		(keepout
			(tracks not_allowed)
			(vias allowed)
			(pads allowed)
			(copperpour not_allowed)
			(footprints allowed)
		)
		(placement
			(enabled no)
			(sheetname "")
		)
		(fill
			(thermal_gap 0.5)
			(thermal_bridge_width 0.5)
			(island_removal_mode 0)
		)
		(polygon
			(pts
				(arc
					(start 385.326382 -157.973014)
					(mid 382.900174 -157.973014)
					(end 385.326382 -157.973014)
				)
			)
		)
	)
	(zone
		(layer "In1.Cu")
		(hatch none 0.5)
		(connect_pads
			(clearance 0)
		)
		(min_thickness 0.25)
		(keepout
			(tracks not_allowed)
			(vias allowed)
			(pads allowed)
			(copperpour not_allowed)
			(footprints allowed)
		)
		(placement
			(enabled no)
			(sheetname "")
		)
		(fill
			(thermal_gap 0.5)
			(thermal_bridge_width 0.5)
			(island_removal_mode 0)
		)
		(polygon
			(pts
				(arc
					(start 400.546824 -155.871418)
					(mid 398.120616 -155.871418)
					(end 400.546824 -155.871418)
				)
			)
		)
	)
	(zone
		(layer "In1.Cu")
		(hatch none 0.5)
		(connect_pads
			(clearance 0)
		)
		(min_thickness 0.25)
		(keepout
			(tracks not_allowed)
			(vias allowed)
			(pads allowed)
			(copperpour not_allowed)
			(footprints allowed)
		)
		(placement
			(enabled no)
			(sheetname "")
		)
		(fill
			(thermal_gap 0.5)
			(thermal_bridge_width 0.5)
			(island_removal_mode 0)
		)
		(polygon
			(pts
				(arc
					(start 77.215492 -157.871414)
					(mid 74.789284 -157.871414)
					(end 77.215492 -157.871414)
				)
			)
		)
	)
	(zone
		(layer "In1.Cu")
		(hatch none 0.5)
		(connect_pads
			(clearance 0)
		)
		(min_thickness 0.25)
		(keepout
			(tracks not_allowed)
			(vias allowed)
			(pads allowed)
			(copperpour not_allowed)
			(footprints allowed)
		)
		(placement
			(enabled no)
			(sheetname "")
		)
		(fill
			(thermal_gap 0.5)
			(thermal_bridge_width 0.5)
			(island_removal_mode 0)
		)
		(polygon
			(pts
				(arc
					(start 37.072062 -163.769802)
					(mid 34.645854 -163.769802)
					(end 37.072062 -163.769802)
				)
			)
		)
	)
	(zone
		(layer "In1.Cu")
		(hatch none 0.5)
		(connect_pads
			(clearance 0)
		)
		(min_thickness 0.25)
		(keepout
			(tracks not_allowed)
			(vias allowed)
			(pads allowed)
			(copperpour not_allowed)
			(footprints allowed)
		)
		(placement
			(enabled no)
			(sheetname "")
		)
		(fill
			(thermal_gap 0.5)
			(thermal_bridge_width 0.5)
			(island_removal_mode 0)
		)
		(polygon
			(pts
				(arc
					(start 400.546824 -161.871406)
					(mid 398.120616 -161.871406)
					(end 400.546824 -161.871406)
				)
			)
		)
	)
	(zone
		(layer "In1.Cu")
		(hatch none 0.5)
		(connect_pads
			(clearance 0)
		)
		(min_thickness 0.25)
		(keepout
			(tracks not_allowed)
			(vias allowed)
			(pads allowed)
			(copperpour not_allowed)
			(footprints allowed)
		)
		(placement
			(enabled no)
			(sheetname "")
		)
		(fill
			(thermal_gap 0.5)
			(thermal_bridge_width 0.5)
			(island_removal_mode 0)
		)
		(polygon
			(pts
				(arc
					(start 50.997104 -159.82061)
					(mid 48.570896 -159.82061)
					(end 50.997104 -159.82061)
				)
			)
		)
	)
	(zone
		(layer "In1.Cu")
		(hatch none 0.5)
		(connect_pads
			(clearance 0)
		)
		(min_thickness 0.25)
		(keepout
			(tracks not_allowed)
			(vias allowed)
			(pads allowed)
			(copperpour not_allowed)
			(footprints allowed)
		)
		(placement
			(enabled no)
			(sheetname "")
		)
		(fill
			(thermal_gap 0.5)
			(thermal_bridge_width 0.5)
			(island_removal_mode 0)
		)
		(polygon
			(pts
				(arc
					(start 365.209582 -159.89681)
					(mid 362.783374 -159.89681)
					(end 365.209582 -159.89681)
				)
			)
		)
	)
	(zone
		(layer "In1.Cu")
		(hatch none 0.5)
		(connect_pads
			(clearance 0)
		)
		(min_thickness 0.25)
		(keepout
			(tracks not_allowed)
			(vias allowed)
			(pads allowed)
			(copperpour not_allowed)
			(footprints allowed)
		)
		(placement
			(enabled no)
			(sheetname "")
		)
		(fill
			(thermal_gap 0.5)
			(thermal_bridge_width 0.5)
			(island_removal_mode 0)
		)
		(polygon
			(pts
				(arc
					(start 471.734388 -72.525382)
					(mid 468.914988 -72.525382)
					(end 471.734388 -72.525382)
				)
			)
		)
	)
	(zone
		(layer "In1.Cu")
		(hatch none 0.5)
		(connect_pads
			(clearance 0)
		)
		(min_thickness 0.25)
		(keepout
			(tracks not_allowed)
			(vias allowed)
			(pads allowed)
			(copperpour not_allowed)
			(footprints allowed)
		)
		(placement
			(enabled no)
			(sheetname "")
		)
		(fill
			(thermal_gap 0.5)
			(thermal_bridge_width 0.5)
			(island_removal_mode 0)
		)
		(polygon
			(pts
				(arc
					(start 471.734388 -69.985382)
					(mid 468.914988 -69.985382)
					(end 471.734388 -69.985382)
				)
			)
		)
	)
	(zone
		(layer "In1.Cu")
		(hatch none 0.5)
		(connect_pads
			(clearance 0)
		)
		(min_thickness 0.25)
		(keepout
			(tracks not_allowed)
			(vias allowed)
			(pads allowed)
			(copperpour not_allowed)
			(footprints allowed)
		)
		(placement
			(enabled no)
			(sheetname "")
		)
		(fill
			(thermal_gap 0.5)
			(thermal_bridge_width 0.5)
			(island_removal_mode 0)
		)
		(polygon
			(pts
				(arc
					(start 391.295382 -157.744414)
					(mid 388.869174 -157.744414)
					(end 391.295382 -157.744414)
				)
			)
		)
	)
	(zone
		(layer "In1.Cu")
		(hatch none 0.5)
		(connect_pads
			(clearance 0)
		)
		(min_thickness 0.25)
		(keepout
			(tracks not_allowed)
			(vias allowed)
			(pads allowed)
			(copperpour not_allowed)
			(footprints allowed)
		)
		(placement
			(enabled no)
			(sheetname "")
		)
		(fill
			(thermal_gap 0.5)
			(thermal_bridge_width 0.5)
			(island_removal_mode 0)
		)
		(polygon
			(pts
				(arc
					(start 71.246492 -159.79521)
					(mid 68.820284 -159.79521)
					(end 71.246492 -159.79521)
				)
			)
		)
	)
	(zone
		(layers "In1.Cu" "In3.Cu" "In4.Cu" "In5.Cu" "In6.Cu" "In8.Cu")
		(hatch none 0.5)
		(connect_pads
			(clearance 0)
		)
		(min_thickness 0.25)
		(keepout
			(tracks not_allowed)
			(vias allowed)
			(pads allowed)
			(copperpour not_allowed)
			(footprints allowed)
		)
		(placement
			(enabled no)
			(sheetname "")
		)
		(fill yes
			(thermal_gap 0.5)
			(thermal_bridge_width 0.5)
			(island_removal_mode 0)
		)
		(polygon
			(pts
				(arc
					(start 210.20913 -51.049936)
					(mid 207.411066 -51.049936)
					(end 210.20913 -51.049936)
				)
			)
		)
	)
	(zone
		(layers "In1.Cu" "In3.Cu" "In4.Cu" "In5.Cu" "In6.Cu" "In8.Cu")
		(hatch none 0.5)
		(connect_pads
			(clearance 0)
		)
		(min_thickness 0.25)
		(keepout
			(tracks not_allowed)
			(vias allowed)
			(pads allowed)
			(copperpour not_allowed)
			(footprints allowed)
		)
		(placement
			(enabled no)
			(sheetname "")
		)
		(fill yes
			(thermal_gap 0.5)
			(thermal_bridge_width 0.5)
			(island_removal_mode 0)
		)
		(polygon
			(pts
				(arc
					(start 161.464244 -86.084918)
					(mid 159.686244 -86.084918)
					(end 161.464244 -86.084918)
				)
			)
		)
	)
	(zone
		(layers "In1.Cu" "In3.Cu" "In4.Cu" "In5.Cu" "In6.Cu" "In8.Cu")
		(hatch none 0.5)
		(connect_pads
			(clearance 0)
		)
		(min_thickness 0.25)
		(keepout
			(tracks not_allowed)
			(vias allowed)
			(pads allowed)
			(copperpour not_allowed)
			(footprints allowed)
		)
		(placement
			(enabled no)
			(sheetname "")
		)
		(fill yes
			(thermal_gap 0.5)
			(thermal_bridge_width 0.5)
			(island_removal_mode 0)
		)
		(polygon
			(pts
				(arc
					(start 261.1374 -46.99)
					(mid 259.3594 -46.99)
					(end 261.1374 -46.99)
				)
			)
		)
	)
	(zone
		(layers "In1.Cu" "In3.Cu" "In4.Cu" "In5.Cu" "In6.Cu" "In8.Cu")
		(hatch none 0.5)
		(connect_pads
			(clearance 0)
		)
		(min_thickness 0.25)
		(keepout
			(tracks not_allowed)
			(vias allowed)
			(pads allowed)
			(copperpour not_allowed)
			(footprints allowed)
		)
		(placement
			(enabled no)
			(sheetname "")
		)
		(fill yes
			(thermal_gap 0.5)
			(thermal_bridge_width 0.5)
			(island_removal_mode 0)
		)
		(polygon
			(pts
				(arc
					(start 263.61644 -64.516)
					(mid 261.83844 -64.516)
					(end 263.61644 -64.516)
				)
			)
		)
	)
	(zone
		(layers "In1.Cu" "In3.Cu" "In4.Cu" "In5.Cu" "In6.Cu" "In8.Cu")
		(hatch none 0.5)
		(connect_pads
			(clearance 0)
		)
		(min_thickness 0.25)
		(keepout
			(tracks not_allowed)
			(vias allowed)
			(pads allowed)
			(copperpour not_allowed)
			(footprints allowed)
		)
		(placement
			(enabled no)
			(sheetname "")
		)
		(fill yes
			(thermal_gap 0.5)
			(thermal_bridge_width 0.5)
			(island_removal_mode 0)
		)
		(polygon
			(pts
				(arc
					(start 183.104536 -69.4436)
					(mid 181.326536 -69.4436)
					(end 183.104536 -69.4436)
				)
			)
		)
	)
	(zone
		(layers "In1.Cu" "In3.Cu" "In4.Cu" "In5.Cu" "In6.Cu" "In8.Cu")
		(hatch none 0.5)
		(connect_pads
			(clearance 0)
		)
		(min_thickness 0.25)
		(keepout
			(tracks not_allowed)
			(vias allowed)
			(pads allowed)
			(copperpour not_allowed)
			(footprints allowed)
		)
		(placement
			(enabled no)
			(sheetname "")
		)
		(fill yes
			(thermal_gap 0.5)
			(thermal_bridge_width 0.5)
			(island_removal_mode 0)
		)
		(polygon
			(pts
				(arc
					(start 181.250336 -66.3194)
					(mid 179.472336 -66.3194)
					(end 181.250336 -66.3194)
				)
			)
		)
	)
	(zone
		(layers "In1.Cu" "In3.Cu" "In4.Cu" "In5.Cu" "In6.Cu" "In8.Cu")
		(hatch none 0.5)
		(connect_pads
			(clearance 0)
		)
		(min_thickness 0.25)
		(keepout
			(tracks not_allowed)
			(vias allowed)
			(pads allowed)
			(copperpour not_allowed)
			(footprints allowed)
		)
		(placement
			(enabled no)
			(sheetname "")
		)
		(fill yes
			(thermal_gap 0.5)
			(thermal_bridge_width 0.5)
			(island_removal_mode 0)
		)
		(polygon
			(pts
				(arc
					(start 269.0114 -68.199)
					(mid 267.2334 -68.199)
					(end 269.0114 -68.199)
				)
			)
		)
	)
	(zone
		(layers "In1.Cu" "In3.Cu" "In4.Cu" "In5.Cu" "In6.Cu" "In8.Cu")
		(hatch none 0.5)
		(connect_pads
			(clearance 0)
		)
		(min_thickness 0.25)
		(keepout
			(tracks not_allowed)
			(vias allowed)
			(pads allowed)
			(copperpour not_allowed)
			(footprints allowed)
		)
		(placement
			(enabled no)
			(sheetname "")
		)
		(fill yes
			(thermal_gap 0.5)
			(thermal_bridge_width 0.5)
			(island_removal_mode 0)
		)
		(polygon
			(pts
				(arc
					(start 109.671358 -42.432224)
					(mid 107.893358 -42.432224)
					(end 109.671358 -42.432224)
				)
			)
		)
	)
	(zone
		(layers "In1.Cu" "In3.Cu" "In4.Cu" "In5.Cu" "In6.Cu" "In8.Cu")
		(hatch none 0.5)
		(connect_pads
			(clearance 0)
		)
		(min_thickness 0.25)
		(keepout
			(tracks not_allowed)
			(vias allowed)
			(pads allowed)
			(copperpour not_allowed)
			(footprints allowed)
		)
		(placement
			(enabled no)
			(sheetname "")
		)
		(fill yes
			(thermal_gap 0.5)
			(thermal_bridge_width 0.5)
			(island_removal_mode 0)
		)
		(polygon
			(pts
				(arc
					(start 268.1478 -73.8886)
					(mid 266.3698 -73.8886)
					(end 268.1478 -73.8886)
				)
			)
		)
	)
	(zone
		(layers "In1.Cu" "In3.Cu" "In4.Cu" "In5.Cu" "In6.Cu" "In8.Cu")
		(hatch none 0.5)
		(connect_pads
			(clearance 0)
		)
		(min_thickness 0.25)
		(keepout
			(tracks not_allowed)
			(vias allowed)
			(pads allowed)
			(copperpour not_allowed)
			(footprints allowed)
		)
		(placement
			(enabled no)
			(sheetname "")
		)
		(fill yes
			(thermal_gap 0.5)
			(thermal_bridge_width 0.5)
			(island_removal_mode 0)
		)
		(polygon
			(pts
				(arc
					(start 180.386736 -69.1896)
					(mid 178.608736 -69.1896)
					(end 180.386736 -69.1896)
				)
			)
		)
	)
	(zone
		(layers "In1.Cu" "In3.Cu" "In4.Cu" "In5.Cu" "In6.Cu" "In8.Cu")
		(hatch none 0.5)
		(connect_pads
			(clearance 0)
		)
		(min_thickness 0.25)
		(keepout
			(tracks not_allowed)
			(vias allowed)
			(pads allowed)
			(copperpour not_allowed)
			(footprints allowed)
		)
		(placement
			(enabled no)
			(sheetname "")
		)
		(fill yes
			(thermal_gap 0.5)
			(thermal_bridge_width 0.5)
			(island_removal_mode 0)
		)
		(polygon
			(pts
				(arc
					(start 183.637936 -70.86092)
					(mid 181.859936 -70.86092)
					(end 183.637936 -70.86092)
				)
			)
		)
	)
	(zone
		(layers "In1.Cu" "In3.Cu" "In4.Cu" "In5.Cu" "In6.Cu" "In8.Cu")
		(hatch none 0.5)
		(connect_pads
			(clearance 0)
		)
		(min_thickness 0.25)
		(keepout
			(tracks not_allowed)
			(vias allowed)
			(pads allowed)
			(copperpour not_allowed)
			(footprints allowed)
		)
		(placement
			(enabled no)
			(sheetname "")
		)
		(fill yes
			(thermal_gap 0.5)
			(thermal_bridge_width 0.5)
			(island_removal_mode 0)
		)
		(polygon
			(pts
				(arc
					(start 339.387434 -48.423576)
					(mid 337.609434 -48.423576)
					(end 339.387434 -48.423576)
				)
			)
		)
	)
	(zone
		(layers "In1.Cu" "In3.Cu" "In4.Cu" "In5.Cu" "In6.Cu" "In8.Cu")
		(hatch none 0.5)
		(connect_pads
			(clearance 0)
		)
		(min_thickness 0.25)
		(keepout
			(tracks not_allowed)
			(vias allowed)
			(pads allowed)
			(copperpour not_allowed)
			(footprints allowed)
		)
		(placement
			(enabled no)
			(sheetname "")
		)
		(fill yes
			(thermal_gap 0.5)
			(thermal_bridge_width 0.5)
			(island_removal_mode 0)
		)
		(polygon
			(pts
				(arc
					(start 112.1664 -43.18)
					(mid 110.3884 -43.18)
					(end 112.1664 -43.18)
				)
			)
		)
	)
	(zone
		(layers "In1.Cu" "In3.Cu" "In4.Cu" "In5.Cu" "In6.Cu" "In8.Cu")
		(hatch none 0.5)
		(connect_pads
			(clearance 0)
		)
		(min_thickness 0.25)
		(keepout
			(tracks not_allowed)
			(vias allowed)
			(pads allowed)
			(copperpour not_allowed)
			(footprints allowed)
		)
		(placement
			(enabled no)
			(sheetname "")
		)
		(fill yes
			(thermal_gap 0.5)
			(thermal_bridge_width 0.5)
			(island_removal_mode 0)
		)
		(polygon
			(pts
				(arc
					(start 110.263432 -53.692806)
					(mid 108.485432 -53.692806)
					(end 110.263432 -53.692806)
				)
			)
		)
	)
	(zone
		(layers "In1.Cu" "In3.Cu" "In4.Cu" "In5.Cu" "In6.Cu" "In8.Cu")
		(hatch none 0.5)
		(connect_pads
			(clearance 0)
		)
		(min_thickness 0.25)
		(keepout
			(tracks not_allowed)
			(vias allowed)
			(pads allowed)
			(copperpour not_allowed)
			(footprints allowed)
		)
		(placement
			(enabled no)
			(sheetname "")
		)
		(fill yes
			(thermal_gap 0.5)
			(thermal_bridge_width 0.5)
			(island_removal_mode 0)
		)
		(polygon
			(pts
				(arc
					(start 337.2104 -38.227)
					(mid 335.4324 -38.227)
					(end 337.2104 -38.227)
				)
			)
		)
	)
	(zone
		(layers "In1.Cu" "In3.Cu" "In4.Cu" "In5.Cu" "In6.Cu" "In8.Cu")
		(hatch none 0.5)
		(connect_pads
			(clearance 0)
		)
		(min_thickness 0.25)
		(keepout
			(tracks not_allowed)
			(vias allowed)
			(pads allowed)
			(copperpour not_allowed)
			(footprints allowed)
		)
		(placement
			(enabled no)
			(sheetname "")
		)
		(fill yes
			(thermal_gap 0.5)
			(thermal_bridge_width 0.5)
			(island_removal_mode 0)
		)
		(polygon
			(pts
				(arc
					(start 298.573444 -68.35394)
					(mid 296.795444 -68.35394)
					(end 298.573444 -68.35394)
				)
			)
		)
	)
	(zone
		(layers "In1.Cu" "In3.Cu" "In4.Cu" "In5.Cu" "In6.Cu" "In8.Cu")
		(hatch none 0.5)
		(connect_pads
			(clearance 0)
		)
		(min_thickness 0.25)
		(keepout
			(tracks not_allowed)
			(vias allowed)
			(pads allowed)
			(copperpour not_allowed)
			(footprints allowed)
		)
		(placement
			(enabled no)
			(sheetname "")
		)
		(fill yes
			(thermal_gap 0.5)
			(thermal_bridge_width 0.5)
			(island_removal_mode 0)
		)
		(polygon
			(pts
				(arc
					(start 337.2104 -49.5046)
					(mid 335.4324 -49.5046)
					(end 337.2104 -49.5046)
				)
			)
		)
	)
	(zone
		(layers "In1.Cu" "In3.Cu" "In4.Cu" "In5.Cu" "In6.Cu" "In8.Cu")
		(hatch none 0.5)
		(connect_pads
			(clearance 0)
		)
		(min_thickness 0.25)
		(keepout
			(tracks not_allowed)
			(vias allowed)
			(pads allowed)
			(copperpour not_allowed)
			(footprints allowed)
		)
		(placement
			(enabled no)
			(sheetname "")
		)
		(fill yes
			(thermal_gap 0.5)
			(thermal_bridge_width 0.5)
			(island_removal_mode 0)
		)
		(polygon
			(pts
				(arc
					(start 159.258 -96.266)
					(mid 157.48 -96.266)
					(end 159.258 -96.266)
				)
			)
		)
	)
	(zone
		(layers "In1.Cu" "In3.Cu" "In4.Cu" "In5.Cu" "In6.Cu" "In8.Cu")
		(hatch none 0.5)
		(connect_pads
			(clearance 0)
		)
		(min_thickness 0.25)
		(keepout
			(tracks not_allowed)
			(vias allowed)
			(pads allowed)
			(copperpour not_allowed)
			(footprints allowed)
		)
		(placement
			(enabled no)
			(sheetname "")
		)
		(fill yes
			(thermal_gap 0.5)
			(thermal_bridge_width 0.5)
			(island_removal_mode 0)
		)
		(polygon
			(pts
				(arc
					(start 112.1664 -54.483)
					(mid 110.3884 -54.483)
					(end 112.1664 -54.483)
				)
			)
		)
	)
	(zone
		(layers "In1.Cu" "In3.Cu" "In4.Cu" "In5.Cu" "In6.Cu" "In8.Cu")
		(hatch none 0.5)
		(connect_pads
			(clearance 0)
		)
		(min_thickness 0.25)
		(keepout
			(tracks not_allowed)
			(vias allowed)
			(pads allowed)
			(copperpour not_allowed)
			(footprints allowed)
		)
		(placement
			(enabled no)
			(sheetname "")
		)
		(fill yes
			(thermal_gap 0.5)
			(thermal_bridge_width 0.5)
			(island_removal_mode 0)
		)
		(polygon
			(pts
				(arc
					(start 266.2936 -70.7644)
					(mid 264.5156 -70.7644)
					(end 266.2936 -70.7644)
				)
			)
		)
	)
	(zone
		(layers "In1.Cu" "In3.Cu" "In4.Cu" "In5.Cu" "In6.Cu" "In8.Cu")
		(hatch none 0.5)
		(connect_pads
			(clearance 0)
		)
		(min_thickness 0.25)
		(keepout
			(tracks not_allowed)
			(vias allowed)
			(pads allowed)
			(copperpour not_allowed)
			(footprints allowed)
		)
		(placement
			(enabled no)
			(sheetname "")
		)
		(fill yes
			(thermal_gap 0.5)
			(thermal_bridge_width 0.5)
			(island_removal_mode 0)
		)
		(polygon
			(pts
				(arc
					(start 269.0114 -71.0184)
					(mid 267.2334 -71.0184)
					(end 269.0114 -71.0184)
				)
			)
		)
	)
	(zone
		(layers "In1.Cu" "In3.Cu" "In4.Cu" "In5.Cu" "In6.Cu" "In8.Cu")
		(hatch none 0.5)
		(connect_pads
			(clearance 0)
		)
		(min_thickness 0.25)
		(keepout
			(tracks not_allowed)
			(vias allowed)
			(pads allowed)
			(copperpour not_allowed)
			(footprints allowed)
		)
		(placement
			(enabled no)
			(sheetname "")
		)
		(fill yes
			(thermal_gap 0.5)
			(thermal_bridge_width 0.5)
			(island_removal_mode 0)
		)
		(polygon
			(pts
				(arc
					(start 179.76596 -46.99)
					(mid 177.98796 -46.99)
					(end 179.76596 -46.99)
				)
			)
		)
	)
	(zone
		(layers "In1.Cu" "In3.Cu" "In4.Cu" "In5.Cu" "In6.Cu" "In8.Cu")
		(hatch none 0.5)
		(connect_pads
			(clearance 0)
		)
		(min_thickness 0.25)
		(keepout
			(tracks not_allowed)
			(vias allowed)
			(pads allowed)
			(copperpour not_allowed)
			(footprints allowed)
		)
		(placement
			(enabled no)
			(sheetname "")
		)
		(fill yes
			(thermal_gap 0.5)
			(thermal_bridge_width 0.5)
			(island_removal_mode 0)
		)
		(polygon
			(pts
				(arc
					(start 185.039 -74.295)
					(mid 183.261 -74.295)
					(end 185.039 -74.295)
				)
			)
		)
	)
	(zone
		(layers "In1.Cu" "In3.Cu" "In4.Cu" "In5.Cu" "In6.Cu" "In8.Cu")
		(hatch none 0.5)
		(connect_pads
			(clearance 0)
		)
		(min_thickness 0.25)
		(keepout
			(tracks not_allowed)
			(vias allowed)
			(pads allowed)
			(copperpour not_allowed)
			(footprints allowed)
		)
		(placement
			(enabled no)
			(sheetname "")
		)
		(fill yes
			(thermal_gap 0.5)
			(thermal_bridge_width 0.5)
			(island_removal_mode 0)
		)
		(polygon
			(pts
				(arc
					(start 339.76056 -37.247068)
					(mid 337.98256 -37.247068)
					(end 339.76056 -37.247068)
				)
			)
		)
	)
	(zone
		(layers "In1.Cu" "In3.Cu" "In4.Cu" "In5.Cu" "In6.Cu" "In8.Cu")
		(hatch none 0.5)
		(connect_pads
			(clearance 0)
		)
		(min_thickness 0.25)
		(keepout
			(tracks not_allowed)
			(vias allowed)
			(pads allowed)
			(copperpour not_allowed)
			(footprints allowed)
		)
		(placement
			(enabled no)
			(sheetname "")
		)
		(fill yes
			(thermal_gap 0.5)
			(thermal_bridge_width 0.5)
			(island_removal_mode 0)
		)
		(polygon
			(pts
				(arc
					(start 305.952398 -81.003648)
					(mid 304.174398 -81.003648)
					(end 305.952398 -81.003648)
				)
			)
		)
	)
	(zone
		(layers "In1.Cu" "In3.Cu" "In4.Cu" "In5.Cu" "In6.Cu" "In8.Cu")
		(hatch none 0.5)
		(connect_pads
			(clearance 0)
		)
		(min_thickness 0.25)
		(keepout
			(tracks not_allowed)
			(vias allowed)
			(pads allowed)
			(copperpour not_allowed)
			(footprints allowed)
		)
		(placement
			(enabled no)
			(sheetname "")
		)
		(fill yes
			(thermal_gap 0.5)
			(thermal_bridge_width 0.5)
			(island_removal_mode 0)
		)
		(polygon
			(pts
				(arc
					(start 298.573444 -69.854064)
					(mid 296.795444 -69.854064)
					(end 298.573444 -69.854064)
				)
			)
		)
	)
	(zone
		(layers "In1.Cu" "In3.Cu" "In4.Cu" "In5.Cu" "In6.Cu" "In8.Cu")
		(hatch none 0.5)
		(connect_pads
			(clearance 0)
		)
		(min_thickness 0.25)
		(keepout
			(tracks not_allowed)
			(vias allowed)
			(pads allowed)
			(copperpour not_allowed)
			(footprints allowed)
		)
		(placement
			(enabled no)
			(sheetname "")
		)
		(fill yes
			(thermal_gap 0.5)
			(thermal_bridge_width 0.5)
			(island_removal_mode 0)
		)
		(polygon
			(pts
				(arc
					(start 179.446936 -72.009)
					(mid 177.668936 -72.009)
					(end 179.446936 -72.009)
				)
			)
		)
	)
	(zone
		(layers "In1.Cu" "In3.Cu" "In4.Cu" "In5.Cu" "In6.Cu" "In8.Cu")
		(hatch none 0.5)
		(connect_pads
			(clearance 0)
		)
		(min_thickness 0.25)
		(keepout
			(tracks not_allowed)
			(vias allowed)
			(pads allowed)
			(copperpour not_allowed)
			(footprints allowed)
		)
		(placement
			(enabled no)
			(sheetname "")
		)
		(fill yes
			(thermal_gap 0.5)
			(thermal_bridge_width 0.5)
			(island_removal_mode 0)
		)
		(polygon
			(pts
				(arc
					(start 304.959258 -79.823056)
					(mid 303.181258 -79.823056)
					(end 304.959258 -79.823056)
				)
			)
		)
	)
	(zone
		(layers "In1.Cu" "In3.Cu" "In4.Cu" "In5.Cu" "In6.Cu" "In8.Cu")
		(hatch none 0.5)
		(connect_pads
			(clearance 0)
		)
		(min_thickness 0.25)
		(keepout
			(tracks not_allowed)
			(vias allowed)
			(pads allowed)
			(copperpour not_allowed)
			(footprints allowed)
		)
		(placement
			(enabled no)
			(sheetname "")
		)
		(fill yes
			(thermal_gap 0.5)
			(thermal_bridge_width 0.5)
			(island_removal_mode 0)
		)
		(polygon
			(pts
				(arc
					(start 240.20907 -51.049936)
					(mid 237.411006 -51.049936)
					(end 240.20907 -51.049936)
				)
			)
		)
	)
	(zone
		(layers "In1.Cu" "In3.Cu" "In4.Cu" "In5.Cu" "In6.Cu" "In8.Cu")
		(hatch none 0.5)
		(connect_pads
			(clearance 0)
		)
		(min_thickness 0.25)
		(keepout
			(tracks not_allowed)
			(vias allowed)
			(pads allowed)
			(copperpour not_allowed)
			(footprints allowed)
		)
		(placement
			(enabled no)
			(sheetname "")
		)
		(fill yes
			(thermal_gap 0.5)
			(thermal_bridge_width 0.5)
			(island_removal_mode 0)
		)
		(polygon
			(pts
				(arc
					(start 179.446936 -69.1896)
					(mid 177.668936 -69.1896)
					(end 179.446936 -69.1896)
				)
			)
		)
	)
	(zone
		(layers "In1.Cu" "In3.Cu" "In4.Cu" "In5.Cu" "In6.Cu" "In8.Cu")
		(hatch none 0.5)
		(connect_pads
			(clearance 0)
		)
		(min_thickness 0.25)
		(keepout
			(tracks not_allowed)
			(vias allowed)
			(pads allowed)
			(copperpour not_allowed)
			(footprints allowed)
		)
		(placement
			(enabled no)
			(sheetname "")
		)
		(fill yes
			(thermal_gap 0.5)
			(thermal_bridge_width 0.5)
			(island_removal_mode 0)
		)
		(polygon
			(pts
				(arc
					(start 268.9352 -73.8886)
					(mid 267.1572 -73.8886)
					(end 268.9352 -73.8886)
				)
			)
		)
	)
	(zone
		(layers "In1.Cu" "In3.Cu" "In4.Cu" "In5.Cu" "In6.Cu" "In8.Cu")
		(hatch none 0.5)
		(connect_pads
			(clearance 0)
		)
		(min_thickness 0.25)
		(keepout
			(tracks not_allowed)
			(vias allowed)
			(pads allowed)
			(copperpour not_allowed)
			(footprints allowed)
		)
		(placement
			(enabled no)
			(sheetname "")
		)
		(fill yes
			(thermal_gap 0.5)
			(thermal_bridge_width 0.5)
			(island_removal_mode 0)
		)
		(polygon
			(pts
				(arc
					(start 180.386736 -72.009)
					(mid 178.608736 -72.009)
					(end 180.386736 -72.009)
				)
			)
		)
	)
	(zone
		(layers "In1.Cu" "In3.Cu" "In4.Cu" "In5.Cu" "In6.Cu" "In8.Cu")
		(hatch none 0.5)
		(connect_pads
			(clearance 0)
		)
		(min_thickness 0.25)
		(keepout
			(tracks not_allowed)
			(vias allowed)
			(pads allowed)
			(copperpour not_allowed)
			(footprints allowed)
		)
		(placement
			(enabled no)
			(sheetname "")
		)
		(fill yes
			(thermal_gap 0.5)
			(thermal_bridge_width 0.5)
			(island_removal_mode 0)
		)
		(polygon
			(pts
				(arc
					(start 180.462936 -66.3194)
					(mid 178.684936 -66.3194)
					(end 180.462936 -66.3194)
				)
			)
		)
	)
	(zone
		(layers "In1.Cu" "In3.Cu" "In4.Cu" "In6.Cu" "In8.Cu")
		(hatch none 0.5)
		(connect_pads
			(clearance 0)
		)
		(min_thickness 0.25)
		(keepout
			(tracks not_allowed)
			(vias allowed)
			(pads allowed)
			(copperpour not_allowed)
			(footprints allowed)
		)
		(placement
			(enabled no)
			(sheetname "")
		)
		(fill yes
			(thermal_gap 0.5)
			(thermal_bridge_width 0.5)
			(island_removal_mode 0)
		)
		(polygon
			(pts
				(arc
					(start 336.256884 -39.8018)
					(mid 334.478884 -39.8018)
					(end 336.256884 -39.8018)
				)
			)
		)
	)
	(zone
		(layers "In1.Cu" "In3.Cu" "In4.Cu" "In6.Cu" "In8.Cu")
		(hatch none 0.5)
		(connect_pads
			(clearance 0)
		)
		(min_thickness 0.25)
		(keepout
			(tracks not_allowed)
			(vias allowed)
			(pads allowed)
			(copperpour not_allowed)
			(footprints allowed)
		)
		(placement
			(enabled no)
			(sheetname "")
		)
		(fill yes
			(thermal_gap 0.5)
			(thermal_bridge_width 0.5)
			(island_removal_mode 0)
		)
		(polygon
			(pts
				(arc
					(start 276.9362 -86.233)
					(mid 275.1582 -86.233)
					(end 276.9362 -86.233)
				)
			)
		)
	)
	(zone
		(layers "In1.Cu" "In3.Cu" "In4.Cu" "In6.Cu" "In8.Cu")
		(hatch none 0.5)
		(connect_pads
			(clearance 0)
		)
		(min_thickness 0.25)
		(keepout
			(tracks not_allowed)
			(vias allowed)
			(pads allowed)
			(copperpour not_allowed)
			(footprints allowed)
		)
		(placement
			(enabled no)
			(sheetname "")
		)
		(fill yes
			(thermal_gap 0.5)
			(thermal_bridge_width 0.5)
			(island_removal_mode 0)
		)
		(polygon
			(pts
				(arc
					(start 113.141252 -22.2758)
					(mid 111.363252 -22.2758)
					(end 113.141252 -22.2758)
				)
			)
		)
	)
	(zone
		(layers "In1.Cu" "In3.Cu" "In4.Cu" "In6.Cu" "In8.Cu")
		(hatch none 0.5)
		(connect_pads
			(clearance 0)
		)
		(min_thickness 0.25)
		(keepout
			(tracks not_allowed)
			(vias allowed)
			(pads allowed)
			(copperpour not_allowed)
			(footprints allowed)
		)
		(placement
			(enabled no)
			(sheetname "")
		)
		(fill yes
			(thermal_gap 0.5)
			(thermal_bridge_width 0.5)
			(island_removal_mode 0)
		)
		(polygon
			(pts
				(arc
					(start 273.6342 -86.233)
					(mid 271.8562 -86.233)
					(end 273.6342 -86.233)
				)
			)
		)
	)
	(zone
		(layers "In1.Cu" "In3.Cu" "In4.Cu" "In6.Cu" "In8.Cu")
		(hatch none 0.5)
		(connect_pads
			(clearance 0)
		)
		(min_thickness 0.25)
		(keepout
			(tracks not_allowed)
			(vias allowed)
			(pads allowed)
			(copperpour not_allowed)
			(footprints allowed)
		)
		(placement
			(enabled no)
			(sheetname "")
		)
		(fill yes
			(thermal_gap 0.5)
			(thermal_bridge_width 0.5)
			(island_removal_mode 0)
		)
		(polygon
			(pts
				(arc
					(start 113.141252 -56.1086)
					(mid 111.363252 -56.1086)
					(end 113.141252 -56.1086)
				)
			)
		)
	)
	(zone
		(layers "In1.Cu" "In3.Cu" "In4.Cu" "In6.Cu" "In8.Cu")
		(hatch none 0.5)
		(connect_pads
			(clearance 0)
		)
		(min_thickness 0.25)
		(keepout
			(tracks not_allowed)
			(vias allowed)
			(pads allowed)
			(copperpour not_allowed)
			(footprints allowed)
		)
		(placement
			(enabled no)
			(sheetname "")
		)
		(fill yes
			(thermal_gap 0.5)
			(thermal_bridge_width 0.5)
			(island_removal_mode 0)
		)
		(polygon
			(pts
				(arc
					(start 113.141252 -78.6638)
					(mid 111.363252 -78.6638)
					(end 113.141252 -78.6638)
				)
			)
		)
	)
	(zone
		(layers "In1.Cu" "In3.Cu" "In4.Cu" "In6.Cu" "In8.Cu")
		(hatch none 0.5)
		(connect_pads
			(clearance 0)
		)
		(min_thickness 0.25)
		(keepout
			(tracks not_allowed)
			(vias allowed)
			(pads allowed)
			(copperpour not_allowed)
			(footprints allowed)
		)
		(placement
			(enabled no)
			(sheetname "")
		)
		(fill yes
			(thermal_gap 0.5)
			(thermal_bridge_width 0.5)
			(island_removal_mode 0)
		)
		(polygon
			(pts
				(arc
					(start 150.824692 -70.353936)
					(mid 149.046692 -70.353936)
					(end 150.824692 -70.353936)
				)
			)
		)
	)
	(zone
		(layers "In1.Cu" "In3.Cu" "In4.Cu" "In6.Cu" "In8.Cu")
		(hatch none 0.5)
		(connect_pads
			(clearance 0)
		)
		(min_thickness 0.25)
		(keepout
			(tracks not_allowed)
			(vias allowed)
			(pads allowed)
			(copperpour not_allowed)
			(footprints allowed)
		)
		(placement
			(enabled no)
			(sheetname "")
		)
		(fill yes
			(thermal_gap 0.5)
			(thermal_bridge_width 0.5)
			(island_removal_mode 0)
		)
		(polygon
			(pts
				(arc
					(start 144.422114 -76.858368)
					(mid 142.644114 -76.858368)
					(end 144.422114 -76.858368)
				)
			)
		)
	)
	(zone
		(layers "In1.Cu" "In3.Cu" "In4.Cu" "In6.Cu" "In8.Cu")
		(hatch none 0.5)
		(connect_pads
			(clearance 0)
		)
		(min_thickness 0.25)
		(keepout
			(tracks not_allowed)
			(vias allowed)
			(pads allowed)
			(copperpour not_allowed)
			(footprints allowed)
		)
		(placement
			(enabled no)
			(sheetname "")
		)
		(fill yes
			(thermal_gap 0.5)
			(thermal_bridge_width 0.5)
			(island_removal_mode 0)
		)
		(polygon
			(pts
				(arc
					(start 270.9672 -86.233)
					(mid 269.1892 -86.233)
					(end 270.9672 -86.233)
				)
			)
		)
	)
	(zone
		(layers "In1.Cu" "In3.Cu" "In4.Cu" "In6.Cu" "In8.Cu")
		(hatch none 0.5)
		(connect_pads
			(clearance 0)
		)
		(min_thickness 0.25)
		(keepout
			(tracks not_allowed)
			(vias allowed)
			(pads allowed)
			(copperpour not_allowed)
			(footprints allowed)
		)
		(placement
			(enabled no)
			(sheetname "")
		)
		(fill yes
			(thermal_gap 0.5)
			(thermal_bridge_width 0.5)
			(island_removal_mode 0)
		)
		(polygon
			(pts
				(arc
					(start 336.256884 -28.5242)
					(mid 334.478884 -28.5242)
					(end 336.256884 -28.5242)
				)
			)
		)
	)
	(zone
		(layers "In1.Cu" "In3.Cu" "In4.Cu" "In6.Cu" "In8.Cu")
		(hatch none 0.5)
		(connect_pads
			(clearance 0)
		)
		(min_thickness 0.25)
		(keepout
			(tracks not_allowed)
			(vias allowed)
			(pads allowed)
			(copperpour not_allowed)
			(footprints allowed)
		)
		(placement
			(enabled no)
			(sheetname "")
		)
		(fill yes
			(thermal_gap 0.5)
			(thermal_bridge_width 0.5)
			(island_removal_mode 0)
		)
		(polygon
			(pts
				(arc
					(start 150.824692 -71.85406)
					(mid 149.046692 -71.85406)
					(end 150.824692 -71.85406)
				)
			)
		)
	)
	(zone
		(layers "In1.Cu" "In3.Cu" "In4.Cu" "In6.Cu" "In8.Cu")
		(hatch none 0.5)
		(connect_pads
			(clearance 0)
		)
		(min_thickness 0.25)
		(keepout
			(tracks not_allowed)
			(vias allowed)
			(pads allowed)
			(copperpour not_allowed)
			(footprints allowed)
		)
		(placement
			(enabled no)
			(sheetname "")
		)
		(fill yes
			(thermal_gap 0.5)
			(thermal_bridge_width 0.5)
			(island_removal_mode 0)
		)
		(polygon
			(pts
				(arc
					(start 336.256884 -62.357)
					(mid 334.478884 -62.357)
					(end 336.256884 -62.357)
				)
			)
		)
	)
	(zone
		(layers "In1.Cu" "In3.Cu" "In4.Cu" "In6.Cu" "In8.Cu")
		(hatch none 0.5)
		(connect_pads
			(clearance 0)
		)
		(min_thickness 0.25)
		(keepout
			(tracks not_allowed)
			(vias allowed)
			(pads allowed)
			(copperpour not_allowed)
			(footprints allowed)
		)
		(placement
			(enabled no)
			(sheetname "")
		)
		(fill yes
			(thermal_gap 0.5)
			(thermal_bridge_width 0.5)
			(island_removal_mode 0)
		)
		(polygon
			(pts
				(arc
					(start 336.256884 -73.6346)
					(mid 334.478884 -73.6346)
					(end 336.256884 -73.6346)
				)
			)
		)
	)
	(zone
		(layers "In1.Cu" "In3.Cu" "In4.Cu" "In6.Cu" "In8.Cu")
		(hatch none 0.5)
		(connect_pads
			(clearance 0)
		)
		(min_thickness 0.25)
		(keepout
			(tracks not_allowed)
			(vias allowed)
			(pads allowed)
			(copperpour not_allowed)
			(footprints allowed)
		)
		(placement
			(enabled no)
			(sheetname "")
		)
		(fill yes
			(thermal_gap 0.5)
			(thermal_bridge_width 0.5)
			(island_removal_mode 0)
		)
		(polygon
			(pts
				(arc
					(start 113.141252 -33.5534)
					(mid 111.363252 -33.5534)
					(end 113.141252 -33.5534)
				)
			)
		)
	)
	(zone
		(layers "In1.Cu" "In3.Cu" "In4.Cu" "In6.Cu" "In8.Cu")
		(hatch none 0.5)
		(connect_pads
			(clearance 0)
		)
		(min_thickness 0.25)
		(keepout
			(tracks not_allowed)
			(vias allowed)
			(pads allowed)
			(copperpour not_allowed)
			(footprints allowed)
		)
		(placement
			(enabled no)
			(sheetname "")
		)
		(fill yes
			(thermal_gap 0.5)
			(thermal_bridge_width 0.5)
			(island_removal_mode 0)
		)
		(polygon
			(pts
				(arc
					(start 146.060668 -73.42251)
					(mid 144.282668 -73.42251)
					(end 146.060668 -73.42251)
				)
			)
		)
	)
	(zone
		(layers "In1.Cu" "In3.Cu" "In4.Cu" "In6.Cu" "In8.Cu")
		(hatch none 0.5)
		(connect_pads
			(clearance 0)
		)
		(min_thickness 0.25)
		(keepout
			(tracks not_allowed)
			(vias allowed)
			(pads allowed)
			(copperpour not_allowed)
			(footprints allowed)
		)
		(placement
			(enabled no)
			(sheetname "")
		)
		(fill yes
			(thermal_gap 0.5)
			(thermal_bridge_width 0.5)
			(island_removal_mode 0)
		)
		(polygon
			(pts
				(arc
					(start 275.6662 -86.233)
					(mid 273.8882 -86.233)
					(end 275.6662 -86.233)
				)
			)
		)
	)
	(zone
		(layers "In1.Cu" "In3.Cu" "In4.Cu" "In6.Cu" "In8.Cu")
		(hatch none 0.5)
		(connect_pads
			(clearance 0)
		)
		(min_thickness 0.25)
		(keepout
			(tracks not_allowed)
			(vias allowed)
			(pads allowed)
			(copperpour not_allowed)
			(footprints allowed)
		)
		(placement
			(enabled no)
			(sheetname "")
		)
		(fill yes
			(thermal_gap 0.5)
			(thermal_bridge_width 0.5)
			(island_removal_mode 0)
		)
		(polygon
			(pts
				(arc
					(start 336.256884 -17.2466)
					(mid 334.478884 -17.2466)
					(end 336.256884 -17.2466)
				)
			)
		)
	)
	(zone
		(layers "In1.Cu" "In3.Cu" "In4.Cu" "In6.Cu" "In8.Cu")
		(hatch none 0.5)
		(connect_pads
			(clearance 0)
		)
		(min_thickness 0.25)
		(keepout
			(tracks not_allowed)
			(vias allowed)
			(pads allowed)
			(copperpour not_allowed)
			(footprints allowed)
		)
		(placement
			(enabled no)
			(sheetname "")
		)
		(fill yes
			(thermal_gap 0.5)
			(thermal_bridge_width 0.5)
			(island_removal_mode 0)
		)
		(polygon
			(pts
				(arc
					(start 150.922736 -79.7052)
					(mid 149.144736 -79.7052)
					(end 150.922736 -79.7052)
				)
			)
		)
	)
	(zone
		(layers "In1.Cu" "In3.Cu" "In4.Cu" "In6.Cu" "In8.Cu")
		(hatch none 0.5)
		(connect_pads
			(clearance 0)
		)
		(min_thickness 0.25)
		(keepout
			(tracks not_allowed)
			(vias allowed)
			(pads allowed)
			(copperpour not_allowed)
			(footprints allowed)
		)
		(placement
			(enabled no)
			(sheetname "")
		)
		(fill yes
			(thermal_gap 0.5)
			(thermal_bridge_width 0.5)
			(island_removal_mode 0)
		)
		(polygon
			(pts
				(arc
					(start 113.141252 -67.3862)
					(mid 111.363252 -67.3862)
					(end 113.141252 -67.3862)
				)
			)
		)
	)
	(zone
		(layers "In1.Cu" "In3.Cu" "In4.Cu" "In6.Cu" "In8.Cu")
		(hatch none 0.5)
		(connect_pads
			(clearance 0)
		)
		(min_thickness 0.25)
		(keepout
			(tracks not_allowed)
			(vias allowed)
			(pads allowed)
			(copperpour not_allowed)
			(footprints allowed)
		)
		(placement
			(enabled no)
			(sheetname "")
		)
		(fill yes
			(thermal_gap 0.5)
			(thermal_bridge_width 0.5)
			(island_removal_mode 0)
		)
		(polygon
			(pts
				(arc
					(start 275.0312 -86.233)
					(mid 273.2532 -86.233)
					(end 275.0312 -86.233)
				)
			)
		)
	)
	(zone
		(layers "In1.Cu" "In3.Cu" "In4.Cu" "In6.Cu" "In8.Cu")
		(hatch none 0.5)
		(connect_pads
			(clearance 0)
		)
		(min_thickness 0.25)
		(keepout
			(tracks not_allowed)
			(vias allowed)
			(pads allowed)
			(copperpour not_allowed)
			(footprints allowed)
		)
		(placement
			(enabled no)
			(sheetname "")
		)
		(fill yes
			(thermal_gap 0.5)
			(thermal_bridge_width 0.5)
			(island_removal_mode 0)
		)
		(polygon
			(pts
				(arc
					(start 271.6022 -86.233)
					(mid 269.8242 -86.233)
					(end 271.6022 -86.233)
				)
			)
		)
	)
	(zone
		(layers "In1.Cu" "In3.Cu" "In4.Cu" "In6.Cu" "In8.Cu")
		(hatch none 0.5)
		(connect_pads
			(clearance 0)
		)
		(min_thickness 0.25)
		(keepout
			(tracks not_allowed)
			(vias allowed)
			(pads allowed)
			(copperpour not_allowed)
			(footprints allowed)
		)
		(placement
			(enabled no)
			(sheetname "")
		)
		(fill yes
			(thermal_gap 0.5)
			(thermal_bridge_width 0.5)
			(island_removal_mode 0)
		)
		(polygon
			(pts
				(arc
					(start 145.781522 -76.886308)
					(mid 144.003522 -76.886308)
					(end 145.781522 -76.886308)
				)
			)
		)
	)
	(zone
		(layers "In1.Cu" "In3.Cu" "In4.Cu" "In6.Cu" "In8.Cu")
		(hatch none 0.5)
		(connect_pads
			(clearance 0)
		)
		(min_thickness 0.25)
		(keepout
			(tracks not_allowed)
			(vias allowed)
			(pads allowed)
			(copperpour not_allowed)
			(footprints allowed)
		)
		(placement
			(enabled no)
			(sheetname "")
		)
		(fill yes
			(thermal_gap 0.5)
			(thermal_bridge_width 0.5)
			(island_removal_mode 0)
		)
		(polygon
			(pts
				(arc
					(start 146.00555 -74.360278)
					(mid 144.22755 -74.360278)
					(end 146.00555 -74.360278)
				)
			)
		)
	)
	(zone
		(layers "In1.Cu" "In3.Cu" "In4.Cu" "In6.Cu" "In8.Cu")
		(hatch none 0.5)
		(connect_pads
			(clearance 0)
		)
		(min_thickness 0.25)
		(keepout
			(tracks not_allowed)
			(vias allowed)
			(pads allowed)
			(copperpour not_allowed)
			(footprints allowed)
		)
		(placement
			(enabled no)
			(sheetname "")
		)
		(fill yes
			(thermal_gap 0.5)
			(thermal_bridge_width 0.5)
			(island_removal_mode 0)
		)
		(polygon
			(pts
				(arc
					(start 336.256884 -51.0794)
					(mid 334.478884 -51.0794)
					(end 336.256884 -51.0794)
				)
			)
		)
	)
	(zone
		(layers "In1.Cu" "In3.Cu" "In4.Cu" "In6.Cu" "In8.Cu")
		(hatch none 0.5)
		(connect_pads
			(clearance 0)
		)
		(min_thickness 0.25)
		(keepout
			(tracks not_allowed)
			(vias allowed)
			(pads allowed)
			(copperpour not_allowed)
			(footprints allowed)
		)
		(placement
			(enabled no)
			(sheetname "")
		)
		(fill yes
			(thermal_gap 0.5)
			(thermal_bridge_width 0.5)
			(island_removal_mode 0)
		)
		(polygon
			(pts
				(arc
					(start 150.922736 -78.9432)
					(mid 149.144736 -78.9432)
					(end 150.922736 -78.9432)
				)
			)
		)
	)
	(zone
		(layers "In1.Cu" "In3.Cu" "In4.Cu" "In6.Cu" "In8.Cu")
		(hatch none 0.5)
		(connect_pads
			(clearance 0)
		)
		(min_thickness 0.25)
		(keepout
			(tracks not_allowed)
			(vias allowed)
			(pads allowed)
			(copperpour not_allowed)
			(footprints allowed)
		)
		(placement
			(enabled no)
			(sheetname "")
		)
		(fill yes
			(thermal_gap 0.5)
			(thermal_bridge_width 0.5)
			(island_removal_mode 0)
		)
		(polygon
			(pts
				(arc
					(start 272.9992 -86.233)
					(mid 271.2212 -86.233)
					(end 272.9992 -86.233)
				)
			)
		)
	)
	(zone
		(layers "In1.Cu" "In3.Cu" "In4.Cu" "In6.Cu" "In8.Cu")
		(hatch none 0.5)
		(connect_pads
			(clearance 0)
		)
		(min_thickness 0.25)
		(keepout
			(tracks not_allowed)
			(vias allowed)
			(pads allowed)
			(copperpour not_allowed)
			(footprints allowed)
		)
		(placement
			(enabled no)
			(sheetname "")
		)
		(fill yes
			(thermal_gap 0.5)
			(thermal_bridge_width 0.5)
			(island_removal_mode 0)
		)
		(polygon
			(pts
				(arc
					(start 113.141252 -44.831)
					(mid 111.363252 -44.831)
					(end 113.141252 -44.831)
				)
			)
		)
	)
	(zone
		(layers "In1.Cu" "In3.Cu" "In4.Cu" "In6.Cu" "In8.Cu")
		(hatch none 0.5)
		(connect_pads
			(clearance 0)
		)
		(min_thickness 0.25)
		(keepout
			(tracks not_allowed)
			(vias allowed)
			(pads allowed)
			(copperpour not_allowed)
			(footprints allowed)
		)
		(placement
			(enabled no)
			(sheetname "")
		)
		(fill yes
			(thermal_gap 0.5)
			(thermal_bridge_width 0.5)
			(island_removal_mode 0)
		)
		(polygon
			(pts
				(arc
					(start 265.7602 -69.34708)
					(mid 263.9822 -69.34708)
					(end 265.7602 -69.34708)
				)
			)
		)
	)
	(zone
		(layers "In1.Cu" "In3.Cu" "In4.Cu" "In6.Cu" "In8.Cu")
		(hatch none 0.5)
		(connect_pads
			(clearance 0)
		)
		(min_thickness 0.25)
		(keepout
			(tracks not_allowed)
			(vias allowed)
			(pads allowed)
			(copperpour not_allowed)
			(footprints allowed)
		)
		(placement
			(enabled no)
			(sheetname "")
		)
		(fill yes
			(thermal_gap 0.5)
			(thermal_bridge_width 0.5)
			(island_removal_mode 0)
		)
		(polygon
			(pts
				(arc
					(start 277.5712 -86.233)
					(mid 275.7932 -86.233)
					(end 277.5712 -86.233)
				)
			)
		)
	)
	(zone
		(layers "In1.Cu" "In3.Cu" "In5.Cu" "In6.Cu" "In8.Cu")
		(hatch none 0.5)
		(connect_pads
			(clearance 0)
		)
		(min_thickness 0.25)
		(keepout
			(tracks not_allowed)
			(vias allowed)
			(pads allowed)
			(copperpour not_allowed)
			(footprints allowed)
		)
		(placement
			(enabled no)
			(sheetname "")
		)
		(fill yes
			(thermal_gap 0.5)
			(thermal_bridge_width 0.5)
			(island_removal_mode 0)
		)
		(polygon
			(pts
				(arc
					(start 152.452832 -60.917582)
					(mid 150.674832 -60.917582)
					(end 152.452832 -60.917582)
				)
			)
		)
	)
	(zone
		(layers "In1.Cu" "In3.Cu" "In5.Cu" "In6.Cu" "In8.Cu")
		(hatch none 0.5)
		(connect_pads
			(clearance 0)
		)
		(min_thickness 0.25)
		(keepout
			(tracks not_allowed)
			(vias allowed)
			(pads allowed)
			(copperpour not_allowed)
			(footprints allowed)
		)
		(placement
			(enabled no)
			(sheetname "")
		)
		(fill yes
			(thermal_gap 0.5)
			(thermal_bridge_width 0.5)
			(island_removal_mode 0)
		)
		(polygon
			(pts
				(arc
					(start 281.218894 -78.1558)
					(mid 279.440894 -78.1558)
					(end 281.218894 -78.1558)
				)
			)
		)
	)
	(zone
		(layers "In1.Cu" "In3.Cu" "In5.Cu" "In6.Cu" "In8.Cu")
		(hatch none 0.5)
		(connect_pads
			(clearance 0)
		)
		(min_thickness 0.25)
		(keepout
			(tracks not_allowed)
			(vias allowed)
			(pads allowed)
			(copperpour not_allowed)
			(footprints allowed)
		)
		(placement
			(enabled no)
			(sheetname "")
		)
		(fill yes
			(thermal_gap 0.5)
			(thermal_bridge_width 0.5)
			(island_removal_mode 0)
		)
		(polygon
			(pts
				(arc
					(start 269.9512 -68.199)
					(mid 268.1732 -68.199)
					(end 269.9512 -68.199)
				)
			)
		)
	)
	(zone
		(layers "In1.Cu" "In3.Cu" "In5.Cu" "In6.Cu" "In8.Cu")
		(hatch none 0.5)
		(connect_pads
			(clearance 0)
		)
		(min_thickness 0.25)
		(keepout
			(tracks not_allowed)
			(vias allowed)
			(pads allowed)
			(copperpour not_allowed)
			(footprints allowed)
		)
		(placement
			(enabled no)
			(sheetname "")
		)
		(fill yes
			(thermal_gap 0.5)
			(thermal_bridge_width 0.5)
			(island_removal_mode 0)
		)
		(polygon
			(pts
				(arc
					(start 185.6994 -68.58)
					(mid 183.9214 -68.58)
					(end 185.6994 -68.58)
				)
			)
		)
	)
	(zone
		(layers "In1.Cu" "In3.Cu" "In5.Cu" "In6.Cu" "In8.Cu")
		(hatch none 0.5)
		(connect_pads
			(clearance 0)
		)
		(min_thickness 0.25)
		(keepout
			(tracks not_allowed)
			(vias allowed)
			(pads allowed)
			(copperpour not_allowed)
			(footprints allowed)
		)
		(placement
			(enabled no)
			(sheetname "")
		)
		(fill yes
			(thermal_gap 0.5)
			(thermal_bridge_width 0.5)
			(island_removal_mode 0)
		)
		(polygon
			(pts
				(arc
					(start 168.1734 -60.3758)
					(mid 166.3954 -60.3758)
					(end 168.1734 -60.3758)
				)
			)
		)
	)
	(zone
		(layers "In1.Cu" "In3.Cu" "In5.Cu" "In6.Cu" "In8.Cu")
		(hatch none 0.5)
		(connect_pads
			(clearance 0)
		)
		(min_thickness 0.25)
		(keepout
			(tracks not_allowed)
			(vias allowed)
			(pads allowed)
			(copperpour not_allowed)
			(footprints allowed)
		)
		(placement
			(enabled no)
			(sheetname "")
		)
		(fill yes
			(thermal_gap 0.5)
			(thermal_bridge_width 0.5)
			(island_removal_mode 0)
		)
		(polygon
			(pts
				(arc
					(start 304.8 -74.494136)
					(mid 303.022 -74.494136)
					(end 304.8 -74.494136)
				)
			)
		)
	)
	(zone
		(layers "In1.Cu" "In3.Cu" "In5.Cu" "In6.Cu" "In8.Cu")
		(hatch none 0.5)
		(connect_pads
			(clearance 0)
		)
		(min_thickness 0.25)
		(keepout
			(tracks not_allowed)
			(vias allowed)
			(pads allowed)
			(copperpour not_allowed)
			(footprints allowed)
		)
		(placement
			(enabled no)
			(sheetname "")
		)
		(fill yes
			(thermal_gap 0.5)
			(thermal_bridge_width 0.5)
			(island_removal_mode 0)
		)
		(polygon
			(pts
				(arc
					(start 262.382 -71.5772)
					(mid 260.604 -71.5772)
					(end 262.382 -71.5772)
				)
			)
		)
	)
	(zone
		(layers "In1.Cu" "In3.Cu" "In5.Cu" "In6.Cu" "In8.Cu")
		(hatch none 0.5)
		(connect_pads
			(clearance 0)
		)
		(min_thickness 0.25)
		(keepout
			(tracks not_allowed)
			(vias allowed)
			(pads allowed)
			(copperpour not_allowed)
			(footprints allowed)
		)
		(placement
			(enabled no)
			(sheetname "")
		)
		(fill yes
			(thermal_gap 0.5)
			(thermal_bridge_width 0.5)
			(island_removal_mode 0)
		)
		(polygon
			(pts
				(arc
					(start 306.07 -74.494136)
					(mid 304.292 -74.494136)
					(end 306.07 -74.494136)
				)
			)
		)
	)
	(zone
		(layers "In1.Cu" "In3.Cu" "In5.Cu" "In6.Cu" "In8.Cu")
		(hatch none 0.5)
		(connect_pads
			(clearance 0)
		)
		(min_thickness 0.25)
		(keepout
			(tracks not_allowed)
			(vias allowed)
			(pads allowed)
			(copperpour not_allowed)
			(footprints allowed)
		)
		(placement
			(enabled no)
			(sheetname "")
		)
		(fill yes
			(thermal_gap 0.5)
			(thermal_bridge_width 0.5)
			(island_removal_mode 0)
		)
		(polygon
			(pts
				(arc
					(start 271.2974 -57.912)
					(mid 269.5194 -57.912)
					(end 271.2974 -57.912)
				)
			)
		)
	)
	(zone
		(layers "In1.Cu" "In3.Cu" "In5.Cu" "In6.Cu" "In8.Cu")
		(hatch none 0.5)
		(connect_pads
			(clearance 0)
		)
		(min_thickness 0.25)
		(keepout
			(tracks not_allowed)
			(vias allowed)
			(pads allowed)
			(copperpour not_allowed)
			(footprints allowed)
		)
		(placement
			(enabled no)
			(sheetname "")
		)
		(fill yes
			(thermal_gap 0.5)
			(thermal_bridge_width 0.5)
			(island_removal_mode 0)
		)
		(polygon
			(pts
				(arc
					(start 281.980894 -78.1558)
					(mid 280.202894 -78.1558)
					(end 281.980894 -78.1558)
				)
			)
		)
	)
	(zone
		(layers "In1.Cu" "In3.Cu" "In5.Cu" "In6.Cu" "In8.Cu")
		(hatch none 0.5)
		(connect_pads
			(clearance 0)
		)
		(min_thickness 0.25)
		(keepout
			(tracks not_allowed)
			(vias allowed)
			(pads allowed)
			(copperpour not_allowed)
			(footprints allowed)
		)
		(placement
			(enabled no)
			(sheetname "")
		)
		(fill yes
			(thermal_gap 0.5)
			(thermal_bridge_width 0.5)
			(island_removal_mode 0)
		)
		(polygon
			(pts
				(arc
					(start 186.4614 -68.58)
					(mid 184.6834 -68.58)
					(end 186.4614 -68.58)
				)
			)
		)
	)
	(zone
		(layers "In1.Cu" "In3.Cu" "In5.Cu" "In6.Cu" "In8.Cu")
		(hatch none 0.5)
		(connect_pads
			(clearance 0)
		)
		(min_thickness 0.25)
		(keepout
			(tracks not_allowed)
			(vias allowed)
			(pads allowed)
			(copperpour not_allowed)
			(footprints allowed)
		)
		(placement
			(enabled no)
			(sheetname "")
		)
		(fill yes
			(thermal_gap 0.5)
			(thermal_bridge_width 0.5)
			(island_removal_mode 0)
		)
		(polygon
			(pts
				(arc
					(start 270.5354 -57.912)
					(mid 268.7574 -57.912)
					(end 270.5354 -57.912)
				)
			)
		)
	)
	(zone
		(layers "In1.Cu" "In3.Cu" "In5.Cu" "In6.Cu" "In8.Cu")
		(hatch none 0.5)
		(connect_pads
			(clearance 0)
		)
		(min_thickness 0.25)
		(keepout
			(tracks not_allowed)
			(vias allowed)
			(pads allowed)
			(copperpour not_allowed)
			(footprints allowed)
		)
		(placement
			(enabled no)
			(sheetname "")
		)
		(fill yes
			(thermal_gap 0.5)
			(thermal_bridge_width 0.5)
			(island_removal_mode 0)
		)
		(polygon
			(pts
				(arc
					(start 263.144 -71.5772)
					(mid 261.366 -71.5772)
					(end 263.144 -71.5772)
				)
			)
		)
	)
	(zone
		(layers "In1.Cu" "In3.Cu" "In5.Cu" "In6.Cu" "In8.Cu")
		(hatch none 0.5)
		(connect_pads
			(clearance 0)
		)
		(min_thickness 0.25)
		(keepout
			(tracks not_allowed)
			(vias allowed)
			(pads allowed)
			(copperpour not_allowed)
			(footprints allowed)
		)
		(placement
			(enabled no)
			(sheetname "")
		)
		(fill yes
			(thermal_gap 0.5)
			(thermal_bridge_width 0.5)
			(island_removal_mode 0)
		)
		(polygon
			(pts
				(arc
					(start 167.4114 -60.3758)
					(mid 165.6334 -60.3758)
					(end 167.4114 -60.3758)
				)
			)
		)
	)
	(zone
		(layers "In1.Cu" "In3.Cu" "In5.Cu" "In6.Cu" "In8.Cu")
		(hatch none 0.5)
		(connect_pads
			(clearance 0)
		)
		(min_thickness 0.25)
		(keepout
			(tracks not_allowed)
			(vias allowed)
			(pads allowed)
			(copperpour not_allowed)
			(footprints allowed)
		)
		(placement
			(enabled no)
			(sheetname "")
		)
		(fill yes
			(thermal_gap 0.5)
			(thermal_bridge_width 0.5)
			(island_removal_mode 0)
		)
		(polygon
			(pts
				(arc
					(start 272.8214 -57.912)
					(mid 271.0434 -57.912)
					(end 272.8214 -57.912)
				)
			)
		)
	)
	(zone
		(layers "In1.Cu" "In3.Cu" "In5.Cu" "In6.Cu" "In8.Cu")
		(hatch none 0.5)
		(connect_pads
			(clearance 0)
		)
		(min_thickness 0.25)
		(keepout
			(tracks not_allowed)
			(vias allowed)
			(pads allowed)
			(copperpour not_allowed)
			(footprints allowed)
		)
		(placement
			(enabled no)
			(sheetname "")
		)
		(fill yes
			(thermal_gap 0.5)
			(thermal_bridge_width 0.5)
			(island_removal_mode 0)
		)
		(polygon
			(pts
				(arc
					(start 273.5834 -57.912)
					(mid 271.8054 -57.912)
					(end 273.5834 -57.912)
				)
			)
		)
	)
	(zone
		(layers "In1.Cu" "In3.Cu" "In5.Cu" "In6.Cu" "In8.Cu")
		(hatch none 0.5)
		(connect_pads
			(clearance 0)
		)
		(min_thickness 0.25)
		(keepout
			(tracks not_allowed)
			(vias allowed)
			(pads allowed)
			(copperpour not_allowed)
			(footprints allowed)
		)
		(placement
			(enabled no)
			(sheetname "")
		)
		(fill yes
			(thermal_gap 0.5)
			(thermal_bridge_width 0.5)
			(island_removal_mode 0)
		)
		(polygon
			(pts
				(arc
					(start 299.6438 -80.391)
					(mid 297.8658 -80.391)
					(end 299.6438 -80.391)
				)
			)
		)
	)
	(zone
		(layers "In1.Cu" "In3.Cu" "In5.Cu" "In6.Cu" "In8.Cu")
		(hatch none 0.5)
		(connect_pads
			(clearance 0)
		)
		(min_thickness 0.25)
		(keepout
			(tracks not_allowed)
			(vias allowed)
			(pads allowed)
			(copperpour not_allowed)
			(footprints allowed)
		)
		(placement
			(enabled no)
			(sheetname "")
		)
		(fill yes
			(thermal_gap 0.5)
			(thermal_bridge_width 0.5)
			(island_removal_mode 0)
		)
		(polygon
			(pts
				(arc
					(start 269.9512 -71.0184)
					(mid 268.1732 -71.0184)
					(end 269.9512 -71.0184)
				)
			)
		)
	)
	(zone
		(layers "In1.Cu" "In3.Cu" "In5.Cu" "In6.Cu" "In8.Cu")
		(hatch none 0.5)
		(connect_pads
			(clearance 0)
		)
		(min_thickness 0.25)
		(keepout
			(tracks not_allowed)
			(vias allowed)
			(pads allowed)
			(copperpour not_allowed)
			(footprints allowed)
		)
		(placement
			(enabled no)
			(sheetname "")
		)
		(fill yes
			(thermal_gap 0.5)
			(thermal_bridge_width 0.5)
			(island_removal_mode 0)
		)
		(polygon
			(pts
				(arc
					(start 298.958 -75.819)
					(mid 297.18 -75.819)
					(end 298.958 -75.819)
				)
			)
		)
	)
	(zone
		(layers "In1.Cu" "In3.Cu" "In5.Cu" "In6.Cu" "In8.Cu")
		(hatch none 0.5)
		(connect_pads
			(clearance 0)
		)
		(min_thickness 0.25)
		(keepout
			(tracks not_allowed)
			(vias allowed)
			(pads allowed)
			(copperpour not_allowed)
			(footprints allowed)
		)
		(placement
			(enabled no)
			(sheetname "")
		)
		(fill yes
			(thermal_gap 0.5)
			(thermal_bridge_width 0.5)
			(island_removal_mode 0)
		)
		(polygon
			(pts
				(arc
					(start 177.140616 -82.304128)
					(mid 175.362616 -82.304128)
					(end 177.140616 -82.304128)
				)
			)
		)
	)
	(zone
		(layers "In1.Cu" "In3.Cu" "In5.Cu" "In6.Cu" "In8.Cu")
		(hatch none 0.5)
		(connect_pads
			(clearance 0)
		)
		(min_thickness 0.25)
		(keepout
			(tracks not_allowed)
			(vias allowed)
			(pads allowed)
			(copperpour not_allowed)
			(footprints allowed)
		)
		(placement
			(enabled no)
			(sheetname "")
		)
		(fill yes
			(thermal_gap 0.5)
			(thermal_bridge_width 0.5)
			(island_removal_mode 0)
		)
		(polygon
			(pts
				(arc
					(start 298.8818 -80.391)
					(mid 297.1038 -80.391)
					(end 298.8818 -80.391)
				)
			)
		)
	)
	(zone
		(layers "In1.Cu" "In3.Cu" "In5.Cu" "In6.Cu" "In8.Cu")
		(hatch none 0.5)
		(connect_pads
			(clearance 0)
		)
		(min_thickness 0.25)
		(keepout
			(tracks not_allowed)
			(vias allowed)
			(pads allowed)
			(copperpour not_allowed)
			(footprints allowed)
		)
		(placement
			(enabled no)
			(sheetname "")
		)
		(fill yes
			(thermal_gap 0.5)
			(thermal_bridge_width 0.5)
			(island_removal_mode 0)
		)
		(polygon
			(pts
				(arc
					(start 177.828702 -82.304128)
					(mid 176.050702 -82.304128)
					(end 177.828702 -82.304128)
				)
			)
		)
	)
	(zone
		(layers "In1.Cu" "In3.Cu" "In5.Cu" "In6.Cu" "In8.Cu")
		(hatch none 0.5)
		(connect_pads
			(clearance 0)
		)
		(min_thickness 0.25)
		(keepout
			(tracks not_allowed)
			(vias allowed)
			(pads allowed)
			(copperpour not_allowed)
			(footprints allowed)
		)
		(placement
			(enabled no)
			(sheetname "")
		)
		(fill yes
			(thermal_gap 0.5)
			(thermal_bridge_width 0.5)
			(island_removal_mode 0)
		)
		(polygon
			(pts
				(arc
					(start 151.690832 -60.917582)
					(mid 149.912832 -60.917582)
					(end 151.690832 -60.917582)
				)
			)
		)
	)
	(zone
		(layers "In1.Cu" "In3.Cu" "In6.Cu" "In8.Cu")
		(hatch none 0.5)
		(connect_pads
			(clearance 0)
		)
		(min_thickness 0.25)
		(keepout
			(tracks not_allowed)
			(vias allowed)
			(pads allowed)
			(copperpour not_allowed)
			(footprints allowed)
		)
		(placement
			(enabled no)
			(sheetname "")
		)
		(fill yes
			(thermal_gap 0.5)
			(thermal_bridge_width 0.5)
			(island_removal_mode 0)
		)
		(polygon
			(pts
				(arc
					(start 336.0928 -32.8422)
					(mid 334.3148 -32.8422)
					(end 336.0928 -32.8422)
				)
			)
		)
	)
	(zone
		(layers "In1.Cu" "In3.Cu" "In6.Cu" "In8.Cu")
		(hatch none 0.5)
		(connect_pads
			(clearance 0)
		)
		(min_thickness 0.25)
		(keepout
			(tracks not_allowed)
			(vias allowed)
			(pads allowed)
			(copperpour not_allowed)
			(footprints allowed)
		)
		(placement
			(enabled no)
			(sheetname "")
		)
		(fill yes
			(thermal_gap 0.5)
			(thermal_bridge_width 0.5)
			(island_removal_mode 0)
		)
		(polygon
			(pts
				(arc
					(start 52.013104 -156.830014)
					(mid 49.586896 -156.830014)
					(end 52.013104 -156.830014)
				)
			)
		)
	)
	(zone
		(layers "In1.Cu" "In3.Cu" "In6.Cu" "In8.Cu")
		(hatch none 0.5)
		(connect_pads
			(clearance 0)
		)
		(min_thickness 0.25)
		(keepout
			(tracks not_allowed)
			(vias allowed)
			(pads allowed)
			(copperpour not_allowed)
			(footprints allowed)
		)
		(placement
			(enabled no)
			(sheetname "")
		)
		(fill yes
			(thermal_gap 0.5)
			(thermal_bridge_width 0.5)
			(island_removal_mode 0)
		)
		(polygon
			(pts
				(arc
					(start 43.88739 -99.06)
					(mid 40.83939 -99.06)
					(end 43.88739 -99.06)
				)
			)
		)
	)
	(zone
		(layers "In1.Cu" "In3.Cu" "In6.Cu" "In8.Cu")
		(hatch none 0.5)
		(connect_pads
			(clearance 0)
		)
		(min_thickness 0.25)
		(keepout
			(tracks not_allowed)
			(vias allowed)
			(pads allowed)
			(copperpour not_allowed)
			(footprints allowed)
		)
		(placement
			(enabled no)
			(sheetname "")
		)
		(fill yes
			(thermal_gap 0.5)
			(thermal_bridge_width 0.5)
			(island_removal_mode 0)
		)
		(polygon
			(pts
				(arc
					(start 113.344452 -36.7792)
					(mid 111.566452 -36.7792)
					(end 113.344452 -36.7792)
				)
			)
		)
	)
	(zone
		(layers "In1.Cu" "In3.Cu" "In6.Cu" "In8.Cu")
		(hatch none 0.5)
		(connect_pads
			(clearance 0)
		)
		(min_thickness 0.25)
		(keepout
			(tracks not_allowed)
			(vias allowed)
			(pads allowed)
			(copperpour not_allowed)
			(footprints allowed)
		)
		(placement
			(enabled no)
			(sheetname "")
		)
		(fill yes
			(thermal_gap 0.5)
			(thermal_bridge_width 0.5)
			(island_removal_mode 0)
		)
		(polygon
			(pts
				(arc
					(start 335.3308 -67.437)
					(mid 333.5528 -67.437)
					(end 335.3308 -67.437)
				)
			)
		)
	)
	(zone
		(layers "In1.Cu" "In3.Cu" "In6.Cu" "In8.Cu")
		(hatch none 0.5)
		(connect_pads
			(clearance 0)
		)
		(min_thickness 0.25)
		(keepout
			(tracks not_allowed)
			(vias allowed)
			(pads allowed)
			(copperpour not_allowed)
			(footprints allowed)
		)
		(placement
			(enabled no)
			(sheetname "")
		)
		(fill yes
			(thermal_gap 0.5)
			(thermal_bridge_width 0.5)
			(island_removal_mode 0)
		)
		(polygon
			(pts
				(arc
					(start 114.106452 -14.986)
					(mid 112.328452 -14.986)
					(end 114.106452 -14.986)
				)
			)
		)
	)
	(zone
		(layers "In1.Cu" "In3.Cu" "In6.Cu" "In8.Cu")
		(hatch none 0.5)
		(connect_pads
			(clearance 0)
		)
		(min_thickness 0.25)
		(keepout
			(tracks not_allowed)
			(vias allowed)
			(pads allowed)
			(copperpour not_allowed)
			(footprints allowed)
		)
		(placement
			(enabled no)
			(sheetname "")
		)
		(fill yes
			(thermal_gap 0.5)
			(thermal_bridge_width 0.5)
			(island_removal_mode 0)
		)
		(polygon
			(pts
				(arc
					(start 113.344452 -50.3428)
					(mid 111.566452 -50.3428)
					(end 113.344452 -50.3428)
				)
			)
		)
	)
	(zone
		(layers "In1.Cu" "In3.Cu" "In6.Cu" "In8.Cu")
		(hatch none 0.5)
		(connect_pads
			(clearance 0)
		)
		(min_thickness 0.25)
		(keepout
			(tracks not_allowed)
			(vias allowed)
			(pads allowed)
			(copperpour not_allowed)
			(footprints allowed)
		)
		(placement
			(enabled no)
			(sheetname "")
		)
		(fill yes
			(thermal_gap 0.5)
			(thermal_bridge_width 0.5)
			(island_removal_mode 0)
		)
		(polygon
			(pts
				(arc
					(start 333.8068 -65.913)
					(mid 332.0288 -65.913)
					(end 333.8068 -65.913)
				)
			)
		)
	)
	(zone
		(layers "In1.Cu" "In3.Cu" "In6.Cu" "In8.Cu")
		(hatch none 0.5)
		(connect_pads
			(clearance 0)
		)
		(min_thickness 0.25)
		(keepout
			(tracks not_allowed)
			(vias allowed)
			(pads allowed)
			(copperpour not_allowed)
			(footprints allowed)
		)
		(placement
			(enabled no)
			(sheetname "")
		)
		(fill yes
			(thermal_gap 0.5)
			(thermal_bridge_width 0.5)
			(island_removal_mode 0)
		)
		(polygon
			(pts
				(arc
					(start 364.21314 -156.830014)
					(mid 361.786932 -156.830014)
					(end 364.21314 -156.830014)
				)
			)
		)
	)
	(zone
		(layers "In1.Cu" "In3.Cu" "In6.Cu" "In8.Cu")
		(hatch none 0.5)
		(connect_pads
			(clearance 0)
		)
		(min_thickness 0.25)
		(keepout
			(tracks not_allowed)
			(vias allowed)
			(pads allowed)
			(copperpour not_allowed)
			(footprints allowed)
		)
		(placement
			(enabled no)
			(sheetname "")
		)
		(fill yes
			(thermal_gap 0.5)
			(thermal_bridge_width 0.5)
			(island_removal_mode 0)
		)
		(polygon
			(pts
				(arc
					(start 333.8068 -42.5958)
					(mid 332.0288 -42.5958)
					(end 333.8068 -42.5958)
				)
			)
		)
	)
	(zone
		(layers "In1.Cu" "In3.Cu" "In6.Cu" "In8.Cu")
		(hatch none 0.5)
		(connect_pads
			(clearance 0)
		)
		(min_thickness 0.25)
		(keepout
			(tracks not_allowed)
			(vias allowed)
			(pads allowed)
			(copperpour not_allowed)
			(footprints allowed)
		)
		(placement
			(enabled no)
			(sheetname "")
		)
		(fill yes
			(thermal_gap 0.5)
			(thermal_bridge_width 0.5)
			(island_removal_mode 0)
		)
		(polygon
			(pts
				(arc
					(start 355.78542 -3.829304)
					(mid 354.00742 -3.829304)
					(end 355.78542 -3.829304)
				)
			)
		)
	)
	(zone
		(layers "In1.Cu" "In3.Cu" "In6.Cu" "In8.Cu")
		(hatch none 0.5)
		(connect_pads
			(clearance 0)
		)
		(min_thickness 0.25)
		(keepout
			(tracks not_allowed)
			(vias allowed)
			(pads allowed)
			(copperpour not_allowed)
			(footprints allowed)
		)
		(placement
			(enabled no)
			(sheetname "")
		)
		(fill yes
			(thermal_gap 0.5)
			(thermal_bridge_width 0.5)
			(island_removal_mode 0)
		)
		(polygon
			(pts
				(arc
					(start 379.603 -139.7)
					(mid 376.555 -139.7)
					(end 379.603 -139.7)
				)
			)
		)
	)
	(zone
		(layers "In1.Cu" "In3.Cu" "In6.Cu" "In8.Cu")
		(hatch none 0.5)
		(connect_pads
			(clearance 0)
		)
		(min_thickness 0.25)
		(keepout
			(tracks not_allowed)
			(vias allowed)
			(pads allowed)
			(copperpour not_allowed)
			(footprints allowed)
		)
		(placement
			(enabled no)
			(sheetname "")
		)
		(fill yes
			(thermal_gap 0.5)
			(thermal_bridge_width 0.5)
			(island_removal_mode 0)
		)
		(polygon
			(pts
				(arc
					(start 113.344452 -70.612)
					(mid 111.566452 -70.612)
					(end 113.344452 -70.612)
				)
			)
		)
	)
	(zone
		(layers "In1.Cu" "In3.Cu" "In6.Cu" "In8.Cu")
		(hatch none 0.5)
		(connect_pads
			(clearance 0)
		)
		(min_thickness 0.25)
		(keepout
			(tracks not_allowed)
			(vias allowed)
			(pads allowed)
			(copperpour not_allowed)
			(footprints allowed)
		)
		(placement
			(enabled no)
			(sheetname "")
		)
		(fill yes
			(thermal_gap 0.5)
			(thermal_bridge_width 0.5)
			(island_removal_mode 0)
		)
		(polygon
			(pts
				(arc
					(start 334.5688 -77.1906)
					(mid 332.7908 -77.1906)
					(end 334.5688 -77.1906)
				)
			)
		)
	)
	(zone
		(layers "In1.Cu" "In3.Cu" "In6.Cu" "In8.Cu")
		(hatch none 0.5)
		(connect_pads
			(clearance 0)
		)
		(min_thickness 0.25)
		(keepout
			(tracks not_allowed)
			(vias allowed)
			(pads allowed)
			(copperpour not_allowed)
			(footprints allowed)
		)
		(placement
			(enabled no)
			(sheetname "")
		)
		(fill yes
			(thermal_gap 0.5)
			(thermal_bridge_width 0.5)
			(island_removal_mode 0)
		)
		(polygon
			(pts
				(arc
					(start 359.59542 -4.591304)
					(mid 357.81742 -4.591304)
					(end 359.59542 -4.591304)
				)
			)
		)
	)
	(zone
		(layers "In1.Cu" "In3.Cu" "In6.Cu" "In8.Cu")
		(hatch none 0.5)
		(connect_pads
			(clearance 0)
		)
		(min_thickness 0.25)
		(keepout
			(tracks not_allowed)
			(vias allowed)
			(pads allowed)
			(copperpour not_allowed)
			(footprints allowed)
		)
		(placement
			(enabled no)
			(sheetname "")
		)
		(fill yes
			(thermal_gap 0.5)
			(thermal_bridge_width 0.5)
			(island_removal_mode 0)
		)
		(polygon
			(pts
				(arc
					(start 334.5688 -76.4286)
					(mid 332.7908 -76.4286)
					(end 334.5688 -76.4286)
				)
			)
		)
	)
	(zone
		(layers "In1.Cu" "In3.Cu" "In6.Cu" "In8.Cu")
		(hatch none 0.5)
		(connect_pads
			(clearance 0)
		)
		(min_thickness 0.25)
		(keepout
			(tracks not_allowed)
			(vias allowed)
			(pads allowed)
			(copperpour not_allowed)
			(footprints allowed)
		)
		(placement
			(enabled no)
			(sheetname "")
		)
		(fill yes
			(thermal_gap 0.5)
			(thermal_bridge_width 0.5)
			(island_removal_mode 0)
		)
		(polygon
			(pts
				(arc
					(start 38.088062 -158.83001)
					(mid 35.661854 -158.83001)
					(end 38.088062 -158.83001)
				)
			)
		)
	)
	(zone
		(layers "In1.Cu" "In3.Cu" "In6.Cu" "In8.Cu")
		(hatch none 0.5)
		(connect_pads
			(clearance 0)
		)
		(min_thickness 0.25)
		(keepout
			(tracks not_allowed)
			(vias allowed)
			(pads allowed)
			(copperpour not_allowed)
			(footprints allowed)
		)
		(placement
			(enabled no)
			(sheetname "")
		)
		(fill yes
			(thermal_gap 0.5)
			(thermal_bridge_width 0.5)
			(island_removal_mode 0)
		)
		(polygon
			(pts
				(arc
					(start 64.213232 -160.830006)
					(mid 61.787024 -160.830006)
					(end 64.213232 -160.830006)
				)
			)
		)
	)
	(zone
		(layers "In1.Cu" "In3.Cu" "In6.Cu" "In8.Cu")
		(hatch none 0.5)
		(connect_pads
			(clearance 0)
		)
		(min_thickness 0.25)
		(keepout
			(tracks not_allowed)
			(vias allowed)
			(pads allowed)
			(copperpour not_allowed)
			(footprints allowed)
		)
		(placement
			(enabled no)
			(sheetname "")
		)
		(fill yes
			(thermal_gap 0.5)
			(thermal_bridge_width 0.5)
			(island_removal_mode 0)
		)
		(polygon
			(pts
				(arc
					(start 335.3308 -43.3578)
					(mid 333.5528 -43.3578)
					(end 335.3308 -43.3578)
				)
			)
		)
	)
	(zone
		(layers "In1.Cu" "In3.Cu" "In6.Cu" "In8.Cu")
		(hatch none 0.5)
		(connect_pads
			(clearance 0)
		)
		(min_thickness 0.25)
		(keepout
			(tracks not_allowed)
			(vias allowed)
			(pads allowed)
			(copperpour not_allowed)
			(footprints allowed)
		)
		(placement
			(enabled no)
			(sheetname "")
		)
		(fill yes
			(thermal_gap 0.5)
			(thermal_bridge_width 0.5)
			(island_removal_mode 0)
		)
		(polygon
			(pts
				(arc
					(start 333.0448 -20.8026)
					(mid 331.2668 -20.8026)
					(end 333.0448 -20.8026)
				)
			)
		)
	)
	(zone
		(layers "In1.Cu" "In3.Cu" "In6.Cu" "In8.Cu")
		(hatch none 0.5)
		(connect_pads
			(clearance 0)
		)
		(min_thickness 0.25)
		(keepout
			(tracks not_allowed)
			(vias allowed)
			(pads allowed)
			(copperpour not_allowed)
			(footprints allowed)
		)
		(placement
			(enabled no)
			(sheetname "")
		)
		(fill yes
			(thermal_gap 0.5)
			(thermal_bridge_width 0.5)
			(island_removal_mode 0)
		)
		(polygon
			(pts
				(arc
					(start 116.392452 -59.3344)
					(mid 114.614452 -59.3344)
					(end 116.392452 -59.3344)
				)
			)
		)
	)
	(zone
		(layers "In1.Cu" "In3.Cu" "In6.Cu" "In8.Cu")
		(hatch none 0.5)
		(connect_pads
			(clearance 0)
		)
		(min_thickness 0.25)
		(keepout
			(tracks not_allowed)
			(vias allowed)
			(pads allowed)
			(copperpour not_allowed)
			(footprints allowed)
		)
		(placement
			(enabled no)
			(sheetname "")
		)
		(fill yes
			(thermal_gap 0.5)
			(thermal_bridge_width 0.5)
			(island_removal_mode 0)
		)
		(polygon
			(pts
				(arc
					(start 115.630452 -50.3428)
					(mid 113.852452 -50.3428)
					(end 115.630452 -50.3428)
				)
			)
		)
	)
	(zone
		(layers "In1.Cu" "In3.Cu" "In6.Cu" "In8.Cu")
		(hatch none 0.5)
		(connect_pads
			(clearance 0)
		)
		(min_thickness 0.25)
		(keepout
			(tracks not_allowed)
			(vias allowed)
			(pads allowed)
			(copperpour not_allowed)
			(footprints allowed)
		)
		(placement
			(enabled no)
			(sheetname "")
		)
		(fill yes
			(thermal_gap 0.5)
			(thermal_bridge_width 0.5)
			(island_removal_mode 0)
		)
		(polygon
			(pts
				(arc
					(start 386.412994 -156.830014)
					(mid 383.986786 -156.830014)
					(end 386.412994 -156.830014)
				)
			)
		)
	)
	(zone
		(layers "In1.Cu" "In3.Cu" "In6.Cu" "In8.Cu")
		(hatch none 0.5)
		(connect_pads
			(clearance 0)
		)
		(min_thickness 0.25)
		(keepout
			(tracks not_allowed)
			(vias allowed)
			(pads allowed)
			(copperpour not_allowed)
			(footprints allowed)
		)
		(placement
			(enabled no)
			(sheetname "")
		)
		(fill yes
			(thermal_gap 0.5)
			(thermal_bridge_width 0.5)
			(island_removal_mode 0)
		)
		(polygon
			(pts
				(arc
					(start 334.5688 -21.5646)
					(mid 332.7908 -21.5646)
					(end 334.5688 -21.5646)
				)
			)
		)
	)
	(zone
		(layers "In1.Cu" "In3.Cu" "In6.Cu" "In8.Cu")
		(hatch none 0.5)
		(connect_pads
			(clearance 0)
		)
		(min_thickness 0.25)
		(keepout
			(tracks not_allowed)
			(vias allowed)
			(pads allowed)
			(copperpour not_allowed)
			(footprints allowed)
		)
		(placement
			(enabled no)
			(sheetname "")
		)
		(fill yes
			(thermal_gap 0.5)
			(thermal_bridge_width 0.5)
			(island_removal_mode 0)
		)
		(polygon
			(pts
				(arc
					(start 372.213124 -158.83001)
					(mid 369.786916 -158.83001)
					(end 372.213124 -158.83001)
				)
			)
		)
	)
	(zone
		(layers "In1.Cu" "In3.Cu" "In6.Cu" "In8.Cu")
		(hatch none 0.5)
		(connect_pads
			(clearance 0)
		)
		(min_thickness 0.25)
		(keepout
			(tracks not_allowed)
			(vias allowed)
			(pads allowed)
			(copperpour not_allowed)
			(footprints allowed)
		)
		(placement
			(enabled no)
			(sheetname "")
		)
		(fill yes
			(thermal_gap 0.5)
			(thermal_bridge_width 0.5)
			(island_removal_mode 0)
		)
		(polygon
			(pts
				(arc
					(start 83.566 -4.572)
					(mid 81.788 -4.572)
					(end 83.566 -4.572)
				)
			)
		)
	)
	(zone
		(layers "In1.Cu" "In3.Cu" "In6.Cu" "In8.Cu")
		(hatch none 0.5)
		(connect_pads
			(clearance 0)
		)
		(min_thickness 0.25)
		(keepout
			(tracks not_allowed)
			(vias allowed)
			(pads allowed)
			(copperpour not_allowed)
			(footprints allowed)
		)
		(placement
			(enabled no)
			(sheetname "")
		)
		(fill yes
			(thermal_gap 0.5)
			(thermal_bridge_width 0.5)
			(island_removal_mode 0)
		)
		(polygon
			(pts
				(arc
					(start 116.392452 -17.272)
					(mid 114.614452 -17.272)
					(end 116.392452 -17.272)
				)
			)
		)
	)
	(zone
		(layers "In1.Cu" "In3.Cu" "In6.Cu" "In8.Cu")
		(hatch none 0.5)
		(connect_pads
			(clearance 0)
		)
		(min_thickness 0.25)
		(keepout
			(tracks not_allowed)
			(vias allowed)
			(pads allowed)
			(copperpour not_allowed)
			(footprints allowed)
		)
		(placement
			(enabled no)
			(sheetname "")
		)
		(fill yes
			(thermal_gap 0.5)
			(thermal_bridge_width 0.5)
			(island_removal_mode 0)
		)
		(polygon
			(pts
				(arc
					(start 67.473068 -2.590038)
					(mid 65.04686 -2.590038)
					(end 67.473068 -2.590038)
				)
			)
		)
	)
	(zone
		(layers "In1.Cu" "In3.Cu" "In6.Cu" "In8.Cu")
		(hatch none 0.5)
		(connect_pads
			(clearance 0)
		)
		(min_thickness 0.25)
		(keepout
			(tracks not_allowed)
			(vias allowed)
			(pads allowed)
			(copperpour not_allowed)
			(footprints allowed)
		)
		(placement
			(enabled no)
			(sheetname "")
		)
		(fill yes
			(thermal_gap 0.5)
			(thermal_bridge_width 0.5)
			(island_removal_mode 0)
		)
		(polygon
			(pts
				(arc
					(start 36.088066 -164.829998)
					(mid 33.661858 -164.829998)
					(end 36.088066 -164.829998)
				)
			)
		)
	)
	(zone
		(layers "In1.Cu" "In3.Cu" "In6.Cu" "In8.Cu")
		(hatch none 0.5)
		(connect_pads
			(clearance 0)
		)
		(min_thickness 0.25)
		(keepout
			(tracks not_allowed)
			(vias allowed)
			(pads allowed)
			(copperpour not_allowed)
			(footprints allowed)
		)
		(placement
			(enabled no)
			(sheetname "")
		)
		(fill yes
			(thermal_gap 0.5)
			(thermal_bridge_width 0.5)
			(island_removal_mode 0)
		)
		(polygon
			(pts
				(arc
					(start 335.3308 -21.5646)
					(mid 333.5528 -21.5646)
					(end 335.3308 -21.5646)
				)
			)
		)
	)
	(zone
		(layers "In1.Cu" "In3.Cu" "In6.Cu" "In8.Cu")
		(hatch none 0.5)
		(connect_pads
			(clearance 0)
		)
		(min_thickness 0.25)
		(keepout
			(tracks not_allowed)
			(vias allowed)
			(pads allowed)
			(copperpour not_allowed)
			(footprints allowed)
		)
		(placement
			(enabled no)
			(sheetname "")
		)
		(fill yes
			(thermal_gap 0.5)
			(thermal_bridge_width 0.5)
			(island_removal_mode 0)
		)
		(polygon
			(pts
				(arc
					(start 366.213136 -156.830014)
					(mid 363.786928 -156.830014)
					(end 366.213136 -156.830014)
				)
			)
		)
	)
	(zone
		(layers "In1.Cu" "In3.Cu" "In6.Cu" "In8.Cu")
		(hatch none 0.5)
		(connect_pads
			(clearance 0)
		)
		(min_thickness 0.25)
		(keepout
			(tracks not_allowed)
			(vias allowed)
			(pads allowed)
			(copperpour not_allowed)
			(footprints allowed)
		)
		(placement
			(enabled no)
			(sheetname "")
		)
		(fill yes
			(thermal_gap 0.5)
			(thermal_bridge_width 0.5)
			(island_removal_mode 0)
		)
		(polygon
			(pts
				(arc
					(start 470.329768 -71.229982)
					(mid 467.510368 -71.229982)
					(end 470.329768 -71.229982)
				)
			)
		)
	)
	(zone
		(layers "In1.Cu" "In3.Cu" "In6.Cu" "In8.Cu")
		(hatch none 0.5)
		(connect_pads
			(clearance 0)
		)
		(min_thickness 0.25)
		(keepout
			(tracks not_allowed)
			(vias allowed)
			(pads allowed)
			(copperpour not_allowed)
			(footprints allowed)
		)
		(placement
			(enabled no)
			(sheetname "")
		)
		(fill yes
			(thermal_gap 0.5)
			(thermal_bridge_width 0.5)
			(island_removal_mode 0)
		)
		(polygon
			(pts
				(arc
					(start 62.937898 -50.919888)
					(mid 60.904882 -50.919888)
					(end 62.937898 -50.919888)
				)
			)
		)
	)
	(zone
		(layers "In1.Cu" "In3.Cu" "In6.Cu" "In8.Cu")
		(hatch none 0.5)
		(connect_pads
			(clearance 0)
		)
		(min_thickness 0.25)
		(keepout
			(tracks not_allowed)
			(vias allowed)
			(pads allowed)
			(copperpour not_allowed)
			(footprints allowed)
		)
		(placement
			(enabled no)
			(sheetname "")
		)
		(fill yes
			(thermal_gap 0.5)
			(thermal_bridge_width 0.5)
			(island_removal_mode 0)
		)
		(polygon
			(pts
				(arc
					(start 114.868452 -14.986)
					(mid 113.090452 -14.986)
					(end 114.868452 -14.986)
				)
			)
		)
	)
	(zone
		(layers "In1.Cu" "In3.Cu" "In6.Cu" "In8.Cu")
		(hatch none 0.5)
		(connect_pads
			(clearance 0)
		)
		(min_thickness 0.25)
		(keepout
			(tracks not_allowed)
			(vias allowed)
			(pads allowed)
			(copperpour not_allowed)
			(footprints allowed)
		)
		(placement
			(enabled no)
			(sheetname "")
		)
		(fill yes
			(thermal_gap 0.5)
			(thermal_bridge_width 0.5)
			(island_removal_mode 0)
		)
		(polygon
			(pts
				(arc
					(start 115.630452 -39.8272)
					(mid 113.852452 -39.8272)
					(end 115.630452 -39.8272)
				)
			)
		)
	)
	(zone
		(layers "In1.Cu" "In3.Cu" "In6.Cu" "In8.Cu")
		(hatch none 0.5)
		(connect_pads
			(clearance 0)
		)
		(min_thickness 0.25)
		(keepout
			(tracks not_allowed)
			(vias allowed)
			(pads allowed)
			(copperpour not_allowed)
			(footprints allowed)
		)
		(placement
			(enabled no)
			(sheetname "")
		)
		(fill yes
			(thermal_gap 0.5)
			(thermal_bridge_width 0.5)
			(island_removal_mode 0)
		)
		(polygon
			(pts
				(arc
					(start 114.868452 -62.3824)
					(mid 113.090452 -62.3824)
					(end 114.868452 -62.3824)
				)
			)
		)
	)
	(zone
		(layers "In1.Cu" "In3.Cu" "In6.Cu" "In8.Cu")
		(hatch none 0.5)
		(connect_pads
			(clearance 0)
		)
		(min_thickness 0.25)
		(keepout
			(tracks not_allowed)
			(vias allowed)
			(pads allowed)
			(copperpour not_allowed)
			(footprints allowed)
		)
		(placement
			(enabled no)
			(sheetname "")
		)
		(fill yes
			(thermal_gap 0.5)
			(thermal_bridge_width 0.5)
			(island_removal_mode 0)
		)
		(polygon
			(pts
				(arc
					(start 333.0448 -22.3266)
					(mid 331.2668 -22.3266)
					(end 333.0448 -22.3266)
				)
			)
		)
	)
	(zone
		(layers "In1.Cu" "In3.Cu" "In6.Cu" "In8.Cu")
		(hatch none 0.5)
		(connect_pads
			(clearance 0)
		)
		(min_thickness 0.25)
		(keepout
			(tracks not_allowed)
			(vias allowed)
			(pads allowed)
			(copperpour not_allowed)
			(footprints allowed)
		)
		(placement
			(enabled no)
			(sheetname "")
		)
		(fill yes
			(thermal_gap 0.5)
			(thermal_bridge_width 0.5)
			(island_removal_mode 0)
		)
		(polygon
			(pts
				(arc
					(start 114.106452 -14.224)
					(mid 112.328452 -14.224)
					(end 114.106452 -14.224)
				)
			)
		)
	)
	(zone
		(layers "In1.Cu" "In3.Cu" "In6.Cu" "In8.Cu")
		(hatch none 0.5)
		(connect_pads
			(clearance 0)
		)
		(min_thickness 0.25)
		(keepout
			(tracks not_allowed)
			(vias allowed)
			(pads allowed)
			(copperpour not_allowed)
			(footprints allowed)
		)
		(placement
			(enabled no)
			(sheetname "")
		)
		(fill yes
			(thermal_gap 0.5)
			(thermal_bridge_width 0.5)
			(island_removal_mode 0)
		)
		(polygon
			(pts
				(arc
					(start 334.5688 -56.9214)
					(mid 332.7908 -56.9214)
					(end 334.5688 -56.9214)
				)
			)
		)
	)
	(zone
		(layers "In1.Cu" "In3.Cu" "In6.Cu" "In8.Cu")
		(hatch none 0.5)
		(connect_pads
			(clearance 0)
		)
		(min_thickness 0.25)
		(keepout
			(tracks not_allowed)
			(vias allowed)
			(pads allowed)
			(copperpour not_allowed)
			(footprints allowed)
		)
		(placement
			(enabled no)
			(sheetname "")
		)
		(fill yes
			(thermal_gap 0.5)
			(thermal_bridge_width 0.5)
			(island_removal_mode 0)
		)
		(polygon
			(pts
				(arc
					(start 86.614 -3.81)
					(mid 84.836 -3.81)
					(end 86.614 -3.81)
				)
			)
		)
	)
	(zone
		(layers "In1.Cu" "In3.Cu" "In6.Cu" "In8.Cu")
		(hatch none 0.5)
		(connect_pads
			(clearance 0)
		)
		(min_thickness 0.25)
		(keepout
			(tracks not_allowed)
			(vias allowed)
			(pads allowed)
			(copperpour not_allowed)
			(footprints allowed)
		)
		(placement
			(enabled no)
			(sheetname "")
		)
		(fill yes
			(thermal_gap 0.5)
			(thermal_bridge_width 0.5)
			(island_removal_mode 0)
		)
		(polygon
			(pts
				(arc
					(start 36.088066 -162.830002)
					(mid 33.661858 -162.830002)
					(end 36.088066 -162.830002)
				)
			)
		)
	)
	(zone
		(layers "In1.Cu" "In3.Cu" "In6.Cu" "In8.Cu")
		(hatch none 0.5)
		(connect_pads
			(clearance 0)
		)
		(min_thickness 0.25)
		(keepout
			(tracks not_allowed)
			(vias allowed)
			(pads allowed)
			(copperpour not_allowed)
			(footprints allowed)
		)
		(placement
			(enabled no)
			(sheetname "")
		)
		(fill yes
			(thermal_gap 0.5)
			(thermal_bridge_width 0.5)
			(island_removal_mode 0)
		)
		(polygon
			(pts
				(arc
					(start 334.5688 -44.8818)
					(mid 332.7908 -44.8818)
					(end 334.5688 -44.8818)
				)
			)
		)
	)
	(zone
		(layers "In1.Cu" "In3.Cu" "In6.Cu" "In8.Cu")
		(hatch none 0.5)
		(connect_pads
			(clearance 0)
		)
		(min_thickness 0.25)
		(keepout
			(tracks not_allowed)
			(vias allowed)
			(pads allowed)
			(copperpour not_allowed)
			(footprints allowed)
		)
		(placement
			(enabled no)
			(sheetname "")
		)
		(fill yes
			(thermal_gap 0.5)
			(thermal_bridge_width 0.5)
			(island_removal_mode 0)
		)
		(polygon
			(pts
				(arc
					(start 390.412986 -160.830006)
					(mid 387.986778 -160.830006)
					(end 390.412986 -160.830006)
				)
			)
		)
	)
	(zone
		(layers "In1.Cu" "In3.Cu" "In6.Cu" "In8.Cu")
		(hatch none 0.5)
		(connect_pads
			(clearance 0)
		)
		(min_thickness 0.25)
		(keepout
			(tracks not_allowed)
			(vias allowed)
			(pads allowed)
			(copperpour not_allowed)
			(footprints allowed)
		)
		(placement
			(enabled no)
			(sheetname "")
		)
		(fill yes
			(thermal_gap 0.5)
			(thermal_bridge_width 0.5)
			(island_removal_mode 0)
		)
		(polygon
			(pts
				(arc
					(start 63.44539 -139.7)
					(mid 60.39739 -139.7)
					(end 63.44539 -139.7)
				)
			)
		)
	)
	(zone
		(layers "In1.Cu" "In3.Cu" "In6.Cu" "In8.Cu")
		(hatch none 0.5)
		(connect_pads
			(clearance 0)
		)
		(min_thickness 0.25)
		(keepout
			(tracks not_allowed)
			(vias allowed)
			(pads allowed)
			(copperpour not_allowed)
			(footprints allowed)
		)
		(placement
			(enabled no)
			(sheetname "")
		)
		(fill yes
			(thermal_gap 0.5)
			(thermal_bridge_width 0.5)
			(island_removal_mode 0)
		)
		(polygon
			(pts
				(arc
					(start 43.379898 -132.199888)
					(mid 41.346882 -132.199888)
					(end 43.379898 -132.199888)
				)
			)
		)
	)
	(zone
		(layers "In1.Cu" "In3.Cu" "In6.Cu" "In8.Cu")
		(hatch none 0.5)
		(connect_pads
			(clearance 0)
		)
		(min_thickness 0.25)
		(keepout
			(tracks not_allowed)
			(vias allowed)
			(pads allowed)
			(copperpour not_allowed)
			(footprints allowed)
		)
		(placement
			(enabled no)
			(sheetname "")
		)
		(fill yes
			(thermal_gap 0.5)
			(thermal_bridge_width 0.5)
			(island_removal_mode 0)
		)
		(polygon
			(pts
				(arc
					(start 116.392452 -73.66)
					(mid 114.614452 -73.66)
					(end 116.392452 -73.66)
				)
			)
		)
	)
	(zone
		(layers "In1.Cu" "In3.Cu" "In6.Cu" "In8.Cu")
		(hatch none 0.5)
		(connect_pads
			(clearance 0)
		)
		(min_thickness 0.25)
		(keepout
			(tracks not_allowed)
			(vias allowed)
			(pads allowed)
			(copperpour not_allowed)
			(footprints allowed)
		)
		(placement
			(enabled no)
			(sheetname "")
		)
		(fill yes
			(thermal_gap 0.5)
			(thermal_bridge_width 0.5)
			(island_removal_mode 0)
		)
		(polygon
			(pts
				(arc
					(start 114.868452 -16.51)
					(mid 113.090452 -16.51)
					(end 114.868452 -16.51)
				)
			)
		)
	)
	(zone
		(layers "In1.Cu" "In3.Cu" "In6.Cu" "In8.Cu")
		(hatch none 0.5)
		(connect_pads
			(clearance 0)
		)
		(min_thickness 0.25)
		(keepout
			(tracks not_allowed)
			(vias allowed)
			(pads allowed)
			(copperpour not_allowed)
			(footprints allowed)
		)
		(placement
			(enabled no)
			(sheetname "")
		)
		(fill yes
			(thermal_gap 0.5)
			(thermal_bridge_width 0.5)
			(island_removal_mode 0)
		)
		(polygon
			(pts
				(arc
					(start 399.588228 -160.830006)
					(mid 397.16202 -160.830006)
					(end 399.588228 -160.830006)
				)
			)
		)
	)
	(zone
		(layers "In1.Cu" "In3.Cu" "In6.Cu" "In8.Cu")
		(hatch none 0.5)
		(connect_pads
			(clearance 0)
		)
		(min_thickness 0.25)
		(keepout
			(tracks not_allowed)
			(vias allowed)
			(pads allowed)
			(copperpour not_allowed)
			(footprints allowed)
		)
		(placement
			(enabled no)
			(sheetname "")
		)
		(fill yes
			(thermal_gap 0.5)
			(thermal_bridge_width 0.5)
			(island_removal_mode 0)
		)
		(polygon
			(pts
				(arc
					(start 114.106452 -61.6204)
					(mid 112.328452 -61.6204)
					(end 114.106452 -61.6204)
				)
			)
		)
	)
	(zone
		(layers "In1.Cu" "In3.Cu" "In6.Cu" "In8.Cu")
		(hatch none 0.5)
		(connect_pads
			(clearance 0)
		)
		(min_thickness 0.25)
		(keepout
			(tracks not_allowed)
			(vias allowed)
			(pads allowed)
			(copperpour not_allowed)
			(footprints allowed)
		)
		(placement
			(enabled no)
			(sheetname "")
		)
		(fill yes
			(thermal_gap 0.5)
			(thermal_bridge_width 0.5)
			(island_removal_mode 0)
		)
		(polygon
			(pts
				(arc
					(start 356.54742 -4.591304)
					(mid 354.76942 -4.591304)
					(end 356.54742 -4.591304)
				)
			)
		)
	)
	(zone
		(layers "In1.Cu" "In3.Cu" "In6.Cu" "In8.Cu")
		(hatch none 0.5)
		(connect_pads
			(clearance 0)
		)
		(min_thickness 0.25)
		(keepout
			(tracks not_allowed)
			(vias allowed)
			(pads allowed)
			(copperpour not_allowed)
			(footprints allowed)
		)
		(placement
			(enabled no)
			(sheetname "")
		)
		(fill yes
			(thermal_gap 0.5)
			(thermal_bridge_width 0.5)
			(island_removal_mode 0)
		)
		(polygon
			(pts
				(arc
					(start 399.588228 -156.830014)
					(mid 397.16202 -156.830014)
					(end 399.588228 -156.830014)
				)
			)
		)
	)
	(zone
		(layers "In1.Cu" "In3.Cu" "In6.Cu" "In8.Cu")
		(hatch none 0.5)
		(connect_pads
			(clearance 0)
		)
		(min_thickness 0.25)
		(keepout
			(tracks not_allowed)
			(vias allowed)
			(pads allowed)
			(copperpour not_allowed)
			(footprints allowed)
		)
		(placement
			(enabled no)
			(sheetname "")
		)
		(fill yes
			(thermal_gap 0.5)
			(thermal_bridge_width 0.5)
			(island_removal_mode 0)
		)
		(polygon
			(pts
				(arc
					(start 473.029788 -73.769982)
					(mid 470.210388 -73.769982)
					(end 473.029788 -73.769982)
				)
			)
		)
	)
	(zone
		(layers "In1.Cu" "In3.Cu" "In6.Cu" "In8.Cu")
		(hatch none 0.5)
		(connect_pads
			(clearance 0)
		)
		(min_thickness 0.25)
		(keepout
			(tracks not_allowed)
			(vias allowed)
			(pads allowed)
			(copperpour not_allowed)
			(footprints allowed)
		)
		(placement
			(enabled no)
			(sheetname "")
		)
		(fill yes
			(thermal_gap 0.5)
			(thermal_bridge_width 0.5)
			(island_removal_mode 0)
		)
		(polygon
			(pts
				(arc
					(start 334.5688 -22.3266)
					(mid 332.7908 -22.3266)
					(end 334.5688 -22.3266)
				)
			)
		)
	)
	(zone
		(layers "In1.Cu" "In3.Cu" "In6.Cu" "In8.Cu")
		(hatch none 0.5)
		(connect_pads
			(clearance 0)
		)
		(min_thickness 0.25)
		(keepout
			(tracks not_allowed)
			(vias allowed)
			(pads allowed)
			(copperpour not_allowed)
			(footprints allowed)
		)
		(placement
			(enabled no)
			(sheetname "")
		)
		(fill yes
			(thermal_gap 0.5)
			(thermal_bridge_width 0.5)
			(island_removal_mode 0)
		)
		(polygon
			(pts
				(arc
					(start 333.0448 -65.913)
					(mid 331.2668 -65.913)
					(end 333.0448 -65.913)
				)
			)
		)
	)
	(zone
		(layers "In1.Cu" "In3.Cu" "In6.Cu" "In8.Cu")
		(hatch none 0.5)
		(connect_pads
			(clearance 0)
		)
		(min_thickness 0.25)
		(keepout
			(tracks not_allowed)
			(vias allowed)
			(pads allowed)
			(copperpour not_allowed)
			(footprints allowed)
		)
		(placement
			(enabled no)
			(sheetname "")
		)
		(fill yes
			(thermal_gap 0.5)
			(thermal_bridge_width 0.5)
			(island_removal_mode 0)
		)
		(polygon
			(pts
				(arc
					(start 43.88739 -119.38)
					(mid 40.83939 -119.38)
					(end 43.88739 -119.38)
				)
			)
		)
	)
	(zone
		(layers "In1.Cu" "In3.Cu" "In6.Cu" "In8.Cu")
		(hatch none 0.5)
		(connect_pads
			(clearance 0)
		)
		(min_thickness 0.25)
		(keepout
			(tracks not_allowed)
			(vias allowed)
			(pads allowed)
			(copperpour not_allowed)
			(footprints allowed)
		)
		(placement
			(enabled no)
			(sheetname "")
		)
		(fill yes
			(thermal_gap 0.5)
			(thermal_bridge_width 0.5)
			(island_removal_mode 0)
		)
		(polygon
			(pts
				(arc
					(start 333.0448 -77.1906)
					(mid 331.2668 -77.1906)
					(end 333.0448 -77.1906)
				)
			)
		)
	)
	(zone
		(layers "In1.Cu" "In3.Cu" "In6.Cu" "In8.Cu")
		(hatch none 0.5)
		(connect_pads
			(clearance 0)
		)
		(min_thickness 0.25)
		(keepout
			(tracks not_allowed)
			(vias allowed)
			(pads allowed)
			(copperpour not_allowed)
			(footprints allowed)
		)
		(placement
			(enabled no)
			(sheetname "")
		)
		(fill yes
			(thermal_gap 0.5)
			(thermal_bridge_width 0.5)
			(island_removal_mode 0)
		)
		(polygon
			(pts
				(arc
					(start 333.8068 -77.1906)
					(mid 332.0288 -77.1906)
					(end 333.8068 -77.1906)
				)
			)
		)
	)
	(zone
		(layers "In1.Cu" "In3.Cu" "In6.Cu" "In8.Cu")
		(hatch none 0.5)
		(connect_pads
			(clearance 0)
		)
		(min_thickness 0.25)
		(keepout
			(tracks not_allowed)
			(vias allowed)
			(pads allowed)
			(copperpour not_allowed)
			(footprints allowed)
		)
		(placement
			(enabled no)
			(sheetname "")
		)
		(fill yes
			(thermal_gap 0.5)
			(thermal_bridge_width 0.5)
			(island_removal_mode 0)
		)
		(polygon
			(pts
				(arc
					(start 333.8068 -34.3662)
					(mid 332.0288 -34.3662)
					(end 333.8068 -34.3662)
				)
			)
		)
	)
	(zone
		(layers "In1.Cu" "In3.Cu" "In6.Cu" "In8.Cu")
		(hatch none 0.5)
		(connect_pads
			(clearance 0)
		)
		(min_thickness 0.25)
		(keepout
			(tracks not_allowed)
			(vias allowed)
			(pads allowed)
			(copperpour not_allowed)
			(footprints allowed)
		)
		(placement
			(enabled no)
			(sheetname "")
		)
		(fill yes
			(thermal_gap 0.5)
			(thermal_bridge_width 0.5)
			(island_removal_mode 0)
		)
		(polygon
			(pts
				(arc
					(start 336.0928 -56.9214)
					(mid 334.3148 -56.9214)
					(end 336.0928 -56.9214)
				)
			)
		)
	)
	(zone
		(layers "In1.Cu" "In3.Cu" "In6.Cu" "In8.Cu")
		(hatch none 0.5)
		(connect_pads
			(clearance 0)
		)
		(min_thickness 0.25)
		(keepout
			(tracks not_allowed)
			(vias allowed)
			(pads allowed)
			(copperpour not_allowed)
			(footprints allowed)
		)
		(placement
			(enabled no)
			(sheetname "")
		)
		(fill yes
			(thermal_gap 0.5)
			(thermal_bridge_width 0.5)
			(island_removal_mode 0)
		)
		(polygon
			(pts
				(arc
					(start 56.013096 -158.83001)
					(mid 53.586888 -158.83001)
					(end 56.013096 -158.83001)
				)
			)
		)
	)
	(zone
		(layers "In1.Cu" "In3.Cu" "In6.Cu" "In8.Cu")
		(hatch none 0.5)
		(connect_pads
			(clearance 0)
		)
		(min_thickness 0.25)
		(keepout
			(tracks not_allowed)
			(vias allowed)
			(pads allowed)
			(copperpour not_allowed)
			(footprints allowed)
		)
		(placement
			(enabled no)
			(sheetname "")
		)
		(fill yes
			(thermal_gap 0.5)
			(thermal_bridge_width 0.5)
			(island_removal_mode 0)
		)
		(polygon
			(pts
				(arc
					(start 333.0448 -65.151)
					(mid 331.2668 -65.151)
					(end 333.0448 -65.151)
				)
			)
		)
	)
	(zone
		(layers "In1.Cu" "In3.Cu" "In6.Cu" "In8.Cu")
		(hatch none 0.5)
		(connect_pads
			(clearance 0)
		)
		(min_thickness 0.25)
		(keepout
			(tracks not_allowed)
			(vias allowed)
			(pads allowed)
			(copperpour not_allowed)
			(footprints allowed)
		)
		(placement
			(enabled no)
			(sheetname "")
		)
		(fill yes
			(thermal_gap 0.5)
			(thermal_bridge_width 0.5)
			(island_removal_mode 0)
		)
		(polygon
			(pts
				(arc
					(start 356.54742 -5.353304)
					(mid 354.76942 -5.353304)
					(end 356.54742 -5.353304)
				)
			)
		)
	)
	(zone
		(layers "In1.Cu" "In3.Cu" "In6.Cu" "In8.Cu")
		(hatch none 0.5)
		(connect_pads
			(clearance 0)
		)
		(min_thickness 0.25)
		(keepout
			(tracks not_allowed)
			(vias allowed)
			(pads allowed)
			(copperpour not_allowed)
			(footprints allowed)
		)
		(placement
			(enabled no)
			(sheetname "")
		)
		(fill yes
			(thermal_gap 0.5)
			(thermal_bridge_width 0.5)
			(island_removal_mode 0)
		)
		(polygon
			(pts
				(arc
					(start 62.937898 -71.239888)
					(mid 60.904882 -71.239888)
					(end 62.937898 -71.239888)
				)
			)
		)
	)
	(zone
		(layers "In1.Cu" "In3.Cu" "In6.Cu" "In8.Cu")
		(hatch none 0.5)
		(connect_pads
			(clearance 0)
		)
		(min_thickness 0.25)
		(keepout
			(tracks not_allowed)
			(vias allowed)
			(pads allowed)
			(copperpour not_allowed)
			(footprints allowed)
		)
		(placement
			(enabled no)
			(sheetname "")
		)
		(fill yes
			(thermal_gap 0.5)
			(thermal_bridge_width 0.5)
			(island_removal_mode 0)
		)
		(polygon
			(pts
				(arc
					(start 114.868452 -51.1048)
					(mid 113.090452 -51.1048)
					(end 114.868452 -51.1048)
				)
			)
		)
	)
	(zone
		(layers "In1.Cu" "In3.Cu" "In6.Cu" "In8.Cu")
		(hatch none 0.5)
		(connect_pads
			(clearance 0)
		)
		(min_thickness 0.25)
		(keepout
			(tracks not_allowed)
			(vias allowed)
			(pads allowed)
			(copperpour not_allowed)
			(footprints allowed)
		)
		(placement
			(enabled no)
			(sheetname "")
		)
		(fill yes
			(thermal_gap 0.5)
			(thermal_bridge_width 0.5)
			(island_removal_mode 0)
		)
		(polygon
			(pts
				(arc
					(start 115.630452 -15.748)
					(mid 113.852452 -15.748)
					(end 115.630452 -15.748)
				)
			)
		)
	)
	(zone
		(layers "In1.Cu" "In3.Cu" "In6.Cu" "In8.Cu")
		(hatch none 0.5)
		(connect_pads
			(clearance 0)
		)
		(min_thickness 0.25)
		(keepout
			(tracks not_allowed)
			(vias allowed)
			(pads allowed)
			(copperpour not_allowed)
			(footprints allowed)
		)
		(placement
			(enabled no)
			(sheetname "")
		)
		(fill yes
			(thermal_gap 0.5)
			(thermal_bridge_width 0.5)
			(island_removal_mode 0)
		)
		(polygon
			(pts
				(arc
					(start 114.868452 -72.136)
					(mid 113.090452 -72.136)
					(end 114.868452 -72.136)
				)
			)
		)
	)
	(zone
		(layers "In1.Cu" "In3.Cu" "In6.Cu" "In8.Cu")
		(hatch none 0.5)
		(connect_pads
			(clearance 0)
		)
		(min_thickness 0.25)
		(keepout
			(tracks not_allowed)
			(vias allowed)
			(pads allowed)
			(copperpour not_allowed)
			(footprints allowed)
		)
		(placement
			(enabled no)
			(sheetname "")
		)
		(fill yes
			(thermal_gap 0.5)
			(thermal_bridge_width 0.5)
			(island_removal_mode 0)
		)
		(polygon
			(pts
				(arc
					(start 114.868452 -39.0652)
					(mid 113.090452 -39.0652)
					(end 114.868452 -39.0652)
				)
			)
		)
	)
	(zone
		(layers "In1.Cu" "In3.Cu" "In6.Cu" "In8.Cu")
		(hatch none 0.5)
		(connect_pads
			(clearance 0)
		)
		(min_thickness 0.25)
		(keepout
			(tracks not_allowed)
			(vias allowed)
			(pads allowed)
			(copperpour not_allowed)
			(footprints allowed)
		)
		(placement
			(enabled no)
			(sheetname "")
		)
		(fill yes
			(thermal_gap 0.5)
			(thermal_bridge_width 0.5)
			(island_removal_mode 0)
		)
		(polygon
			(pts
				(arc
					(start 52.013104 -160.830006)
					(mid 49.586896 -160.830006)
					(end 52.013104 -160.830006)
				)
			)
		)
	)
	(zone
		(layers "In1.Cu" "In3.Cu" "In6.Cu" "In8.Cu")
		(hatch none 0.5)
		(connect_pads
			(clearance 0)
		)
		(min_thickness 0.25)
		(keepout
			(tracks not_allowed)
			(vias allowed)
			(pads allowed)
			(copperpour not_allowed)
			(footprints allowed)
		)
		(placement
			(enabled no)
			(sheetname "")
		)
		(fill yes
			(thermal_gap 0.5)
			(thermal_bridge_width 0.5)
			(island_removal_mode 0)
		)
		(polygon
			(pts
				(arc
					(start 333.0448 -45.6438)
					(mid 331.2668 -45.6438)
					(end 333.0448 -45.6438)
				)
			)
		)
	)
	(zone
		(layers "In1.Cu" "In3.Cu" "In6.Cu" "In8.Cu")
		(hatch none 0.5)
		(connect_pads
			(clearance 0)
		)
		(min_thickness 0.25)
		(keepout
			(tracks not_allowed)
			(vias allowed)
			(pads allowed)
			(copperpour not_allowed)
			(footprints allowed)
		)
		(placement
			(enabled no)
			(sheetname "")
		)
		(fill yes
			(thermal_gap 0.5)
			(thermal_bridge_width 0.5)
			(island_removal_mode 0)
		)
		(polygon
			(pts
				(arc
					(start 114.868452 -59.3344)
					(mid 113.090452 -59.3344)
					(end 114.868452 -59.3344)
				)
			)
		)
	)
	(zone
		(layers "In1.Cu" "In3.Cu" "In6.Cu" "In8.Cu")
		(hatch none 0.5)
		(connect_pads
			(clearance 0)
		)
		(min_thickness 0.25)
		(keepout
			(tracks not_allowed)
			(vias allowed)
			(pads allowed)
			(copperpour not_allowed)
			(footprints allowed)
		)
		(placement
			(enabled no)
			(sheetname "")
		)
		(fill yes
			(thermal_gap 0.5)
			(thermal_bridge_width 0.5)
			(island_removal_mode 0)
		)
		(polygon
			(pts
				(arc
					(start 114.106452 -73.66)
					(mid 112.328452 -73.66)
					(end 114.106452 -73.66)
				)
			)
		)
	)
	(zone
		(layers "In1.Cu" "In3.Cu" "In6.Cu" "In8.Cu")
		(hatch none 0.5)
		(connect_pads
			(clearance 0)
		)
		(min_thickness 0.25)
		(keepout
			(tracks not_allowed)
			(vias allowed)
			(pads allowed)
			(copperpour not_allowed)
			(footprints allowed)
		)
		(placement
			(enabled no)
			(sheetname "")
		)
		(fill yes
			(thermal_gap 0.5)
			(thermal_bridge_width 0.5)
			(island_removal_mode 0)
		)
		(polygon
			(pts
				(arc
					(start 336.0928 -33.6042)
					(mid 334.3148 -33.6042)
					(end 336.0928 -33.6042)
				)
			)
		)
	)
	(zone
		(layers "In1.Cu" "In3.Cu" "In6.Cu" "In8.Cu")
		(hatch none 0.5)
		(connect_pads
			(clearance 0)
		)
		(min_thickness 0.25)
		(keepout
			(tracks not_allowed)
			(vias allowed)
			(pads allowed)
			(copperpour not_allowed)
			(footprints allowed)
		)
		(placement
			(enabled no)
			(sheetname "")
		)
		(fill yes
			(thermal_gap 0.5)
			(thermal_bridge_width 0.5)
			(island_removal_mode 0)
		)
		(polygon
			(pts
				(arc
					(start 336.0928 -22.3266)
					(mid 334.3148 -22.3266)
					(end 336.0928 -22.3266)
				)
			)
		)
	)
	(zone
		(layers "In1.Cu" "In3.Cu" "In6.Cu" "In8.Cu")
		(hatch none 0.5)
		(connect_pads
			(clearance 0)
		)
		(min_thickness 0.25)
		(keepout
			(tracks not_allowed)
			(vias allowed)
			(pads allowed)
			(copperpour not_allowed)
			(footprints allowed)
		)
		(placement
			(enabled no)
			(sheetname "")
		)
		(fill yes
			(thermal_gap 0.5)
			(thermal_bridge_width 0.5)
			(island_removal_mode 0)
		)
		(polygon
			(pts
				(arc
					(start 379.603 -58.42)
					(mid 376.555 -58.42)
					(end 379.603 -58.42)
				)
			)
		)
	)
	(zone
		(layers "In1.Cu" "In3.Cu" "In6.Cu" "In8.Cu")
		(hatch none 0.5)
		(connect_pads
			(clearance 0)
		)
		(min_thickness 0.25)
		(keepout
			(tracks not_allowed)
			(vias allowed)
			(pads allowed)
			(copperpour not_allowed)
			(footprints allowed)
		)
		(placement
			(enabled no)
			(sheetname "")
		)
		(fill yes
			(thermal_gap 0.5)
			(thermal_bridge_width 0.5)
			(island_removal_mode 0)
		)
		(polygon
			(pts
				(arc
					(start 43.88739 -78.74)
					(mid 40.83939 -78.74)
					(end 43.88739 -78.74)
				)
			)
		)
	)
	(zone
		(layers "In1.Cu" "In3.Cu" "In6.Cu" "In8.Cu")
		(hatch none 0.5)
		(connect_pads
			(clearance 0)
		)
		(min_thickness 0.25)
		(keepout
			(tracks not_allowed)
			(vias allowed)
			(pads allowed)
			(copperpour not_allowed)
			(footprints allowed)
		)
		(placement
			(enabled no)
			(sheetname "")
		)
		(fill yes
			(thermal_gap 0.5)
			(thermal_bridge_width 0.5)
			(island_removal_mode 0)
		)
		(polygon
			(pts
				(arc
					(start 114.868452 -71.374)
					(mid 113.090452 -71.374)
					(end 114.868452 -71.374)
				)
			)
		)
	)
	(zone
		(layers "In1.Cu" "In3.Cu" "In6.Cu" "In8.Cu")
		(hatch none 0.5)
		(connect_pads
			(clearance 0)
		)
		(min_thickness 0.25)
		(keepout
			(tracks not_allowed)
			(vias allowed)
			(pads allowed)
			(copperpour not_allowed)
			(footprints allowed)
		)
		(placement
			(enabled no)
			(sheetname "")
		)
		(fill yes
			(thermal_gap 0.5)
			(thermal_bridge_width 0.5)
			(island_removal_mode 0)
		)
		(polygon
			(pts
				(arc
					(start 114.106452 -51.1048)
					(mid 112.328452 -51.1048)
					(end 114.106452 -51.1048)
				)
			)
		)
	)
	(zone
		(layers "In1.Cu" "In3.Cu" "In6.Cu" "In8.Cu")
		(hatch none 0.5)
		(connect_pads
			(clearance 0)
		)
		(min_thickness 0.25)
		(keepout
			(tracks not_allowed)
			(vias allowed)
			(pads allowed)
			(copperpour not_allowed)
			(footprints allowed)
		)
		(placement
			(enabled no)
			(sheetname "")
		)
		(fill yes
			(thermal_gap 0.5)
			(thermal_bridge_width 0.5)
			(island_removal_mode 0)
		)
		(polygon
			(pts
				(arc
					(start 116.392452 -15.748)
					(mid 114.614452 -15.748)
					(end 116.392452 -15.748)
				)
			)
		)
	)
	(zone
		(layers "In1.Cu" "In3.Cu" "In6.Cu" "In8.Cu")
		(hatch none 0.5)
		(connect_pads
			(clearance 0)
		)
		(min_thickness 0.25)
		(keepout
			(tracks not_allowed)
			(vias allowed)
			(pads allowed)
			(copperpour not_allowed)
			(footprints allowed)
		)
		(placement
			(enabled no)
			(sheetname "")
		)
		(fill yes
			(thermal_gap 0.5)
			(thermal_bridge_width 0.5)
			(island_removal_mode 0)
		)
		(polygon
			(pts
				(arc
					(start 359.59542 -5.353304)
					(mid 357.81742 -5.353304)
					(end 359.59542 -5.353304)
				)
			)
		)
	)
	(zone
		(layers "In1.Cu" "In3.Cu" "In6.Cu" "In8.Cu")
		(hatch none 0.5)
		(connect_pads
			(clearance 0)
		)
		(min_thickness 0.25)
		(keepout
			(tracks not_allowed)
			(vias allowed)
			(pads allowed)
			(copperpour not_allowed)
			(footprints allowed)
		)
		(placement
			(enabled no)
			(sheetname "")
		)
		(fill yes
			(thermal_gap 0.5)
			(thermal_bridge_width 0.5)
			(island_removal_mode 0)
		)
		(polygon
			(pts
				(arc
					(start 372.213124 -156.830014)
					(mid 369.786916 -156.830014)
					(end 372.213124 -156.830014)
				)
			)
		)
	)
	(zone
		(layers "In1.Cu" "In3.Cu" "In6.Cu" "In8.Cu")
		(hatch none 0.5)
		(connect_pads
			(clearance 0)
		)
		(min_thickness 0.25)
		(keepout
			(tracks not_allowed)
			(vias allowed)
			(pads allowed)
			(copperpour not_allowed)
			(footprints allowed)
		)
		(placement
			(enabled no)
			(sheetname "")
		)
		(fill yes
			(thermal_gap 0.5)
			(thermal_bridge_width 0.5)
			(island_removal_mode 0)
		)
		(polygon
			(pts
				(arc
					(start 114.106452 -27.0256)
					(mid 112.328452 -27.0256)
					(end 114.106452 -27.0256)
				)
			)
		)
	)
	(zone
		(layers "In1.Cu" "In3.Cu" "In6.Cu" "In8.Cu")
		(hatch none 0.5)
		(connect_pads
			(clearance 0)
		)
		(min_thickness 0.25)
		(keepout
			(tracks not_allowed)
			(vias allowed)
			(pads allowed)
			(copperpour not_allowed)
			(footprints allowed)
		)
		(placement
			(enabled no)
			(sheetname "")
		)
		(fill yes
			(thermal_gap 0.5)
			(thermal_bridge_width 0.5)
			(island_removal_mode 0)
		)
		(polygon
			(pts
				(arc
					(start 333.8068 -43.3578)
					(mid 332.0288 -43.3578)
					(end 333.8068 -43.3578)
				)
			)
		)
	)
	(zone
		(layers "In1.Cu" "In3.Cu" "In6.Cu" "In8.Cu")
		(hatch none 0.5)
		(connect_pads
			(clearance 0)
		)
		(min_thickness 0.25)
		(keepout
			(tracks not_allowed)
			(vias allowed)
			(pads allowed)
			(copperpour not_allowed)
			(footprints allowed)
		)
		(placement
			(enabled no)
			(sheetname "")
		)
		(fill yes
			(thermal_gap 0.5)
			(thermal_bridge_width 0.5)
			(island_removal_mode 0)
		)
		(polygon
			(pts
				(arc
					(start 334.5688 -68.199)
					(mid 332.7908 -68.199)
					(end 334.5688 -68.199)
				)
			)
		)
	)
	(zone
		(layers "In1.Cu" "In3.Cu" "In6.Cu" "In8.Cu")
		(hatch none 0.5)
		(connect_pads
			(clearance 0)
		)
		(min_thickness 0.25)
		(keepout
			(tracks not_allowed)
			(vias allowed)
			(pads allowed)
			(copperpour not_allowed)
			(footprints allowed)
		)
		(placement
			(enabled no)
			(sheetname "")
		)
		(fill yes
			(thermal_gap 0.5)
			(thermal_bridge_width 0.5)
			(island_removal_mode 0)
		)
		(polygon
			(pts
				(arc
					(start 58.013092 -158.83001)
					(mid 55.586884 -158.83001)
					(end 58.013092 -158.83001)
				)
			)
		)
	)
	(zone
		(layers "In1.Cu" "In3.Cu" "In6.Cu" "In8.Cu")
		(hatch none 0.5)
		(connect_pads
			(clearance 0)
		)
		(min_thickness 0.25)
		(keepout
			(tracks not_allowed)
			(vias allowed)
			(pads allowed)
			(copperpour not_allowed)
			(footprints allowed)
		)
		(placement
			(enabled no)
			(sheetname "")
		)
		(fill yes
			(thermal_gap 0.5)
			(thermal_bridge_width 0.5)
			(island_removal_mode 0)
		)
		(polygon
			(pts
				(arc
					(start 38.088062 -156.830014)
					(mid 35.661854 -156.830014)
					(end 38.088062 -156.830014)
				)
			)
		)
	)
	(zone
		(layers "In1.Cu" "In3.Cu" "In6.Cu" "In8.Cu")
		(hatch none 0.5)
		(connect_pads
			(clearance 0)
		)
		(min_thickness 0.25)
		(keepout
			(tracks not_allowed)
			(vias allowed)
			(pads allowed)
			(copperpour not_allowed)
			(footprints allowed)
		)
		(placement
			(enabled no)
			(sheetname "")
		)
		(fill yes
			(thermal_gap 0.5)
			(thermal_bridge_width 0.5)
			(island_removal_mode 0)
		)
		(polygon
			(pts
				(arc
					(start 114.106452 -38.3032)
					(mid 112.328452 -38.3032)
					(end 114.106452 -38.3032)
				)
			)
		)
	)
	(zone
		(layers "In1.Cu" "In3.Cu" "In6.Cu" "In8.Cu")
		(hatch none 0.5)
		(connect_pads
			(clearance 0)
		)
		(min_thickness 0.25)
		(keepout
			(tracks not_allowed)
			(vias allowed)
			(pads allowed)
			(copperpour not_allowed)
			(footprints allowed)
		)
		(placement
			(enabled no)
			(sheetname "")
		)
		(fill yes
			(thermal_gap 0.5)
			(thermal_bridge_width 0.5)
			(island_removal_mode 0)
		)
		(polygon
			(pts
				(arc
					(start 336.0928 -68.199)
					(mid 334.3148 -68.199)
					(end 336.0928 -68.199)
				)
			)
		)
	)
	(zone
		(layers "In1.Cu" "In3.Cu" "In6.Cu" "In8.Cu")
		(hatch none 0.5)
		(connect_pads
			(clearance 0)
		)
		(min_thickness 0.25)
		(keepout
			(tracks not_allowed)
			(vias allowed)
			(pads allowed)
			(copperpour not_allowed)
			(footprints allowed)
		)
		(placement
			(enabled no)
			(sheetname "")
		)
		(fill yes
			(thermal_gap 0.5)
			(thermal_bridge_width 0.5)
			(island_removal_mode 0)
		)
		(polygon
			(pts
				(arc
					(start 378.213112 -160.830006)
					(mid 375.786904 -160.830006)
					(end 378.213112 -160.830006)
				)
			)
		)
	)
	(zone
		(layers "In1.Cu" "In3.Cu" "In6.Cu" "In8.Cu")
		(hatch none 0.5)
		(connect_pads
			(clearance 0)
		)
		(min_thickness 0.25)
		(keepout
			(tracks not_allowed)
			(vias allowed)
			(pads allowed)
			(copperpour not_allowed)
			(footprints allowed)
		)
		(placement
			(enabled no)
			(sheetname "")
		)
		(fill yes
			(thermal_gap 0.5)
			(thermal_bridge_width 0.5)
			(island_removal_mode 0)
		)
		(polygon
			(pts
				(arc
					(start 114.106452 -27.7876)
					(mid 112.328452 -27.7876)
					(end 114.106452 -27.7876)
				)
			)
		)
	)
	(zone
		(layers "In1.Cu" "In3.Cu" "In6.Cu" "In8.Cu")
		(hatch none 0.5)
		(connect_pads
			(clearance 0)
		)
		(min_thickness 0.25)
		(keepout
			(tracks not_allowed)
			(vias allowed)
			(pads allowed)
			(copperpour not_allowed)
			(footprints allowed)
		)
		(placement
			(enabled no)
			(sheetname "")
		)
		(fill yes
			(thermal_gap 0.5)
			(thermal_bridge_width 0.5)
			(island_removal_mode 0)
		)
		(polygon
			(pts
				(arc
					(start 58.013092 -156.830014)
					(mid 55.586884 -156.830014)
					(end 58.013092 -156.830014)
				)
			)
		)
	)
	(zone
		(layers "In1.Cu" "In3.Cu" "In6.Cu" "In8.Cu")
		(hatch none 0.5)
		(connect_pads
			(clearance 0)
		)
		(min_thickness 0.25)
		(keepout
			(tracks not_allowed)
			(vias allowed)
			(pads allowed)
			(copperpour not_allowed)
			(footprints allowed)
		)
		(placement
			(enabled no)
			(sheetname "")
		)
		(fill yes
			(thermal_gap 0.5)
			(thermal_bridge_width 0.5)
			(island_removal_mode 0)
		)
		(polygon
			(pts
				(arc
					(start 335.3308 -32.0802)
					(mid 333.5528 -32.0802)
					(end 335.3308 -32.0802)
				)
			)
		)
	)
	(zone
		(layers "In1.Cu" "In3.Cu" "In6.Cu" "In8.Cu")
		(hatch none 0.5)
		(connect_pads
			(clearance 0)
		)
		(min_thickness 0.25)
		(keepout
			(tracks not_allowed)
			(vias allowed)
			(pads allowed)
			(copperpour not_allowed)
			(footprints allowed)
		)
		(placement
			(enabled no)
			(sheetname "")
		)
		(fill yes
			(thermal_gap 0.5)
			(thermal_bridge_width 0.5)
			(island_removal_mode 0)
		)
		(polygon
			(pts
				(arc
					(start 116.392452 -48.0568)
					(mid 114.614452 -48.0568)
					(end 116.392452 -48.0568)
				)
			)
		)
	)
	(zone
		(layers "In1.Cu" "In3.Cu" "In6.Cu" "In8.Cu")
		(hatch none 0.5)
		(connect_pads
			(clearance 0)
		)
		(min_thickness 0.25)
		(keepout
			(tracks not_allowed)
			(vias allowed)
			(pads allowed)
			(copperpour not_allowed)
			(footprints allowed)
		)
		(placement
			(enabled no)
			(sheetname "")
		)
		(fill yes
			(thermal_gap 0.5)
			(thermal_bridge_width 0.5)
			(island_removal_mode 0)
		)
		(polygon
			(pts
				(arc
					(start 116.392452 -51.1048)
					(mid 114.614452 -51.1048)
					(end 116.392452 -51.1048)
				)
			)
		)
	)
	(zone
		(layers "In1.Cu" "In3.Cu" "In6.Cu" "In8.Cu")
		(hatch none 0.5)
		(connect_pads
			(clearance 0)
		)
		(min_thickness 0.25)
		(keepout
			(tracks not_allowed)
			(vias allowed)
			(pads allowed)
			(copperpour not_allowed)
			(footprints allowed)
		)
		(placement
			(enabled no)
			(sheetname "")
		)
		(fill yes
			(thermal_gap 0.5)
			(thermal_bridge_width 0.5)
			(island_removal_mode 0)
		)
		(polygon
			(pts
				(arc
					(start 335.3308 -68.199)
					(mid 333.5528 -68.199)
					(end 335.3308 -68.199)
				)
			)
		)
	)
	(zone
		(layers "In1.Cu" "In3.Cu" "In6.Cu" "In8.Cu")
		(hatch none 0.5)
		(connect_pads
			(clearance 0)
		)
		(min_thickness 0.25)
		(keepout
			(tracks not_allowed)
			(vias allowed)
			(pads allowed)
			(copperpour not_allowed)
			(footprints allowed)
		)
		(placement
			(enabled no)
			(sheetname "")
		)
		(fill yes
			(thermal_gap 0.5)
			(thermal_bridge_width 0.5)
			(island_removal_mode 0)
		)
		(polygon
			(pts
				(arc
					(start 386.412994 -158.83001)
					(mid 383.986786 -158.83001)
					(end 386.412994 -158.83001)
				)
			)
		)
	)
	(zone
		(layers "In1.Cu" "In3.Cu" "In6.Cu" "In8.Cu")
		(hatch none 0.5)
		(connect_pads
			(clearance 0)
		)
		(min_thickness 0.25)
		(keepout
			(tracks not_allowed)
			(vias allowed)
			(pads allowed)
			(copperpour not_allowed)
			(footprints allowed)
		)
		(placement
			(enabled no)
			(sheetname "")
		)
		(fill yes
			(thermal_gap 0.5)
			(thermal_bridge_width 0.5)
			(island_removal_mode 0)
		)
		(polygon
			(pts
				(arc
					(start 335.3308 -33.6042)
					(mid 333.5528 -33.6042)
					(end 335.3308 -33.6042)
				)
			)
		)
	)
	(zone
		(layers "In1.Cu" "In3.Cu" "In6.Cu" "In8.Cu")
		(hatch none 0.5)
		(connect_pads
			(clearance 0)
		)
		(min_thickness 0.25)
		(keepout
			(tracks not_allowed)
			(vias allowed)
			(pads allowed)
			(copperpour not_allowed)
			(footprints allowed)
		)
		(placement
			(enabled no)
			(sheetname "")
		)
		(fill yes
			(thermal_gap 0.5)
			(thermal_bridge_width 0.5)
			(island_removal_mode 0)
		)
		(polygon
			(pts
				(arc
					(start 116.392452 -28.5496)
					(mid 114.614452 -28.5496)
					(end 116.392452 -28.5496)
				)
			)
		)
	)
	(zone
		(layers "In1.Cu" "In3.Cu" "In6.Cu" "In8.Cu")
		(hatch none 0.5)
		(connect_pads
			(clearance 0)
		)
		(min_thickness 0.25)
		(keepout
			(tracks not_allowed)
			(vias allowed)
			(pads allowed)
			(copperpour not_allowed)
			(footprints allowed)
		)
		(placement
			(enabled no)
			(sheetname "")
		)
		(fill yes
			(thermal_gap 0.5)
			(thermal_bridge_width 0.5)
			(island_removal_mode 0)
		)
		(polygon
			(pts
				(arc
					(start 358.07142 -5.353304)
					(mid 356.29342 -5.353304)
					(end 358.07142 -5.353304)
				)
			)
		)
	)
	(zone
		(layers "In1.Cu" "In3.Cu" "In6.Cu" "In8.Cu")
		(hatch none 0.5)
		(connect_pads
			(clearance 0)
		)
		(min_thickness 0.25)
		(keepout
			(tracks not_allowed)
			(vias allowed)
			(pads allowed)
			(copperpour not_allowed)
			(footprints allowed)
		)
		(placement
			(enabled no)
			(sheetname "")
		)
		(fill yes
			(thermal_gap 0.5)
			(thermal_bridge_width 0.5)
			(island_removal_mode 0)
		)
		(polygon
			(pts
				(arc
					(start 113.344452 -38.3032)
					(mid 111.566452 -38.3032)
					(end 113.344452 -38.3032)
				)
			)
		)
	)
	(zone
		(layers "In1.Cu" "In3.Cu" "In6.Cu" "In8.Cu")
		(hatch none 0.5)
		(connect_pads
			(clearance 0)
		)
		(min_thickness 0.25)
		(keepout
			(tracks not_allowed)
			(vias allowed)
			(pads allowed)
			(copperpour not_allowed)
			(footprints allowed)
		)
		(placement
			(enabled no)
			(sheetname "")
		)
		(fill yes
			(thermal_gap 0.5)
			(thermal_bridge_width 0.5)
			(island_removal_mode 0)
		)
		(polygon
			(pts
				(arc
					(start 333.8068 -23.0886)
					(mid 332.0288 -23.0886)
					(end 333.8068 -23.0886)
				)
			)
		)
	)
	(zone
		(layers "In1.Cu" "In3.Cu" "In6.Cu" "In8.Cu")
		(hatch none 0.5)
		(connect_pads
			(clearance 0)
		)
		(min_thickness 0.25)
		(keepout
			(tracks not_allowed)
			(vias allowed)
			(pads allowed)
			(copperpour not_allowed)
			(footprints allowed)
		)
		(placement
			(enabled no)
			(sheetname "")
		)
		(fill yes
			(thermal_gap 0.5)
			(thermal_bridge_width 0.5)
			(island_removal_mode 0)
		)
		(polygon
			(pts
				(arc
					(start 359.59542 -3.829304)
					(mid 357.81742 -3.829304)
					(end 359.59542 -3.829304)
				)
			)
		)
	)
	(zone
		(layers "In1.Cu" "In3.Cu" "In6.Cu" "In8.Cu")
		(hatch none 0.5)
		(connect_pads
			(clearance 0)
		)
		(min_thickness 0.25)
		(keepout
			(tracks not_allowed)
			(vias allowed)
			(pads allowed)
			(copperpour not_allowed)
			(footprints allowed)
		)
		(placement
			(enabled no)
			(sheetname "")
		)
		(fill yes
			(thermal_gap 0.5)
			(thermal_bridge_width 0.5)
			(island_removal_mode 0)
		)
		(polygon
			(pts
				(arc
					(start 36.088066 -158.83001)
					(mid 33.661858 -158.83001)
					(end 36.088066 -158.83001)
				)
			)
		)
	)
	(zone
		(layers "In1.Cu" "In3.Cu" "In6.Cu" "In8.Cu")
		(hatch none 0.5)
		(connect_pads
			(clearance 0)
		)
		(min_thickness 0.25)
		(keepout
			(tracks not_allowed)
			(vias allowed)
			(pads allowed)
			(copperpour not_allowed)
			(footprints allowed)
		)
		(placement
			(enabled no)
			(sheetname "")
		)
		(fill yes
			(thermal_gap 0.5)
			(thermal_bridge_width 0.5)
			(island_removal_mode 0)
		)
		(polygon
			(pts
				(arc
					(start 87.376 -3.81)
					(mid 85.598 -3.81)
					(end 87.376 -3.81)
				)
			)
		)
	)
	(zone
		(layers "In1.Cu" "In3.Cu" "In6.Cu" "In8.Cu")
		(hatch none 0.5)
		(connect_pads
			(clearance 0)
		)
		(min_thickness 0.25)
		(keepout
			(tracks not_allowed)
			(vias allowed)
			(pads allowed)
			(copperpour not_allowed)
			(footprints allowed)
		)
		(placement
			(enabled no)
			(sheetname "")
		)
		(fill yes
			(thermal_gap 0.5)
			(thermal_bridge_width 0.5)
			(island_removal_mode 0)
		)
		(polygon
			(pts
				(arc
					(start 116.392452 -60.8584)
					(mid 114.614452 -60.8584)
					(end 116.392452 -60.8584)
				)
			)
		)
	)
	(zone
		(layers "In1.Cu" "In3.Cu" "In6.Cu" "In8.Cu")
		(hatch none 0.5)
		(connect_pads
			(clearance 0)
		)
		(min_thickness 0.25)
		(keepout
			(tracks not_allowed)
			(vias allowed)
			(pads allowed)
			(copperpour not_allowed)
			(footprints allowed)
		)
		(placement
			(enabled no)
			(sheetname "")
		)
		(fill yes
			(thermal_gap 0.5)
			(thermal_bridge_width 0.5)
			(island_removal_mode 0)
		)
		(polygon
			(pts
				(arc
					(start 114.106452 -17.272)
					(mid 112.328452 -17.272)
					(end 114.106452 -17.272)
				)
			)
		)
	)
	(zone
		(layers "In1.Cu" "In3.Cu" "In6.Cu" "In8.Cu")
		(hatch none 0.5)
		(connect_pads
			(clearance 0)
		)
		(min_thickness 0.25)
		(keepout
			(tracks not_allowed)
			(vias allowed)
			(pads allowed)
			(copperpour not_allowed)
			(footprints allowed)
		)
		(placement
			(enabled no)
			(sheetname "")
		)
		(fill yes
			(thermal_gap 0.5)
			(thermal_bridge_width 0.5)
			(island_removal_mode 0)
		)
		(polygon
			(pts
				(arc
					(start 38.088062 -164.829998)
					(mid 35.661854 -164.829998)
					(end 38.088062 -164.829998)
				)
			)
		)
	)
	(zone
		(layers "In1.Cu" "In3.Cu" "In6.Cu" "In8.Cu")
		(hatch none 0.5)
		(connect_pads
			(clearance 0)
		)
		(min_thickness 0.25)
		(keepout
			(tracks not_allowed)
			(vias allowed)
			(pads allowed)
			(copperpour not_allowed)
			(footprints allowed)
		)
		(placement
			(enabled no)
			(sheetname "")
		)
		(fill yes
			(thermal_gap 0.5)
			(thermal_bridge_width 0.5)
			(island_removal_mode 0)
		)
		(polygon
			(pts
				(arc
					(start 336.0928 -65.151)
					(mid 334.3148 -65.151)
					(end 336.0928 -65.151)
				)
			)
		)
	)
	(zone
		(layers "In1.Cu" "In3.Cu" "In6.Cu" "In8.Cu")
		(hatch none 0.5)
		(connect_pads
			(clearance 0)
		)
		(min_thickness 0.25)
		(keepout
			(tracks not_allowed)
			(vias allowed)
			(pads allowed)
			(copperpour not_allowed)
			(footprints allowed)
		)
		(placement
			(enabled no)
			(sheetname "")
		)
		(fill yes
			(thermal_gap 0.5)
			(thermal_bridge_width 0.5)
			(island_removal_mode 0)
		)
		(polygon
			(pts
				(arc
					(start 114.106452 -60.8584)
					(mid 112.328452 -60.8584)
					(end 114.106452 -60.8584)
				)
			)
		)
	)
	(zone
		(layers "In1.Cu" "In3.Cu" "In6.Cu" "In8.Cu")
		(hatch none 0.5)
		(connect_pads
			(clearance 0)
		)
		(min_thickness 0.25)
		(keepout
			(tracks not_allowed)
			(vias allowed)
			(pads allowed)
			(copperpour not_allowed)
			(footprints allowed)
		)
		(placement
			(enabled no)
			(sheetname "")
		)
		(fill yes
			(thermal_gap 0.5)
			(thermal_bridge_width 0.5)
			(island_removal_mode 0)
		)
		(polygon
			(pts
				(arc
					(start 336.0928 -23.0886)
					(mid 334.3148 -23.0886)
					(end 336.0928 -23.0886)
				)
			)
		)
	)
	(zone
		(layers "In1.Cu" "In3.Cu" "In6.Cu" "In8.Cu")
		(hatch none 0.5)
		(connect_pads
			(clearance 0)
		)
		(min_thickness 0.25)
		(keepout
			(tracks not_allowed)
			(vias allowed)
			(pads allowed)
			(copperpour not_allowed)
			(footprints allowed)
		)
		(placement
			(enabled no)
			(sheetname "")
		)
		(fill yes
			(thermal_gap 0.5)
			(thermal_bridge_width 0.5)
			(island_removal_mode 0)
		)
		(polygon
			(pts
				(arc
					(start 114.106452 -59.3344)
					(mid 112.328452 -59.3344)
					(end 114.106452 -59.3344)
				)
			)
		)
	)
	(zone
		(layers "In1.Cu" "In3.Cu" "In6.Cu" "In8.Cu")
		(hatch none 0.5)
		(connect_pads
			(clearance 0)
		)
		(min_thickness 0.25)
		(keepout
			(tracks not_allowed)
			(vias allowed)
			(pads allowed)
			(copperpour not_allowed)
			(footprints allowed)
		)
		(placement
			(enabled no)
			(sheetname "")
		)
		(fill yes
			(thermal_gap 0.5)
			(thermal_bridge_width 0.5)
			(island_removal_mode 0)
		)
		(polygon
			(pts
				(arc
					(start 336.0928 -44.8818)
					(mid 334.3148 -44.8818)
					(end 336.0928 -44.8818)
				)
			)
		)
	)
	(zone
		(layers "In1.Cu" "In3.Cu" "In6.Cu" "In8.Cu")
		(hatch none 0.5)
		(connect_pads
			(clearance 0)
		)
		(min_thickness 0.25)
		(keepout
			(tracks not_allowed)
			(vias allowed)
			(pads allowed)
			(copperpour not_allowed)
			(footprints allowed)
		)
		(placement
			(enabled no)
			(sheetname "")
		)
		(fill yes
			(thermal_gap 0.5)
			(thermal_bridge_width 0.5)
			(island_removal_mode 0)
		)
		(polygon
			(pts
				(arc
					(start 334.5688 -65.913)
					(mid 332.7908 -65.913)
					(end 334.5688 -65.913)
				)
			)
		)
	)
	(zone
		(layers "In1.Cu" "In3.Cu" "In6.Cu" "In8.Cu")
		(hatch none 0.5)
		(connect_pads
			(clearance 0)
		)
		(min_thickness 0.25)
		(keepout
			(tracks not_allowed)
			(vias allowed)
			(pads allowed)
			(copperpour not_allowed)
			(footprints allowed)
		)
		(placement
			(enabled no)
			(sheetname "")
		)
		(fill yes
			(thermal_gap 0.5)
			(thermal_bridge_width 0.5)
			(island_removal_mode 0)
		)
		(polygon
			(pts
				(arc
					(start 333.0448 -21.5646)
					(mid 331.2668 -21.5646)
					(end 333.0448 -21.5646)
				)
			)
		)
	)
	(zone
		(layers "In1.Cu" "In3.Cu" "In6.Cu" "In8.Cu")
		(hatch none 0.5)
		(connect_pads
			(clearance 0)
		)
		(min_thickness 0.25)
		(keepout
			(tracks not_allowed)
			(vias allowed)
			(pads allowed)
			(copperpour not_allowed)
			(footprints allowed)
		)
		(placement
			(enabled no)
			(sheetname "")
		)
		(fill yes
			(thermal_gap 0.5)
			(thermal_bridge_width 0.5)
			(island_removal_mode 0)
		)
		(polygon
			(pts
				(arc
					(start 336.0928 -76.4286)
					(mid 334.3148 -76.4286)
					(end 336.0928 -76.4286)
				)
			)
		)
	)
	(zone
		(layers "In1.Cu" "In3.Cu" "In6.Cu" "In8.Cu")
		(hatch none 0.5)
		(connect_pads
			(clearance 0)
		)
		(min_thickness 0.25)
		(keepout
			(tracks not_allowed)
			(vias allowed)
			(pads allowed)
			(copperpour not_allowed)
			(footprints allowed)
		)
		(placement
			(enabled no)
			(sheetname "")
		)
		(fill yes
			(thermal_gap 0.5)
			(thermal_bridge_width 0.5)
			(island_removal_mode 0)
		)
		(polygon
			(pts
				(arc
					(start 333.8068 -56.9214)
					(mid 332.0288 -56.9214)
					(end 333.8068 -56.9214)
				)
			)
		)
	)
	(zone
		(layers "In1.Cu" "In3.Cu" "In6.Cu" "In8.Cu")
		(hatch none 0.5)
		(connect_pads
			(clearance 0)
		)
		(min_thickness 0.25)
		(keepout
			(tracks not_allowed)
			(vias allowed)
			(pads allowed)
			(copperpour not_allowed)
			(footprints allowed)
		)
		(placement
			(enabled no)
			(sheetname "")
		)
		(fill yes
			(thermal_gap 0.5)
			(thermal_bridge_width 0.5)
			(island_removal_mode 0)
		)
		(polygon
			(pts
				(arc
					(start 399.588228 -152.830022)
					(mid 397.16202 -152.830022)
					(end 399.588228 -152.830022)
				)
			)
		)
	)
	(zone
		(layers "In1.Cu" "In3.Cu" "In6.Cu" "In8.Cu")
		(hatch none 0.5)
		(connect_pads
			(clearance 0)
		)
		(min_thickness 0.25)
		(keepout
			(tracks not_allowed)
			(vias allowed)
			(pads allowed)
			(copperpour not_allowed)
			(footprints allowed)
		)
		(placement
			(enabled no)
			(sheetname "")
		)
		(fill yes
			(thermal_gap 0.5)
			(thermal_bridge_width 0.5)
			(island_removal_mode 0)
		)
		(polygon
			(pts
				(arc
					(start 115.630452 -27.0256)
					(mid 113.852452 -27.0256)
					(end 115.630452 -27.0256)
				)
			)
		)
	)
	(zone
		(layers "In1.Cu" "In3.Cu" "In6.Cu" "In8.Cu")
		(hatch none 0.5)
		(connect_pads
			(clearance 0)
		)
		(min_thickness 0.25)
		(keepout
			(tracks not_allowed)
			(vias allowed)
			(pads allowed)
			(copperpour not_allowed)
			(footprints allowed)
		)
		(placement
			(enabled no)
			(sheetname "")
		)
		(fill yes
			(thermal_gap 0.5)
			(thermal_bridge_width 0.5)
			(island_removal_mode 0)
		)
		(polygon
			(pts
				(arc
					(start 113.344452 -72.136)
					(mid 111.566452 -72.136)
					(end 113.344452 -72.136)
				)
			)
		)
	)
	(zone
		(layers "In1.Cu" "In3.Cu" "In6.Cu" "In8.Cu")
		(hatch none 0.5)
		(connect_pads
			(clearance 0)
		)
		(min_thickness 0.25)
		(keepout
			(tracks not_allowed)
			(vias allowed)
			(pads allowed)
			(copperpour not_allowed)
			(footprints allowed)
		)
		(placement
			(enabled no)
			(sheetname "")
		)
		(fill yes
			(thermal_gap 0.5)
			(thermal_bridge_width 0.5)
			(island_removal_mode 0)
		)
		(polygon
			(pts
				(arc
					(start 114.868452 -61.6204)
					(mid 113.090452 -61.6204)
					(end 114.868452 -61.6204)
				)
			)
		)
	)
	(zone
		(layers "In1.Cu" "In3.Cu" "In6.Cu" "In8.Cu")
		(hatch none 0.5)
		(connect_pads
			(clearance 0)
		)
		(min_thickness 0.25)
		(keepout
			(tracks not_allowed)
			(vias allowed)
			(pads allowed)
			(copperpour not_allowed)
			(footprints allowed)
		)
		(placement
			(enabled no)
			(sheetname "")
		)
		(fill yes
			(thermal_gap 0.5)
			(thermal_bridge_width 0.5)
			(island_removal_mode 0)
		)
		(polygon
			(pts
				(arc
					(start 379.603 -78.74)
					(mid 376.555 -78.74)
					(end 379.603 -78.74)
				)
			)
		)
	)
	(zone
		(layers "In1.Cu" "In3.Cu" "In6.Cu" "In8.Cu")
		(hatch none 0.5)
		(connect_pads
			(clearance 0)
		)
		(min_thickness 0.25)
		(keepout
			(tracks not_allowed)
			(vias allowed)
			(pads allowed)
			(copperpour not_allowed)
			(footprints allowed)
		)
		(placement
			(enabled no)
			(sheetname "")
		)
		(fill yes
			(thermal_gap 0.5)
			(thermal_bridge_width 0.5)
			(island_removal_mode 0)
		)
		(polygon
			(pts
				(arc
					(start 114.868452 -27.7876)
					(mid 113.090452 -27.7876)
					(end 114.868452 -27.7876)
				)
			)
		)
	)
	(zone
		(layers "In1.Cu" "In3.Cu" "In6.Cu" "In8.Cu")
		(hatch none 0.5)
		(connect_pads
			(clearance 0)
		)
		(min_thickness 0.25)
		(keepout
			(tracks not_allowed)
			(vias allowed)
			(pads allowed)
			(copperpour not_allowed)
			(footprints allowed)
		)
		(placement
			(enabled no)
			(sheetname "")
		)
		(fill yes
			(thermal_gap 0.5)
			(thermal_bridge_width 0.5)
			(island_removal_mode 0)
		)
		(polygon
			(pts
				(arc
					(start 333.8068 -20.0406)
					(mid 332.0288 -20.0406)
					(end 333.8068 -20.0406)
				)
			)
		)
	)
	(zone
		(layers "In1.Cu" "In3.Cu" "In6.Cu" "In8.Cu")
		(hatch none 0.5)
		(connect_pads
			(clearance 0)
		)
		(min_thickness 0.25)
		(keepout
			(tracks not_allowed)
			(vias allowed)
			(pads allowed)
			(copperpour not_allowed)
			(footprints allowed)
		)
		(placement
			(enabled no)
			(sheetname "")
		)
		(fill yes
			(thermal_gap 0.5)
			(thermal_bridge_width 0.5)
			(island_removal_mode 0)
		)
		(polygon
			(pts
				(arc
					(start 333.8068 -56.1594)
					(mid 332.0288 -56.1594)
					(end 333.8068 -56.1594)
				)
			)
		)
	)
	(zone
		(layers "In1.Cu" "In3.Cu" "In6.Cu" "In8.Cu")
		(hatch none 0.5)
		(connect_pads
			(clearance 0)
		)
		(min_thickness 0.25)
		(keepout
			(tracks not_allowed)
			(vias allowed)
			(pads allowed)
			(copperpour not_allowed)
			(footprints allowed)
		)
		(placement
			(enabled no)
			(sheetname "")
		)
		(fill yes
			(thermal_gap 0.5)
			(thermal_bridge_width 0.5)
			(island_removal_mode 0)
		)
		(polygon
			(pts
				(arc
					(start 333.0448 -32.0802)
					(mid 331.2668 -32.0802)
					(end 333.0448 -32.0802)
				)
			)
		)
	)
	(zone
		(layers "In1.Cu" "In3.Cu" "In6.Cu" "In8.Cu")
		(hatch none 0.5)
		(connect_pads
			(clearance 0)
		)
		(min_thickness 0.25)
		(keepout
			(tracks not_allowed)
			(vias allowed)
			(pads allowed)
			(copperpour not_allowed)
			(footprints allowed)
		)
		(placement
			(enabled no)
			(sheetname "")
		)
		(fill yes
			(thermal_gap 0.5)
			(thermal_bridge_width 0.5)
			(island_removal_mode 0)
		)
		(polygon
			(pts
				(arc
					(start 334.5688 -54.6354)
					(mid 332.7908 -54.6354)
					(end 334.5688 -54.6354)
				)
			)
		)
	)
	(zone
		(layers "In1.Cu" "In3.Cu" "In6.Cu" "In8.Cu")
		(hatch none 0.5)
		(connect_pads
			(clearance 0)
		)
		(min_thickness 0.25)
		(keepout
			(tracks not_allowed)
			(vias allowed)
			(pads allowed)
			(copperpour not_allowed)
			(footprints allowed)
		)
		(placement
			(enabled no)
			(sheetname "")
		)
		(fill yes
			(thermal_gap 0.5)
			(thermal_bridge_width 0.5)
			(island_removal_mode 0)
		)
		(polygon
			(pts
				(arc
					(start 401.588224 -158.83001)
					(mid 399.162016 -158.83001)
					(end 401.588224 -158.83001)
				)
			)
		)
	)
	(zone
		(layers "In1.Cu" "In3.Cu" "In6.Cu" "In8.Cu")
		(hatch none 0.5)
		(connect_pads
			(clearance 0)
		)
		(min_thickness 0.25)
		(keepout
			(tracks not_allowed)
			(vias allowed)
			(pads allowed)
			(copperpour not_allowed)
			(footprints allowed)
		)
		(placement
			(enabled no)
			(sheetname "")
		)
		(fill yes
			(thermal_gap 0.5)
			(thermal_bridge_width 0.5)
			(island_removal_mode 0)
		)
		(polygon
			(pts
				(arc
					(start 333.0448 -23.0886)
					(mid 331.2668 -23.0886)
					(end 333.0448 -23.0886)
				)
			)
		)
	)
	(zone
		(layers "In1.Cu" "In3.Cu" "In6.Cu" "In8.Cu")
		(hatch none 0.5)
		(connect_pads
			(clearance 0)
		)
		(min_thickness 0.25)
		(keepout
			(tracks not_allowed)
			(vias allowed)
			(pads allowed)
			(copperpour not_allowed)
			(footprints allowed)
		)
		(placement
			(enabled no)
			(sheetname "")
		)
		(fill yes
			(thermal_gap 0.5)
			(thermal_bridge_width 0.5)
			(island_removal_mode 0)
		)
		(polygon
			(pts
				(arc
					(start 333.0448 -78.7146)
					(mid 331.2668 -78.7146)
					(end 333.0448 -78.7146)
				)
			)
		)
	)
	(zone
		(layers "In1.Cu" "In3.Cu" "In6.Cu" "In8.Cu")
		(hatch none 0.5)
		(connect_pads
			(clearance 0)
		)
		(min_thickness 0.25)
		(keepout
			(tracks not_allowed)
			(vias allowed)
			(pads allowed)
			(copperpour not_allowed)
			(footprints allowed)
		)
		(placement
			(enabled no)
			(sheetname "")
		)
		(fill yes
			(thermal_gap 0.5)
			(thermal_bridge_width 0.5)
			(island_removal_mode 0)
		)
		(polygon
			(pts
				(arc
					(start 334.5688 -65.151)
					(mid 332.7908 -65.151)
					(end 334.5688 -65.151)
				)
			)
		)
	)
	(zone
		(layers "In1.Cu" "In3.Cu" "In6.Cu" "In8.Cu")
		(hatch none 0.5)
		(connect_pads
			(clearance 0)
		)
		(min_thickness 0.25)
		(keepout
			(tracks not_allowed)
			(vias allowed)
			(pads allowed)
			(copperpour not_allowed)
			(footprints allowed)
		)
		(placement
			(enabled no)
			(sheetname "")
		)
		(fill yes
			(thermal_gap 0.5)
			(thermal_bridge_width 0.5)
			(island_removal_mode 0)
		)
		(polygon
			(pts
				(arc
					(start 335.3308 -20.8026)
					(mid 333.5528 -20.8026)
					(end 335.3308 -20.8026)
				)
			)
		)
	)
	(zone
		(layers "In1.Cu" "In3.Cu" "In6.Cu" "In8.Cu")
		(hatch none 0.5)
		(connect_pads
			(clearance 0)
		)
		(min_thickness 0.25)
		(keepout
			(tracks not_allowed)
			(vias allowed)
			(pads allowed)
			(copperpour not_allowed)
			(footprints allowed)
		)
		(placement
			(enabled no)
			(sheetname "")
		)
		(fill yes
			(thermal_gap 0.5)
			(thermal_bridge_width 0.5)
			(island_removal_mode 0)
		)
		(polygon
			(pts
				(arc
					(start 334.5688 -34.3662)
					(mid 332.7908 -34.3662)
					(end 334.5688 -34.3662)
				)
			)
		)
	)
	(zone
		(layers "In1.Cu" "In3.Cu" "In6.Cu" "In8.Cu")
		(hatch none 0.5)
		(connect_pads
			(clearance 0)
		)
		(min_thickness 0.25)
		(keepout
			(tracks not_allowed)
			(vias allowed)
			(pads allowed)
			(copperpour not_allowed)
			(footprints allowed)
		)
		(placement
			(enabled no)
			(sheetname "")
		)
		(fill yes
			(thermal_gap 0.5)
			(thermal_bridge_width 0.5)
			(island_removal_mode 0)
		)
		(polygon
			(pts
				(arc
					(start 87.376 -5.334)
					(mid 85.598 -5.334)
					(end 87.376 -5.334)
				)
			)
		)
	)
	(zone
		(layers "In1.Cu" "In3.Cu" "In6.Cu" "In8.Cu")
		(hatch none 0.5)
		(connect_pads
			(clearance 0)
		)
		(min_thickness 0.25)
		(keepout
			(tracks not_allowed)
			(vias allowed)
			(pads allowed)
			(copperpour not_allowed)
			(footprints allowed)
		)
		(placement
			(enabled no)
			(sheetname "")
		)
		(fill yes
			(thermal_gap 0.5)
			(thermal_bridge_width 0.5)
			(island_removal_mode 0)
		)
		(polygon
			(pts
				(arc
					(start 366.213136 -158.83001)
					(mid 363.786928 -158.83001)
					(end 366.213136 -158.83001)
				)
			)
		)
	)
	(zone
		(layers "In1.Cu" "In3.Cu" "In6.Cu" "In8.Cu")
		(hatch none 0.5)
		(connect_pads
			(clearance 0)
		)
		(min_thickness 0.25)
		(keepout
			(tracks not_allowed)
			(vias allowed)
			(pads allowed)
			(copperpour not_allowed)
			(footprints allowed)
		)
		(placement
			(enabled no)
			(sheetname "")
		)
		(fill yes
			(thermal_gap 0.5)
			(thermal_bridge_width 0.5)
			(island_removal_mode 0)
		)
		(polygon
			(pts
				(arc
					(start 335.3308 -44.8818)
					(mid 333.5528 -44.8818)
					(end 335.3308 -44.8818)
				)
			)
		)
	)
	(zone
		(layers "In1.Cu" "In3.Cu" "In6.Cu" "In8.Cu")
		(hatch none 0.5)
		(connect_pads
			(clearance 0)
		)
		(min_thickness 0.25)
		(keepout
			(tracks not_allowed)
			(vias allowed)
			(pads allowed)
			(copperpour not_allowed)
			(footprints allowed)
		)
		(placement
			(enabled no)
			(sheetname "")
		)
		(fill yes
			(thermal_gap 0.5)
			(thermal_bridge_width 0.5)
			(island_removal_mode 0)
		)
		(polygon
			(pts
				(arc
					(start 334.5688 -20.8026)
					(mid 332.7908 -20.8026)
					(end 334.5688 -20.8026)
				)
			)
		)
	)
	(zone
		(layers "In1.Cu" "In3.Cu" "In6.Cu" "In8.Cu")
		(hatch none 0.5)
		(connect_pads
			(clearance 0)
		)
		(min_thickness 0.25)
		(keepout
			(tracks not_allowed)
			(vias allowed)
			(pads allowed)
			(copperpour not_allowed)
			(footprints allowed)
		)
		(placement
			(enabled no)
			(sheetname "")
		)
		(fill yes
			(thermal_gap 0.5)
			(thermal_bridge_width 0.5)
			(island_removal_mode 0)
		)
		(polygon
			(pts
				(arc
					(start 335.3308 -42.5958)
					(mid 333.5528 -42.5958)
					(end 335.3308 -42.5958)
				)
			)
		)
	)
	(zone
		(layers "In1.Cu" "In3.Cu" "In6.Cu" "In8.Cu")
		(hatch none 0.5)
		(connect_pads
			(clearance 0)
		)
		(min_thickness 0.25)
		(keepout
			(tracks not_allowed)
			(vias allowed)
			(pads allowed)
			(copperpour not_allowed)
			(footprints allowed)
		)
		(placement
			(enabled no)
			(sheetname "")
		)
		(fill yes
			(thermal_gap 0.5)
			(thermal_bridge_width 0.5)
			(island_removal_mode 0)
		)
		(polygon
			(pts
				(arc
					(start 38.088062 -162.830002)
					(mid 35.661854 -162.830002)
					(end 38.088062 -162.830002)
				)
			)
		)
	)
	(zone
		(layers "In1.Cu" "In3.Cu" "In6.Cu" "In8.Cu")
		(hatch none 0.5)
		(connect_pads
			(clearance 0)
		)
		(min_thickness 0.25)
		(keepout
			(tracks not_allowed)
			(vias allowed)
			(pads allowed)
			(copperpour not_allowed)
			(footprints allowed)
		)
		(placement
			(enabled no)
			(sheetname "")
		)
		(fill yes
			(thermal_gap 0.5)
			(thermal_bridge_width 0.5)
			(island_removal_mode 0)
		)
		(polygon
			(pts
				(arc
					(start 376.213116 -160.830006)
					(mid 373.786908 -160.830006)
					(end 376.213116 -160.830006)
				)
			)
		)
	)
	(zone
		(layers "In1.Cu" "In3.Cu" "In6.Cu" "In8.Cu")
		(hatch none 0.5)
		(connect_pads
			(clearance 0)
		)
		(min_thickness 0.25)
		(keepout
			(tracks not_allowed)
			(vias allowed)
			(pads allowed)
			(copperpour not_allowed)
			(footprints allowed)
		)
		(placement
			(enabled no)
			(sheetname "")
		)
		(fill yes
			(thermal_gap 0.5)
			(thermal_bridge_width 0.5)
			(island_removal_mode 0)
		)
		(polygon
			(pts
				(arc
					(start 36.088066 -168.82999)
					(mid 33.661858 -168.82999)
					(end 36.088066 -168.82999)
				)
			)
		)
	)
	(zone
		(layers "In1.Cu" "In3.Cu" "In6.Cu" "In8.Cu")
		(hatch none 0.5)
		(connect_pads
			(clearance 0)
		)
		(min_thickness 0.25)
		(keepout
			(tracks not_allowed)
			(vias allowed)
			(pads allowed)
			(copperpour not_allowed)
			(footprints allowed)
		)
		(placement
			(enabled no)
			(sheetname "")
		)
		(fill yes
			(thermal_gap 0.5)
			(thermal_bridge_width 0.5)
			(island_removal_mode 0)
		)
		(polygon
			(pts
				(arc
					(start 114.868452 -38.3032)
					(mid 113.090452 -38.3032)
					(end 114.868452 -38.3032)
				)
			)
		)
	)
	(zone
		(layers "In1.Cu" "In3.Cu" "In6.Cu" "In8.Cu")
		(hatch none 0.5)
		(connect_pads
			(clearance 0)
		)
		(min_thickness 0.25)
		(keepout
			(tracks not_allowed)
			(vias allowed)
			(pads allowed)
			(copperpour not_allowed)
			(footprints allowed)
		)
		(placement
			(enabled no)
			(sheetname "")
		)
		(fill yes
			(thermal_gap 0.5)
			(thermal_bridge_width 0.5)
			(island_removal_mode 0)
		)
		(polygon
			(pts
				(arc
					(start 114.106452 -15.748)
					(mid 112.328452 -15.748)
					(end 114.106452 -15.748)
				)
			)
		)
	)
	(zone
		(layers "In1.Cu" "In3.Cu" "In6.Cu" "In8.Cu")
		(hatch none 0.5)
		(connect_pads
			(clearance 0)
		)
		(min_thickness 0.25)
		(keepout
			(tracks not_allowed)
			(vias allowed)
			(pads allowed)
			(copperpour not_allowed)
			(footprints allowed)
		)
		(placement
			(enabled no)
			(sheetname "")
		)
		(fill yes
			(thermal_gap 0.5)
			(thermal_bridge_width 0.5)
			(island_removal_mode 0)
		)
		(polygon
			(pts
				(arc
					(start 336.0928 -67.437)
					(mid 334.3148 -67.437)
					(end 336.0928 -67.437)
				)
			)
		)
	)
	(zone
		(layers "In1.Cu" "In3.Cu" "In6.Cu" "In8.Cu")
		(hatch none 0.5)
		(connect_pads
			(clearance 0)
		)
		(min_thickness 0.25)
		(keepout
			(tracks not_allowed)
			(vias allowed)
			(pads allowed)
			(copperpour not_allowed)
			(footprints allowed)
		)
		(placement
			(enabled no)
			(sheetname "")
		)
		(fill yes
			(thermal_gap 0.5)
			(thermal_bridge_width 0.5)
			(island_removal_mode 0)
		)
		(polygon
			(pts
				(arc
					(start 116.392452 -26.2636)
					(mid 114.614452 -26.2636)
					(end 116.392452 -26.2636)
				)
			)
		)
	)
	(zone
		(layers "In1.Cu" "In3.Cu" "In6.Cu" "In8.Cu")
		(hatch none 0.5)
		(connect_pads
			(clearance 0)
		)
		(min_thickness 0.25)
		(keepout
			(tracks not_allowed)
			(vias allowed)
			(pads allowed)
			(copperpour not_allowed)
			(footprints allowed)
		)
		(placement
			(enabled no)
			(sheetname "")
		)
		(fill yes
			(thermal_gap 0.5)
			(thermal_bridge_width 0.5)
			(island_removal_mode 0)
		)
		(polygon
			(pts
				(arc
					(start 333.8068 -54.6354)
					(mid 332.0288 -54.6354)
					(end 333.8068 -54.6354)
				)
			)
		)
	)
	(zone
		(layers "In1.Cu" "In3.Cu" "In6.Cu" "In8.Cu")
		(hatch none 0.5)
		(connect_pads
			(clearance 0)
		)
		(min_thickness 0.25)
		(keepout
			(tracks not_allowed)
			(vias allowed)
			(pads allowed)
			(copperpour not_allowed)
			(footprints allowed)
		)
		(placement
			(enabled no)
			(sheetname "")
		)
		(fill yes
			(thermal_gap 0.5)
			(thermal_bridge_width 0.5)
			(island_removal_mode 0)
		)
		(polygon
			(pts
				(arc
					(start 384.412998 -158.83001)
					(mid 381.98679 -158.83001)
					(end 384.412998 -158.83001)
				)
			)
		)
	)
	(zone
		(layers "In1.Cu" "In3.Cu" "In6.Cu" "In8.Cu")
		(hatch none 0.5)
		(connect_pads
			(clearance 0)
		)
		(min_thickness 0.25)
		(keepout
			(tracks not_allowed)
			(vias allowed)
			(pads allowed)
			(copperpour not_allowed)
			(footprints allowed)
		)
		(placement
			(enabled no)
			(sheetname "")
		)
		(fill yes
			(thermal_gap 0.5)
			(thermal_bridge_width 0.5)
			(island_removal_mode 0)
		)
		(polygon
			(pts
				(arc
					(start 334.5688 -56.1594)
					(mid 332.7908 -56.1594)
					(end 334.5688 -56.1594)
				)
			)
		)
	)
	(zone
		(layers "In1.Cu" "In3.Cu" "In6.Cu" "In8.Cu")
		(hatch none 0.5)
		(connect_pads
			(clearance 0)
		)
		(min_thickness 0.25)
		(keepout
			(tracks not_allowed)
			(vias allowed)
			(pads allowed)
			(copperpour not_allowed)
			(footprints allowed)
		)
		(placement
			(enabled no)
			(sheetname "")
		)
		(fill yes
			(thermal_gap 0.5)
			(thermal_bridge_width 0.5)
			(island_removal_mode 0)
		)
		(polygon
			(pts
				(arc
					(start 336.0928 -32.0802)
					(mid 334.3148 -32.0802)
					(end 336.0928 -32.0802)
				)
			)
		)
	)
	(zone
		(layers "In1.Cu" "In3.Cu" "In6.Cu" "In8.Cu")
		(hatch none 0.5)
		(connect_pads
			(clearance 0)
		)
		(min_thickness 0.25)
		(keepout
			(tracks not_allowed)
			(vias allowed)
			(pads allowed)
			(copperpour not_allowed)
			(footprints allowed)
		)
		(placement
			(enabled no)
			(sheetname "")
		)
		(fill yes
			(thermal_gap 0.5)
			(thermal_bridge_width 0.5)
			(island_removal_mode 0)
		)
		(polygon
			(pts
				(arc
					(start 333.8068 -79.4766)
					(mid 332.0288 -79.4766)
					(end 333.8068 -79.4766)
				)
			)
		)
	)
	(zone
		(layers "In1.Cu" "In3.Cu" "In6.Cu" "In8.Cu")
		(hatch none 0.5)
		(connect_pads
			(clearance 0)
		)
		(min_thickness 0.25)
		(keepout
			(tracks not_allowed)
			(vias allowed)
			(pads allowed)
			(copperpour not_allowed)
			(footprints allowed)
		)
		(placement
			(enabled no)
			(sheetname "")
		)
		(fill yes
			(thermal_gap 0.5)
			(thermal_bridge_width 0.5)
			(island_removal_mode 0)
		)
		(polygon
			(pts
				(arc
					(start 399.588228 -162.830002)
					(mid 397.16202 -162.830002)
					(end 399.588228 -162.830002)
				)
			)
		)
	)
	(zone
		(layers "In1.Cu" "In3.Cu" "In6.Cu" "In8.Cu")
		(hatch none 0.5)
		(connect_pads
			(clearance 0)
		)
		(min_thickness 0.25)
		(keepout
			(tracks not_allowed)
			(vias allowed)
			(pads allowed)
			(copperpour not_allowed)
			(footprints allowed)
		)
		(placement
			(enabled no)
			(sheetname "")
		)
		(fill yes
			(thermal_gap 0.5)
			(thermal_bridge_width 0.5)
			(island_removal_mode 0)
		)
		(polygon
			(pts
				(arc
					(start 113.344452 -48.8188)
					(mid 111.566452 -48.8188)
					(end 113.344452 -48.8188)
				)
			)
		)
	)
	(zone
		(layers "In1.Cu" "In3.Cu" "In6.Cu" "In8.Cu")
		(hatch none 0.5)
		(connect_pads
			(clearance 0)
		)
		(min_thickness 0.25)
		(keepout
			(tracks not_allowed)
			(vias allowed)
			(pads allowed)
			(copperpour not_allowed)
			(footprints allowed)
		)
		(placement
			(enabled no)
			(sheetname "")
		)
		(fill yes
			(thermal_gap 0.5)
			(thermal_bridge_width 0.5)
			(island_removal_mode 0)
		)
		(polygon
			(pts
				(arc
					(start 358.83342 -3.829304)
					(mid 357.05542 -3.829304)
					(end 358.83342 -3.829304)
				)
			)
		)
	)
	(zone
		(layers "In1.Cu" "In3.Cu" "In6.Cu" "In8.Cu")
		(hatch none 0.5)
		(connect_pads
			(clearance 0)
		)
		(min_thickness 0.25)
		(keepout
			(tracks not_allowed)
			(vias allowed)
			(pads allowed)
			(copperpour not_allowed)
			(footprints allowed)
		)
		(placement
			(enabled no)
			(sheetname "")
		)
		(fill yes
			(thermal_gap 0.5)
			(thermal_bridge_width 0.5)
			(island_removal_mode 0)
		)
		(polygon
			(pts
				(arc
					(start 333.8068 -66.675)
					(mid 332.0288 -66.675)
					(end 333.8068 -66.675)
				)
			)
		)
	)
	(zone
		(layers "In1.Cu" "In3.Cu" "In6.Cu" "In8.Cu")
		(hatch none 0.5)
		(connect_pads
			(clearance 0)
		)
		(min_thickness 0.25)
		(keepout
			(tracks not_allowed)
			(vias allowed)
			(pads allowed)
			(copperpour not_allowed)
			(footprints allowed)
		)
		(placement
			(enabled no)
			(sheetname "")
		)
		(fill yes
			(thermal_gap 0.5)
			(thermal_bridge_width 0.5)
			(island_removal_mode 0)
		)
		(polygon
			(pts
				(arc
					(start 335.3308 -56.1594)
					(mid 333.5528 -56.1594)
					(end 335.3308 -56.1594)
				)
			)
		)
	)
	(zone
		(layers "In1.Cu" "In3.Cu" "In6.Cu" "In8.Cu")
		(hatch none 0.5)
		(connect_pads
			(clearance 0)
		)
		(min_thickness 0.25)
		(keepout
			(tracks not_allowed)
			(vias allowed)
			(pads allowed)
			(copperpour not_allowed)
			(footprints allowed)
		)
		(placement
			(enabled no)
			(sheetname "")
		)
		(fill yes
			(thermal_gap 0.5)
			(thermal_bridge_width 0.5)
			(island_removal_mode 0)
		)
		(polygon
			(pts
				(arc
					(start 370.213128 -158.83001)
					(mid 367.78692 -158.83001)
					(end 370.213128 -158.83001)
				)
			)
		)
	)
	(zone
		(layers "In1.Cu" "In3.Cu" "In6.Cu" "In8.Cu")
		(hatch none 0.5)
		(connect_pads
			(clearance 0)
		)
		(min_thickness 0.25)
		(keepout
			(tracks not_allowed)
			(vias allowed)
			(pads allowed)
			(copperpour not_allowed)
			(footprints allowed)
		)
		(placement
			(enabled no)
			(sheetname "")
		)
		(fill yes
			(thermal_gap 0.5)
			(thermal_bridge_width 0.5)
			(island_removal_mode 0)
		)
		(polygon
			(pts
				(arc
					(start 114.106452 -25.5016)
					(mid 112.328452 -25.5016)
					(end 114.106452 -25.5016)
				)
			)
		)
	)
	(zone
		(layers "In1.Cu" "In3.Cu" "In6.Cu" "In8.Cu")
		(hatch none 0.5)
		(connect_pads
			(clearance 0)
		)
		(min_thickness 0.25)
		(keepout
			(tracks not_allowed)
			(vias allowed)
			(pads allowed)
			(copperpour not_allowed)
			(footprints allowed)
		)
		(placement
			(enabled no)
			(sheetname "")
		)
		(fill yes
			(thermal_gap 0.5)
			(thermal_bridge_width 0.5)
			(island_removal_mode 0)
		)
		(polygon
			(pts
				(arc
					(start 114.868452 -50.3428)
					(mid 113.090452 -50.3428)
					(end 114.868452 -50.3428)
				)
			)
		)
	)
	(zone
		(layers "In1.Cu" "In3.Cu" "In6.Cu" "In8.Cu")
		(hatch none 0.5)
		(connect_pads
			(clearance 0)
		)
		(min_thickness 0.25)
		(keepout
			(tracks not_allowed)
			(vias allowed)
			(pads allowed)
			(copperpour not_allowed)
			(footprints allowed)
		)
		(placement
			(enabled no)
			(sheetname "")
		)
		(fill yes
			(thermal_gap 0.5)
			(thermal_bridge_width 0.5)
			(island_removal_mode 0)
		)
		(polygon
			(pts
				(arc
					(start 333.8068 -32.0802)
					(mid 332.0288 -32.0802)
					(end 333.8068 -32.0802)
				)
			)
		)
	)
	(zone
		(layers "In1.Cu" "In3.Cu" "In6.Cu" "In8.Cu")
		(hatch none 0.5)
		(connect_pads
			(clearance 0)
		)
		(min_thickness 0.25)
		(keepout
			(tracks not_allowed)
			(vias allowed)
			(pads allowed)
			(copperpour not_allowed)
			(footprints allowed)
		)
		(placement
			(enabled no)
			(sheetname "")
		)
		(fill yes
			(thermal_gap 0.5)
			(thermal_bridge_width 0.5)
			(island_removal_mode 0)
		)
		(polygon
			(pts
				(arc
					(start 114.106452 -28.5496)
					(mid 112.328452 -28.5496)
					(end 114.106452 -28.5496)
				)
			)
		)
	)
	(zone
		(layers "In1.Cu" "In3.Cu" "In6.Cu" "In8.Cu")
		(hatch none 0.5)
		(connect_pads
			(clearance 0)
		)
		(min_thickness 0.25)
		(keepout
			(tracks not_allowed)
			(vias allowed)
			(pads allowed)
			(copperpour not_allowed)
			(footprints allowed)
		)
		(placement
			(enabled no)
			(sheetname "")
		)
		(fill yes
			(thermal_gap 0.5)
			(thermal_bridge_width 0.5)
			(island_removal_mode 0)
		)
		(polygon
			(pts
				(arc
					(start 115.630452 -26.2636)
					(mid 113.852452 -26.2636)
					(end 115.630452 -26.2636)
				)
			)
		)
	)
	(zone
		(layers "In1.Cu" "In3.Cu" "In6.Cu" "In8.Cu")
		(hatch none 0.5)
		(connect_pads
			(clearance 0)
		)
		(min_thickness 0.25)
		(keepout
			(tracks not_allowed)
			(vias allowed)
			(pads allowed)
			(copperpour not_allowed)
			(footprints allowed)
		)
		(placement
			(enabled no)
			(sheetname "")
		)
		(fill yes
			(thermal_gap 0.5)
			(thermal_bridge_width 0.5)
			(island_removal_mode 0)
		)
		(polygon
			(pts
				(arc
					(start 115.630452 -27.7876)
					(mid 113.852452 -27.7876)
					(end 115.630452 -27.7876)
				)
			)
		)
	)
	(zone
		(layers "In1.Cu" "In3.Cu" "In6.Cu" "In8.Cu")
		(hatch none 0.5)
		(connect_pads
			(clearance 0)
		)
		(min_thickness 0.25)
		(keepout
			(tracks not_allowed)
			(vias allowed)
			(pads allowed)
			(copperpour not_allowed)
			(footprints allowed)
		)
		(placement
			(enabled no)
			(sheetname "")
		)
		(fill yes
			(thermal_gap 0.5)
			(thermal_bridge_width 0.5)
			(island_removal_mode 0)
		)
		(polygon
			(pts
				(arc
					(start 399.161 -99.06)
					(mid 396.113 -99.06)
					(end 399.161 -99.06)
				)
			)
		)
	)
	(zone
		(layers "In1.Cu" "In3.Cu" "In6.Cu" "In8.Cu")
		(hatch none 0.5)
		(connect_pads
			(clearance 0)
		)
		(min_thickness 0.25)
		(keepout
			(tracks not_allowed)
			(vias allowed)
			(pads allowed)
			(copperpour not_allowed)
			(footprints allowed)
		)
		(placement
			(enabled no)
			(sheetname "")
		)
		(fill yes
			(thermal_gap 0.5)
			(thermal_bridge_width 0.5)
			(island_removal_mode 0)
		)
		(polygon
			(pts
				(arc
					(start 115.630452 -17.272)
					(mid 113.852452 -17.272)
					(end 115.630452 -17.272)
				)
			)
		)
	)
	(zone
		(layers "In1.Cu" "In3.Cu" "In6.Cu" "In8.Cu")
		(hatch none 0.5)
		(connect_pads
			(clearance 0)
		)
		(min_thickness 0.25)
		(keepout
			(tracks not_allowed)
			(vias allowed)
			(pads allowed)
			(copperpour not_allowed)
			(footprints allowed)
		)
		(placement
			(enabled no)
			(sheetname "")
		)
		(fill yes
			(thermal_gap 0.5)
			(thermal_bridge_width 0.5)
			(island_removal_mode 0)
		)
		(polygon
			(pts
				(arc
					(start 114.868452 -60.8584)
					(mid 113.090452 -60.8584)
					(end 114.868452 -60.8584)
				)
			)
		)
	)
	(zone
		(layers "In1.Cu" "In3.Cu" "In6.Cu" "In8.Cu")
		(hatch none 0.5)
		(connect_pads
			(clearance 0)
		)
		(min_thickness 0.25)
		(keepout
			(tracks not_allowed)
			(vias allowed)
			(pads allowed)
			(copperpour not_allowed)
			(footprints allowed)
		)
		(placement
			(enabled no)
			(sheetname "")
		)
		(fill yes
			(thermal_gap 0.5)
			(thermal_bridge_width 0.5)
			(island_removal_mode 0)
		)
		(polygon
			(pts
				(arc
					(start 335.3308 -55.3974)
					(mid 333.5528 -55.3974)
					(end 335.3308 -55.3974)
				)
			)
		)
	)
	(zone
		(layers "In1.Cu" "In3.Cu" "In6.Cu" "In8.Cu")
		(hatch none 0.5)
		(connect_pads
			(clearance 0)
		)
		(min_thickness 0.25)
		(keepout
			(tracks not_allowed)
			(vias allowed)
			(pads allowed)
			(copperpour not_allowed)
			(footprints allowed)
		)
		(placement
			(enabled no)
			(sheetname "")
		)
		(fill yes
			(thermal_gap 0.5)
			(thermal_bridge_width 0.5)
			(island_removal_mode 0)
		)
		(polygon
			(pts
				(arc
					(start 115.630452 -70.612)
					(mid 113.852452 -70.612)
					(end 115.630452 -70.612)
				)
			)
		)
	)
	(zone
		(layers "In1.Cu" "In3.Cu" "In6.Cu" "In8.Cu")
		(hatch none 0.5)
		(connect_pads
			(clearance 0)
		)
		(min_thickness 0.25)
		(keepout
			(tracks not_allowed)
			(vias allowed)
			(pads allowed)
			(copperpour not_allowed)
			(footprints allowed)
		)
		(placement
			(enabled no)
			(sheetname "")
		)
		(fill yes
			(thermal_gap 0.5)
			(thermal_bridge_width 0.5)
			(island_removal_mode 0)
		)
		(polygon
			(pts
				(arc
					(start 333.8068 -31.3182)
					(mid 332.0288 -31.3182)
					(end 333.8068 -31.3182)
				)
			)
		)
	)
	(zone
		(layers "In1.Cu" "In3.Cu" "In6.Cu" "In8.Cu")
		(hatch none 0.5)
		(connect_pads
			(clearance 0)
		)
		(min_thickness 0.25)
		(keepout
			(tracks not_allowed)
			(vias allowed)
			(pads allowed)
			(copperpour not_allowed)
			(footprints allowed)
		)
		(placement
			(enabled no)
			(sheetname "")
		)
		(fill yes
			(thermal_gap 0.5)
			(thermal_bridge_width 0.5)
			(island_removal_mode 0)
		)
		(polygon
			(pts
				(arc
					(start 116.392452 -25.5016)
					(mid 114.614452 -25.5016)
					(end 116.392452 -25.5016)
				)
			)
		)
	)
	(zone
		(layers "In1.Cu" "In3.Cu" "In6.Cu" "In8.Cu")
		(hatch none 0.5)
		(connect_pads
			(clearance 0)
		)
		(min_thickness 0.25)
		(keepout
			(tracks not_allowed)
			(vias allowed)
			(pads allowed)
			(copperpour not_allowed)
			(footprints allowed)
		)
		(placement
			(enabled no)
			(sheetname "")
		)
		(fill yes
			(thermal_gap 0.5)
			(thermal_bridge_width 0.5)
			(island_removal_mode 0)
		)
		(polygon
			(pts
				(arc
					(start 52.013104 -158.83001)
					(mid 49.586896 -158.83001)
					(end 52.013104 -158.83001)
				)
			)
		)
	)
	(zone
		(layers "In1.Cu" "In3.Cu" "In6.Cu" "In8.Cu")
		(hatch none 0.5)
		(connect_pads
			(clearance 0)
		)
		(min_thickness 0.25)
		(keepout
			(tracks not_allowed)
			(vias allowed)
			(pads allowed)
			(copperpour not_allowed)
			(footprints allowed)
		)
		(placement
			(enabled no)
			(sheetname "")
		)
		(fill yes
			(thermal_gap 0.5)
			(thermal_bridge_width 0.5)
			(island_removal_mode 0)
		)
		(polygon
			(pts
				(arc
					(start 115.630452 -39.0652)
					(mid 113.852452 -39.0652)
					(end 115.630452 -39.0652)
				)
			)
		)
	)
	(zone
		(layers "In1.Cu" "In3.Cu" "In6.Cu" "In8.Cu")
		(hatch none 0.5)
		(connect_pads
			(clearance 0)
		)
		(min_thickness 0.25)
		(keepout
			(tracks not_allowed)
			(vias allowed)
			(pads allowed)
			(copperpour not_allowed)
			(footprints allowed)
		)
		(placement
			(enabled no)
			(sheetname "")
		)
		(fill yes
			(thermal_gap 0.5)
			(thermal_bridge_width 0.5)
			(island_removal_mode 0)
		)
		(polygon
			(pts
				(arc
					(start 364.21314 -160.830006)
					(mid 361.786932 -160.830006)
					(end 364.21314 -160.830006)
				)
			)
		)
	)
	(zone
		(layers "In1.Cu" "In3.Cu" "In6.Cu" "In8.Cu")
		(hatch none 0.5)
		(connect_pads
			(clearance 0)
		)
		(min_thickness 0.25)
		(keepout
			(tracks not_allowed)
			(vias allowed)
			(pads allowed)
			(copperpour not_allowed)
			(footprints allowed)
		)
		(placement
			(enabled no)
			(sheetname "")
		)
		(fill yes
			(thermal_gap 0.5)
			(thermal_bridge_width 0.5)
			(island_removal_mode 0)
		)
		(polygon
			(pts
				(arc
					(start 63.44539 -78.74)
					(mid 60.39739 -78.74)
					(end 63.44539 -78.74)
				)
			)
		)
	)
	(zone
		(layers "In1.Cu" "In3.Cu" "In6.Cu" "In8.Cu")
		(hatch none 0.5)
		(connect_pads
			(clearance 0)
		)
		(min_thickness 0.25)
		(keepout
			(tracks not_allowed)
			(vias allowed)
			(pads allowed)
			(copperpour not_allowed)
			(footprints allowed)
		)
		(placement
			(enabled no)
			(sheetname "")
		)
		(fill yes
			(thermal_gap 0.5)
			(thermal_bridge_width 0.5)
			(island_removal_mode 0)
		)
		(polygon
			(pts
				(arc
					(start 386.412994 -160.830006)
					(mid 383.986786 -160.830006)
					(end 386.412994 -160.830006)
				)
			)
		)
	)
	(zone
		(layers "In1.Cu" "In3.Cu" "In6.Cu" "In8.Cu")
		(hatch none 0.5)
		(connect_pads
			(clearance 0)
		)
		(min_thickness 0.25)
		(keepout
			(tracks not_allowed)
			(vias allowed)
			(pads allowed)
			(copperpour not_allowed)
			(footprints allowed)
		)
		(placement
			(enabled no)
			(sheetname "")
		)
		(fill yes
			(thermal_gap 0.5)
			(thermal_bridge_width 0.5)
			(island_removal_mode 0)
		)
		(polygon
			(pts
				(arc
					(start 115.630452 -14.986)
					(mid 113.852452 -14.986)
					(end 115.630452 -14.986)
				)
			)
		)
	)
	(zone
		(layers "In1.Cu" "In3.Cu" "In6.Cu" "In8.Cu")
		(hatch none 0.5)
		(connect_pads
			(clearance 0)
		)
		(min_thickness 0.25)
		(keepout
			(tracks not_allowed)
			(vias allowed)
			(pads allowed)
			(copperpour not_allowed)
			(footprints allowed)
		)
		(placement
			(enabled no)
			(sheetname "")
		)
		(fill yes
			(thermal_gap 0.5)
			(thermal_bridge_width 0.5)
			(island_removal_mode 0)
		)
		(polygon
			(pts
				(arc
					(start 114.106452 -26.2636)
					(mid 112.328452 -26.2636)
					(end 114.106452 -26.2636)
				)
			)
		)
	)
	(zone
		(layers "In1.Cu" "In3.Cu" "In6.Cu" "In8.Cu")
		(hatch none 0.5)
		(connect_pads
			(clearance 0)
		)
		(min_thickness 0.25)
		(keepout
			(tracks not_allowed)
			(vias allowed)
			(pads allowed)
			(copperpour not_allowed)
			(footprints allowed)
		)
		(placement
			(enabled no)
			(sheetname "")
		)
		(fill yes
			(thermal_gap 0.5)
			(thermal_bridge_width 0.5)
			(island_removal_mode 0)
		)
		(polygon
			(pts
				(arc
					(start 114.868452 -60.0964)
					(mid 113.090452 -60.0964)
					(end 114.868452 -60.0964)
				)
			)
		)
	)
	(zone
		(layers "In1.Cu" "In3.Cu" "In6.Cu" "In8.Cu")
		(hatch none 0.5)
		(connect_pads
			(clearance 0)
		)
		(min_thickness 0.25)
		(keepout
			(tracks not_allowed)
			(vias allowed)
			(pads allowed)
			(copperpour not_allowed)
			(footprints allowed)
		)
		(placement
			(enabled no)
			(sheetname "")
		)
		(fill yes
			(thermal_gap 0.5)
			(thermal_bridge_width 0.5)
			(island_removal_mode 0)
		)
		(polygon
			(pts
				(arc
					(start 43.379898 -111.879888)
					(mid 41.346882 -111.879888)
					(end 43.379898 -111.879888)
				)
			)
		)
	)
	(zone
		(layers "In1.Cu" "In3.Cu" "In6.Cu" "In8.Cu")
		(hatch none 0.5)
		(connect_pads
			(clearance 0)
		)
		(min_thickness 0.25)
		(keepout
			(tracks not_allowed)
			(vias allowed)
			(pads allowed)
			(copperpour not_allowed)
			(footprints allowed)
		)
		(placement
			(enabled no)
			(sheetname "")
		)
		(fill yes
			(thermal_gap 0.5)
			(thermal_bridge_width 0.5)
			(island_removal_mode 0)
		)
		(polygon
			(pts
				(arc
					(start 83.566 -3.81)
					(mid 81.788 -3.81)
					(end 83.566 -3.81)
				)
			)
		)
	)
	(zone
		(layers "In1.Cu" "In3.Cu" "In6.Cu" "In8.Cu")
		(hatch none 0.5)
		(connect_pads
			(clearance 0)
		)
		(min_thickness 0.25)
		(keepout
			(tracks not_allowed)
			(vias allowed)
			(pads allowed)
			(copperpour not_allowed)
			(footprints allowed)
		)
		(placement
			(enabled no)
			(sheetname "")
		)
		(fill yes
			(thermal_gap 0.5)
			(thermal_bridge_width 0.5)
			(island_removal_mode 0)
		)
		(polygon
			(pts
				(arc
					(start 85.852 -3.81)
					(mid 84.074 -3.81)
					(end 85.852 -3.81)
				)
			)
		)
	)
	(zone
		(layers "In1.Cu" "In3.Cu" "In6.Cu" "In8.Cu")
		(hatch none 0.5)
		(connect_pads
			(clearance 0)
		)
		(min_thickness 0.25)
		(keepout
			(tracks not_allowed)
			(vias allowed)
			(pads allowed)
			(copperpour not_allowed)
			(footprints allowed)
		)
		(placement
			(enabled no)
			(sheetname "")
		)
		(fill yes
			(thermal_gap 0.5)
			(thermal_bridge_width 0.5)
			(island_removal_mode 0)
		)
		(polygon
			(pts
				(arc
					(start 379.095508 -71.239888)
					(mid 377.062492 -71.239888)
					(end 379.095508 -71.239888)
				)
			)
		)
	)
	(zone
		(layers "In1.Cu" "In3.Cu" "In6.Cu" "In8.Cu")
		(hatch none 0.5)
		(connect_pads
			(clearance 0)
		)
		(min_thickness 0.25)
		(keepout
			(tracks not_allowed)
			(vias allowed)
			(pads allowed)
			(copperpour not_allowed)
			(footprints allowed)
		)
		(placement
			(enabled no)
			(sheetname "")
		)
		(fill yes
			(thermal_gap 0.5)
			(thermal_bridge_width 0.5)
			(island_removal_mode 0)
		)
		(polygon
			(pts
				(arc
					(start 115.630452 -59.3344)
					(mid 113.852452 -59.3344)
					(end 115.630452 -59.3344)
				)
			)
		)
	)
	(zone
		(layers "In1.Cu" "In3.Cu" "In6.Cu" "In8.Cu")
		(hatch none 0.5)
		(connect_pads
			(clearance 0)
		)
		(min_thickness 0.25)
		(keepout
			(tracks not_allowed)
			(vias allowed)
			(pads allowed)
			(copperpour not_allowed)
			(footprints allowed)
		)
		(placement
			(enabled no)
			(sheetname "")
		)
		(fill yes
			(thermal_gap 0.5)
			(thermal_bridge_width 0.5)
			(island_removal_mode 0)
		)
		(polygon
			(pts
				(arc
					(start 113.344452 -49.5808)
					(mid 111.566452 -49.5808)
					(end 113.344452 -49.5808)
				)
			)
		)
	)
	(zone
		(layers "In1.Cu" "In3.Cu" "In6.Cu" "In8.Cu")
		(hatch none 0.5)
		(connect_pads
			(clearance 0)
		)
		(min_thickness 0.25)
		(keepout
			(tracks not_allowed)
			(vias allowed)
			(pads allowed)
			(copperpour not_allowed)
			(footprints allowed)
		)
		(placement
			(enabled no)
			(sheetname "")
		)
		(fill yes
			(thermal_gap 0.5)
			(thermal_bridge_width 0.5)
			(island_removal_mode 0)
		)
		(polygon
			(pts
				(arc
					(start 335.3308 -66.675)
					(mid 333.5528 -66.675)
					(end 335.3308 -66.675)
				)
			)
		)
	)
	(zone
		(layers "In1.Cu" "In3.Cu" "In6.Cu" "In8.Cu")
		(hatch none 0.5)
		(connect_pads
			(clearance 0)
		)
		(min_thickness 0.25)
		(keepout
			(tracks not_allowed)
			(vias allowed)
			(pads allowed)
			(copperpour not_allowed)
			(footprints allowed)
		)
		(placement
			(enabled no)
			(sheetname "")
		)
		(fill yes
			(thermal_gap 0.5)
			(thermal_bridge_width 0.5)
			(island_removal_mode 0)
		)
		(polygon
			(pts
				(arc
					(start 113.344452 -15.748)
					(mid 111.566452 -15.748)
					(end 113.344452 -15.748)
				)
			)
		)
	)
	(zone
		(layers "In1.Cu" "In3.Cu" "In6.Cu" "In8.Cu")
		(hatch none 0.5)
		(connect_pads
			(clearance 0)
		)
		(min_thickness 0.25)
		(keepout
			(tracks not_allowed)
			(vias allowed)
			(pads allowed)
			(copperpour not_allowed)
			(footprints allowed)
		)
		(placement
			(enabled no)
			(sheetname "")
		)
		(fill yes
			(thermal_gap 0.5)
			(thermal_bridge_width 0.5)
			(island_removal_mode 0)
		)
		(polygon
			(pts
				(arc
					(start 333.8068 -53.8734)
					(mid 332.0288 -53.8734)
					(end 333.8068 -53.8734)
				)
			)
		)
	)
	(zone
		(layers "In1.Cu" "In3.Cu" "In6.Cu" "In8.Cu")
		(hatch none 0.5)
		(connect_pads
			(clearance 0)
		)
		(min_thickness 0.25)
		(keepout
			(tracks not_allowed)
			(vias allowed)
			(pads allowed)
			(copperpour not_allowed)
			(footprints allowed)
		)
		(placement
			(enabled no)
			(sheetname "")
		)
		(fill yes
			(thermal_gap 0.5)
			(thermal_bridge_width 0.5)
			(island_removal_mode 0)
		)
		(polygon
			(pts
				(arc
					(start 114.868452 -15.748)
					(mid 113.090452 -15.748)
					(end 114.868452 -15.748)
				)
			)
		)
	)
	(zone
		(layers "In1.Cu" "In3.Cu" "In6.Cu" "In8.Cu")
		(hatch none 0.5)
		(connect_pads
			(clearance 0)
		)
		(min_thickness 0.25)
		(keepout
			(tracks not_allowed)
			(vias allowed)
			(pads allowed)
			(copperpour not_allowed)
			(footprints allowed)
		)
		(placement
			(enabled no)
			(sheetname "")
		)
		(fill yes
			(thermal_gap 0.5)
			(thermal_bridge_width 0.5)
			(island_removal_mode 0)
		)
		(polygon
			(pts
				(arc
					(start 401.588224 -162.830002)
					(mid 399.162016 -162.830002)
					(end 401.588224 -162.830002)
				)
			)
		)
	)
	(zone
		(layers "In1.Cu" "In3.Cu" "In6.Cu" "In8.Cu")
		(hatch none 0.5)
		(connect_pads
			(clearance 0)
		)
		(min_thickness 0.25)
		(keepout
			(tracks not_allowed)
			(vias allowed)
			(pads allowed)
			(copperpour not_allowed)
			(footprints allowed)
		)
		(placement
			(enabled no)
			(sheetname "")
		)
		(fill yes
			(thermal_gap 0.5)
			(thermal_bridge_width 0.5)
			(island_removal_mode 0)
		)
		(polygon
			(pts
				(arc
					(start 113.344452 -39.0652)
					(mid 111.566452 -39.0652)
					(end 113.344452 -39.0652)
				)
			)
		)
	)
	(zone
		(layers "In1.Cu" "In3.Cu" "In6.Cu" "In8.Cu")
		(hatch none 0.5)
		(connect_pads
			(clearance 0)
		)
		(min_thickness 0.25)
		(keepout
			(tracks not_allowed)
			(vias allowed)
			(pads allowed)
			(copperpour not_allowed)
			(footprints allowed)
		)
		(placement
			(enabled no)
			(sheetname "")
		)
		(fill yes
			(thermal_gap 0.5)
			(thermal_bridge_width 0.5)
			(island_removal_mode 0)
		)
		(polygon
			(pts
				(arc
					(start 114.106452 -37.5412)
					(mid 112.328452 -37.5412)
					(end 114.106452 -37.5412)
				)
			)
		)
	)
	(zone
		(layers "In1.Cu" "In3.Cu" "In6.Cu" "In8.Cu")
		(hatch none 0.5)
		(connect_pads
			(clearance 0)
		)
		(min_thickness 0.25)
		(keepout
			(tracks not_allowed)
			(vias allowed)
			(pads allowed)
			(copperpour not_allowed)
			(footprints allowed)
		)
		(placement
			(enabled no)
			(sheetname "")
		)
		(fill yes
			(thermal_gap 0.5)
			(thermal_bridge_width 0.5)
			(island_removal_mode 0)
		)
		(polygon
			(pts
				(arc
					(start 333.0448 -55.3974)
					(mid 331.2668 -55.3974)
					(end 333.0448 -55.3974)
				)
			)
		)
	)
	(zone
		(layers "In1.Cu" "In3.Cu" "In6.Cu" "In8.Cu")
		(hatch none 0.5)
		(connect_pads
			(clearance 0)
		)
		(min_thickness 0.25)
		(keepout
			(tracks not_allowed)
			(vias allowed)
			(pads allowed)
			(copperpour not_allowed)
			(footprints allowed)
		)
		(placement
			(enabled no)
			(sheetname "")
		)
		(fill yes
			(thermal_gap 0.5)
			(thermal_bridge_width 0.5)
			(island_removal_mode 0)
		)
		(polygon
			(pts
				(arc
					(start 335.3308 -65.151)
					(mid 333.5528 -65.151)
					(end 335.3308 -65.151)
				)
			)
		)
	)
	(zone
		(layers "In1.Cu" "In3.Cu" "In6.Cu" "In8.Cu")
		(hatch none 0.5)
		(connect_pads
			(clearance 0)
		)
		(min_thickness 0.25)
		(keepout
			(tracks not_allowed)
			(vias allowed)
			(pads allowed)
			(copperpour not_allowed)
			(footprints allowed)
		)
		(placement
			(enabled no)
			(sheetname "")
		)
		(fill yes
			(thermal_gap 0.5)
			(thermal_bridge_width 0.5)
			(island_removal_mode 0)
		)
		(polygon
			(pts
				(arc
					(start 114.106452 -60.0964)
					(mid 112.328452 -60.0964)
					(end 114.106452 -60.0964)
				)
			)
		)
	)
	(zone
		(layers "In1.Cu" "In3.Cu" "In6.Cu" "In8.Cu")
		(hatch none 0.5)
		(connect_pads
			(clearance 0)
		)
		(min_thickness 0.25)
		(keepout
			(tracks not_allowed)
			(vias allowed)
			(pads allowed)
			(copperpour not_allowed)
			(footprints allowed)
		)
		(placement
			(enabled no)
			(sheetname "")
		)
		(fill yes
			(thermal_gap 0.5)
			(thermal_bridge_width 0.5)
			(island_removal_mode 0)
		)
		(polygon
			(pts
				(arc
					(start 335.3308 -31.3182)
					(mid 333.5528 -31.3182)
					(end 335.3308 -31.3182)
				)
			)
		)
	)
	(zone
		(layers "In1.Cu" "In3.Cu" "In6.Cu" "In8.Cu")
		(hatch none 0.5)
		(connect_pads
			(clearance 0)
		)
		(min_thickness 0.25)
		(keepout
			(tracks not_allowed)
			(vias allowed)
			(pads allowed)
			(copperpour not_allowed)
			(footprints allowed)
		)
		(placement
			(enabled no)
			(sheetname "")
		)
		(fill yes
			(thermal_gap 0.5)
			(thermal_bridge_width 0.5)
			(island_removal_mode 0)
		)
		(polygon
			(pts
				(arc
					(start 70.21322 -158.83001)
					(mid 67.787012 -158.83001)
					(end 70.21322 -158.83001)
				)
			)
		)
	)
	(zone
		(layers "In1.Cu" "In3.Cu" "In6.Cu" "In8.Cu")
		(hatch none 0.5)
		(connect_pads
			(clearance 0)
		)
		(min_thickness 0.25)
		(keepout
			(tracks not_allowed)
			(vias allowed)
			(pads allowed)
			(copperpour not_allowed)
			(footprints allowed)
		)
		(placement
			(enabled no)
			(sheetname "")
		)
		(fill yes
			(thermal_gap 0.5)
			(thermal_bridge_width 0.5)
			(island_removal_mode 0)
		)
		(polygon
			(pts
				(arc
					(start 336.0928 -77.1906)
					(mid 334.3148 -77.1906)
					(end 336.0928 -77.1906)
				)
			)
		)
	)
	(zone
		(layers "In1.Cu" "In3.Cu" "In6.Cu" "In8.Cu")
		(hatch none 0.5)
		(connect_pads
			(clearance 0)
		)
		(min_thickness 0.25)
		(keepout
			(tracks not_allowed)
			(vias allowed)
			(pads allowed)
			(copperpour not_allowed)
			(footprints allowed)
		)
		(placement
			(enabled no)
			(sheetname "")
		)
		(fill yes
			(thermal_gap 0.5)
			(thermal_bridge_width 0.5)
			(island_removal_mode 0)
		)
		(polygon
			(pts
				(arc
					(start 83.566 -5.334)
					(mid 81.788 -5.334)
					(end 83.566 -5.334)
				)
			)
		)
	)
	(zone
		(layers "In1.Cu" "In3.Cu" "In6.Cu" "In8.Cu")
		(hatch none 0.5)
		(connect_pads
			(clearance 0)
		)
		(min_thickness 0.25)
		(keepout
			(tracks not_allowed)
			(vias allowed)
			(pads allowed)
			(copperpour not_allowed)
			(footprints allowed)
		)
		(placement
			(enabled no)
			(sheetname "")
		)
		(fill yes
			(thermal_gap 0.5)
			(thermal_bridge_width 0.5)
			(island_removal_mode 0)
		)
		(polygon
			(pts
				(arc
					(start 335.3308 -54.6354)
					(mid 333.5528 -54.6354)
					(end 335.3308 -54.6354)
				)
			)
		)
	)
	(zone
		(layers "In1.Cu" "In3.Cu" "In6.Cu" "In8.Cu")
		(hatch none 0.5)
		(connect_pads
			(clearance 0)
		)
		(min_thickness 0.25)
		(keepout
			(tracks not_allowed)
			(vias allowed)
			(pads allowed)
			(copperpour not_allowed)
			(footprints allowed)
		)
		(placement
			(enabled no)
			(sheetname "")
		)
		(fill yes
			(thermal_gap 0.5)
			(thermal_bridge_width 0.5)
			(island_removal_mode 0)
		)
		(polygon
			(pts
				(arc
					(start 113.344452 -73.66)
					(mid 111.566452 -73.66)
					(end 113.344452 -73.66)
				)
			)
		)
	)
	(zone
		(layers "In1.Cu" "In3.Cu" "In6.Cu" "In8.Cu")
		(hatch none 0.5)
		(connect_pads
			(clearance 0)
		)
		(min_thickness 0.25)
		(keepout
			(tracks not_allowed)
			(vias allowed)
			(pads allowed)
			(copperpour not_allowed)
			(footprints allowed)
		)
		(placement
			(enabled no)
			(sheetname "")
		)
		(fill yes
			(thermal_gap 0.5)
			(thermal_bridge_width 0.5)
			(island_removal_mode 0)
		)
		(polygon
			(pts
				(arc
					(start 384.412998 -160.830006)
					(mid 381.98679 -160.830006)
					(end 384.412998 -160.830006)
				)
			)
		)
	)
	(zone
		(layers "In1.Cu" "In3.Cu" "In6.Cu" "In8.Cu")
		(hatch none 0.5)
		(connect_pads
			(clearance 0)
		)
		(min_thickness 0.25)
		(keepout
			(tracks not_allowed)
			(vias allowed)
			(pads allowed)
			(copperpour not_allowed)
			(footprints allowed)
		)
		(placement
			(enabled no)
			(sheetname "")
		)
		(fill yes
			(thermal_gap 0.5)
			(thermal_bridge_width 0.5)
			(island_removal_mode 0)
		)
		(polygon
			(pts
				(arc
					(start 333.8068 -32.8422)
					(mid 332.0288 -32.8422)
					(end 333.8068 -32.8422)
				)
			)
		)
	)
	(zone
		(layers "In1.Cu" "In3.Cu" "In6.Cu" "In8.Cu")
		(hatch none 0.5)
		(connect_pads
			(clearance 0)
		)
		(min_thickness 0.25)
		(keepout
			(tracks not_allowed)
			(vias allowed)
			(pads allowed)
			(copperpour not_allowed)
			(footprints allowed)
		)
		(placement
			(enabled no)
			(sheetname "")
		)
		(fill yes
			(thermal_gap 0.5)
			(thermal_bridge_width 0.5)
			(island_removal_mode 0)
		)
		(polygon
			(pts
				(arc
					(start 334.5688 -23.0886)
					(mid 332.7908 -23.0886)
					(end 334.5688 -23.0886)
				)
			)
		)
	)
	(zone
		(layers "In1.Cu" "In3.Cu" "In6.Cu" "In8.Cu")
		(hatch none 0.5)
		(connect_pads
			(clearance 0)
		)
		(min_thickness 0.25)
		(keepout
			(tracks not_allowed)
			(vias allowed)
			(pads allowed)
			(copperpour not_allowed)
			(footprints allowed)
		)
		(placement
			(enabled no)
			(sheetname "")
		)
		(fill yes
			(thermal_gap 0.5)
			(thermal_bridge_width 0.5)
			(island_removal_mode 0)
		)
		(polygon
			(pts
				(arc
					(start 50.013108 -158.83001)
					(mid 47.5869 -158.83001)
					(end 50.013108 -158.83001)
				)
			)
		)
	)
	(zone
		(layers "In1.Cu" "In3.Cu" "In6.Cu" "In8.Cu")
		(hatch none 0.5)
		(connect_pads
			(clearance 0)
		)
		(min_thickness 0.25)
		(keepout
			(tracks not_allowed)
			(vias allowed)
			(pads allowed)
			(copperpour not_allowed)
			(footprints allowed)
		)
		(placement
			(enabled no)
			(sheetname "")
		)
		(fill yes
			(thermal_gap 0.5)
			(thermal_bridge_width 0.5)
			(island_removal_mode 0)
		)
		(polygon
			(pts
				(arc
					(start 113.344452 -51.1048)
					(mid 111.566452 -51.1048)
					(end 113.344452 -51.1048)
				)
			)
		)
	)
	(zone
		(layers "In1.Cu" "In3.Cu" "In6.Cu" "In8.Cu")
		(hatch none 0.5)
		(connect_pads
			(clearance 0)
		)
		(min_thickness 0.25)
		(keepout
			(tracks not_allowed)
			(vias allowed)
			(pads allowed)
			(copperpour not_allowed)
			(footprints allowed)
		)
		(placement
			(enabled no)
			(sheetname "")
		)
		(fill yes
			(thermal_gap 0.5)
			(thermal_bridge_width 0.5)
			(island_removal_mode 0)
		)
		(polygon
			(pts
				(arc
					(start 38.088062 -152.830022)
					(mid 35.661854 -152.830022)
					(end 38.088062 -152.830022)
				)
			)
		)
	)
	(zone
		(layers "In1.Cu" "In3.Cu" "In6.Cu" "In8.Cu")
		(hatch none 0.5)
		(connect_pads
			(clearance 0)
		)
		(min_thickness 0.25)
		(keepout
			(tracks not_allowed)
			(vias allowed)
			(pads allowed)
			(copperpour not_allowed)
			(footprints allowed)
		)
		(placement
			(enabled no)
			(sheetname "")
		)
		(fill yes
			(thermal_gap 0.5)
			(thermal_bridge_width 0.5)
			(island_removal_mode 0)
		)
		(polygon
			(pts
				(arc
					(start 336.0928 -34.3662)
					(mid 334.3148 -34.3662)
					(end 336.0928 -34.3662)
				)
			)
		)
	)
	(zone
		(layers "In1.Cu" "In3.Cu" "In6.Cu" "In8.Cu")
		(hatch none 0.5)
		(connect_pads
			(clearance 0)
		)
		(min_thickness 0.25)
		(keepout
			(tracks not_allowed)
			(vias allowed)
			(pads allowed)
			(copperpour not_allowed)
			(footprints allowed)
		)
		(placement
			(enabled no)
			(sheetname "")
		)
		(fill yes
			(thermal_gap 0.5)
			(thermal_bridge_width 0.5)
			(island_removal_mode 0)
		)
		(polygon
			(pts
				(arc
					(start 115.630452 -72.898)
					(mid 113.852452 -72.898)
					(end 115.630452 -72.898)
				)
			)
		)
	)
	(zone
		(layers "In1.Cu" "In3.Cu" "In6.Cu" "In8.Cu")
		(hatch none 0.5)
		(connect_pads
			(clearance 0)
		)
		(min_thickness 0.25)
		(keepout
			(tracks not_allowed)
			(vias allowed)
			(pads allowed)
			(copperpour not_allowed)
			(footprints allowed)
		)
		(placement
			(enabled no)
			(sheetname "")
		)
		(fill yes
			(thermal_gap 0.5)
			(thermal_bridge_width 0.5)
			(island_removal_mode 0)
		)
		(polygon
			(pts
				(arc
					(start 333.0448 -43.3578)
					(mid 331.2668 -43.3578)
					(end 333.0448 -43.3578)
				)
			)
		)
	)
	(zone
		(layers "In1.Cu" "In3.Cu" "In6.Cu" "In8.Cu")
		(hatch none 0.5)
		(connect_pads
			(clearance 0)
		)
		(min_thickness 0.25)
		(keepout
			(tracks not_allowed)
			(vias allowed)
			(pads allowed)
			(copperpour not_allowed)
			(footprints allowed)
		)
		(placement
			(enabled no)
			(sheetname "")
		)
		(fill yes
			(thermal_gap 0.5)
			(thermal_bridge_width 0.5)
			(island_removal_mode 0)
		)
		(polygon
			(pts
				(arc
					(start 401.588224 -156.830014)
					(mid 399.162016 -156.830014)
					(end 401.588224 -156.830014)
				)
			)
		)
	)
	(zone
		(layers "In1.Cu" "In3.Cu" "In6.Cu" "In8.Cu")
		(hatch none 0.5)
		(connect_pads
			(clearance 0)
		)
		(min_thickness 0.25)
		(keepout
			(tracks not_allowed)
			(vias allowed)
			(pads allowed)
			(copperpour not_allowed)
			(footprints allowed)
		)
		(placement
			(enabled no)
			(sheetname "")
		)
		(fill yes
			(thermal_gap 0.5)
			(thermal_bridge_width 0.5)
			(island_removal_mode 0)
		)
		(polygon
			(pts
				(arc
					(start 336.0928 -53.8734)
					(mid 334.3148 -53.8734)
					(end 336.0928 -53.8734)
				)
			)
		)
	)
	(zone
		(layers "In1.Cu" "In3.Cu" "In6.Cu" "In8.Cu")
		(hatch none 0.5)
		(connect_pads
			(clearance 0)
		)
		(min_thickness 0.25)
		(keepout
			(tracks not_allowed)
			(vias allowed)
			(pads allowed)
			(copperpour not_allowed)
			(footprints allowed)
		)
		(placement
			(enabled no)
			(sheetname "")
		)
		(fill yes
			(thermal_gap 0.5)
			(thermal_bridge_width 0.5)
			(island_removal_mode 0)
		)
		(polygon
			(pts
				(arc
					(start 72.213216 -160.830006)
					(mid 69.787008 -160.830006)
					(end 72.213216 -160.830006)
				)
			)
		)
	)
	(zone
		(layers "In1.Cu" "In3.Cu" "In6.Cu" "In8.Cu")
		(hatch none 0.5)
		(connect_pads
			(clearance 0)
		)
		(min_thickness 0.25)
		(keepout
			(tracks not_allowed)
			(vias allowed)
			(pads allowed)
			(copperpour not_allowed)
			(footprints allowed)
		)
		(placement
			(enabled no)
			(sheetname "")
		)
		(fill yes
			(thermal_gap 0.5)
			(thermal_bridge_width 0.5)
			(island_removal_mode 0)
		)
		(polygon
			(pts
				(arc
					(start 86.614 -4.572)
					(mid 84.836 -4.572)
					(end 86.614 -4.572)
				)
			)
		)
	)
	(zone
		(layers "In1.Cu" "In3.Cu" "In6.Cu" "In8.Cu")
		(hatch none 0.5)
		(connect_pads
			(clearance 0)
		)
		(min_thickness 0.25)
		(keepout
			(tracks not_allowed)
			(vias allowed)
			(pads allowed)
			(copperpour not_allowed)
			(footprints allowed)
		)
		(placement
			(enabled no)
			(sheetname "")
		)
		(fill yes
			(thermal_gap 0.5)
			(thermal_bridge_width 0.5)
			(island_removal_mode 0)
		)
		(polygon
			(pts
				(arc
					(start 78.213204 -156.830014)
					(mid 75.786996 -156.830014)
					(end 78.213204 -156.830014)
				)
			)
		)
	)
	(zone
		(layers "In1.Cu" "In3.Cu" "In6.Cu" "In8.Cu")
		(hatch none 0.5)
		(connect_pads
			(clearance 0)
		)
		(min_thickness 0.25)
		(keepout
			(tracks not_allowed)
			(vias allowed)
			(pads allowed)
			(copperpour not_allowed)
			(footprints allowed)
		)
		(placement
			(enabled no)
			(sheetname "")
		)
		(fill yes
			(thermal_gap 0.5)
			(thermal_bridge_width 0.5)
			(island_removal_mode 0)
		)
		(polygon
			(pts
				(arc
					(start 334.5688 -53.8734)
					(mid 332.7908 -53.8734)
					(end 334.5688 -53.8734)
				)
			)
		)
	)
	(zone
		(layers "In1.Cu" "In3.Cu" "In6.Cu" "In8.Cu")
		(hatch none 0.5)
		(connect_pads
			(clearance 0)
		)
		(min_thickness 0.25)
		(keepout
			(tracks not_allowed)
			(vias allowed)
			(pads allowed)
			(copperpour not_allowed)
			(footprints allowed)
		)
		(placement
			(enabled no)
			(sheetname "")
		)
		(fill yes
			(thermal_gap 0.5)
			(thermal_bridge_width 0.5)
			(island_removal_mode 0)
		)
		(polygon
			(pts
				(arc
					(start 335.3308 -22.3266)
					(mid 333.5528 -22.3266)
					(end 335.3308 -22.3266)
				)
			)
		)
	)
	(zone
		(layers "In1.Cu" "In3.Cu" "In6.Cu" "In8.Cu")
		(hatch none 0.5)
		(connect_pads
			(clearance 0)
		)
		(min_thickness 0.25)
		(keepout
			(tracks not_allowed)
			(vias allowed)
			(pads allowed)
			(copperpour not_allowed)
			(footprints allowed)
		)
		(placement
			(enabled no)
			(sheetname "")
		)
		(fill yes
			(thermal_gap 0.5)
			(thermal_bridge_width 0.5)
			(island_removal_mode 0)
		)
		(polygon
			(pts
				(arc
					(start 72.213216 -156.830014)
					(mid 69.787008 -156.830014)
					(end 72.213216 -156.830014)
				)
			)
		)
	)
	(zone
		(layers "In1.Cu" "In3.Cu" "In6.Cu" "In8.Cu")
		(hatch none 0.5)
		(connect_pads
			(clearance 0)
		)
		(min_thickness 0.25)
		(keepout
			(tracks not_allowed)
			(vias allowed)
			(pads allowed)
			(copperpour not_allowed)
			(footprints allowed)
		)
		(placement
			(enabled no)
			(sheetname "")
		)
		(fill yes
			(thermal_gap 0.5)
			(thermal_bridge_width 0.5)
			(island_removal_mode 0)
		)
		(polygon
			(pts
				(arc
					(start 336.0928 -42.5958)
					(mid 334.3148 -42.5958)
					(end 336.0928 -42.5958)
				)
			)
		)
	)
	(zone
		(layers "In1.Cu" "In3.Cu" "In6.Cu" "In8.Cu")
		(hatch none 0.5)
		(connect_pads
			(clearance 0)
		)
		(min_thickness 0.25)
		(keepout
			(tracks not_allowed)
			(vias allowed)
			(pads allowed)
			(copperpour not_allowed)
			(footprints allowed)
		)
		(placement
			(enabled no)
			(sheetname "")
		)
		(fill yes
			(thermal_gap 0.5)
			(thermal_bridge_width 0.5)
			(island_removal_mode 0)
		)
		(polygon
			(pts
				(arc
					(start 113.344452 -48.0568)
					(mid 111.566452 -48.0568)
					(end 113.344452 -48.0568)
				)
			)
		)
	)
	(zone
		(layers "In1.Cu" "In3.Cu" "In6.Cu" "In8.Cu")
		(hatch none 0.5)
		(connect_pads
			(clearance 0)
		)
		(min_thickness 0.25)
		(keepout
			(tracks not_allowed)
			(vias allowed)
			(pads allowed)
			(copperpour not_allowed)
			(footprints allowed)
		)
		(placement
			(enabled no)
			(sheetname "")
		)
		(fill yes
			(thermal_gap 0.5)
			(thermal_bridge_width 0.5)
			(island_removal_mode 0)
		)
		(polygon
			(pts
				(arc
					(start 114.106452 -39.0652)
					(mid 112.328452 -39.0652)
					(end 114.106452 -39.0652)
				)
			)
		)
	)
	(zone
		(layers "In1.Cu" "In3.Cu" "In6.Cu" "In8.Cu")
		(hatch none 0.5)
		(connect_pads
			(clearance 0)
		)
		(min_thickness 0.25)
		(keepout
			(tracks not_allowed)
			(vias allowed)
			(pads allowed)
			(copperpour not_allowed)
			(footprints allowed)
		)
		(placement
			(enabled no)
			(sheetname "")
		)
		(fill yes
			(thermal_gap 0.5)
			(thermal_bridge_width 0.5)
			(island_removal_mode 0)
		)
		(polygon
			(pts
				(arc
					(start 399.161 -139.7)
					(mid 396.113 -139.7)
					(end 399.161 -139.7)
				)
			)
		)
	)
	(zone
		(layers "In1.Cu" "In3.Cu" "In6.Cu" "In8.Cu")
		(hatch none 0.5)
		(connect_pads
			(clearance 0)
		)
		(min_thickness 0.25)
		(keepout
			(tracks not_allowed)
			(vias allowed)
			(pads allowed)
			(copperpour not_allowed)
			(footprints allowed)
		)
		(placement
			(enabled no)
			(sheetname "")
		)
		(fill yes
			(thermal_gap 0.5)
			(thermal_bridge_width 0.5)
			(island_removal_mode 0)
		)
		(polygon
			(pts
				(arc
					(start 78.213204 -160.830006)
					(mid 75.786996 -160.830006)
					(end 78.213204 -160.830006)
				)
			)
		)
	)
	(zone
		(layers "In1.Cu" "In3.Cu" "In6.Cu" "In8.Cu")
		(hatch none 0.5)
		(connect_pads
			(clearance 0)
		)
		(min_thickness 0.25)
		(keepout
			(tracks not_allowed)
			(vias allowed)
			(pads allowed)
			(copperpour not_allowed)
			(footprints allowed)
		)
		(placement
			(enabled no)
			(sheetname "")
		)
		(fill yes
			(thermal_gap 0.5)
			(thermal_bridge_width 0.5)
			(island_removal_mode 0)
		)
		(polygon
			(pts
				(arc
					(start 114.106452 -71.374)
					(mid 112.328452 -71.374)
					(end 114.106452 -71.374)
				)
			)
		)
	)
	(zone
		(layers "In1.Cu" "In3.Cu" "In6.Cu" "In8.Cu")
		(hatch none 0.5)
		(connect_pads
			(clearance 0)
		)
		(min_thickness 0.25)
		(keepout
			(tracks not_allowed)
			(vias allowed)
			(pads allowed)
			(copperpour not_allowed)
			(footprints allowed)
		)
		(placement
			(enabled no)
			(sheetname "")
		)
		(fill yes
			(thermal_gap 0.5)
			(thermal_bridge_width 0.5)
			(island_removal_mode 0)
		)
		(polygon
			(pts
				(arc
					(start 116.392452 -39.8272)
					(mid 114.614452 -39.8272)
					(end 116.392452 -39.8272)
				)
			)
		)
	)
	(zone
		(layers "In1.Cu" "In3.Cu" "In6.Cu" "In8.Cu")
		(hatch none 0.5)
		(connect_pads
			(clearance 0)
		)
		(min_thickness 0.25)
		(keepout
			(tracks not_allowed)
			(vias allowed)
			(pads allowed)
			(copperpour not_allowed)
			(footprints allowed)
		)
		(placement
			(enabled no)
			(sheetname "")
		)
		(fill yes
			(thermal_gap 0.5)
			(thermal_bridge_width 0.5)
			(island_removal_mode 0)
		)
		(polygon
			(pts
				(arc
					(start 384.412998 -156.830014)
					(mid 381.98679 -156.830014)
					(end 384.412998 -156.830014)
				)
			)
		)
	)
	(zone
		(layers "In1.Cu" "In3.Cu" "In6.Cu" "In8.Cu")
		(hatch none 0.5)
		(connect_pads
			(clearance 0)
		)
		(min_thickness 0.25)
		(keepout
			(tracks not_allowed)
			(vias allowed)
			(pads allowed)
			(copperpour not_allowed)
			(footprints allowed)
		)
		(placement
			(enabled no)
			(sheetname "")
		)
		(fill yes
			(thermal_gap 0.5)
			(thermal_bridge_width 0.5)
			(island_removal_mode 0)
		)
		(polygon
			(pts
				(arc
					(start 333.0448 -31.3182)
					(mid 331.2668 -31.3182)
					(end 333.0448 -31.3182)
				)
			)
		)
	)
	(zone
		(layers "In1.Cu" "In3.Cu" "In6.Cu" "In8.Cu")
		(hatch none 0.5)
		(connect_pads
			(clearance 0)
		)
		(min_thickness 0.25)
		(keepout
			(tracks not_allowed)
			(vias allowed)
			(pads allowed)
			(copperpour not_allowed)
			(footprints allowed)
		)
		(placement
			(enabled no)
			(sheetname "")
		)
		(fill yes
			(thermal_gap 0.5)
			(thermal_bridge_width 0.5)
			(island_removal_mode 0)
		)
		(polygon
			(pts
				(arc
					(start 114.868452 -73.66)
					(mid 113.090452 -73.66)
					(end 114.868452 -73.66)
				)
			)
		)
	)
	(zone
		(layers "In1.Cu" "In3.Cu" "In6.Cu" "In8.Cu")
		(hatch none 0.5)
		(connect_pads
			(clearance 0)
		)
		(min_thickness 0.25)
		(keepout
			(tracks not_allowed)
			(vias allowed)
			(pads allowed)
			(copperpour not_allowed)
			(footprints allowed)
		)
		(placement
			(enabled no)
			(sheetname "")
		)
		(fill yes
			(thermal_gap 0.5)
			(thermal_bridge_width 0.5)
			(island_removal_mode 0)
		)
		(polygon
			(pts
				(arc
					(start 116.392452 -27.0256)
					(mid 114.614452 -27.0256)
					(end 116.392452 -27.0256)
				)
			)
		)
	)
	(zone
		(layers "In1.Cu" "In3.Cu" "In6.Cu" "In8.Cu")
		(hatch none 0.5)
		(connect_pads
			(clearance 0)
		)
		(min_thickness 0.25)
		(keepout
			(tracks not_allowed)
			(vias allowed)
			(pads allowed)
			(copperpour not_allowed)
			(footprints allowed)
		)
		(placement
			(enabled no)
			(sheetname "")
		)
		(fill yes
			(thermal_gap 0.5)
			(thermal_bridge_width 0.5)
			(island_removal_mode 0)
		)
		(polygon
			(pts
				(arc
					(start 113.344452 -60.0964)
					(mid 111.566452 -60.0964)
					(end 113.344452 -60.0964)
				)
			)
		)
	)
	(zone
		(layers "In1.Cu" "In3.Cu" "In6.Cu" "In8.Cu")
		(hatch none 0.5)
		(connect_pads
			(clearance 0)
		)
		(min_thickness 0.25)
		(keepout
			(tracks not_allowed)
			(vias allowed)
			(pads allowed)
			(copperpour not_allowed)
			(footprints allowed)
		)
		(placement
			(enabled no)
			(sheetname "")
		)
		(fill yes
			(thermal_gap 0.5)
			(thermal_bridge_width 0.5)
			(island_removal_mode 0)
		)
		(polygon
			(pts
				(arc
					(start 70.21322 -156.830014)
					(mid 67.787012 -156.830014)
					(end 70.21322 -156.830014)
				)
			)
		)
	)
	(zone
		(layers "In1.Cu" "In3.Cu" "In6.Cu" "In8.Cu")
		(hatch none 0.5)
		(connect_pads
			(clearance 0)
		)
		(min_thickness 0.25)
		(keepout
			(tracks not_allowed)
			(vias allowed)
			(pads allowed)
			(copperpour not_allowed)
			(footprints allowed)
		)
		(placement
			(enabled no)
			(sheetname "")
		)
		(fill yes
			(thermal_gap 0.5)
			(thermal_bridge_width 0.5)
			(island_removal_mode 0)
		)
		(polygon
			(pts
				(arc
					(start 357.30942 -5.353304)
					(mid 355.53142 -5.353304)
					(end 357.30942 -5.353304)
				)
			)
		)
	)
	(zone
		(layers "In1.Cu" "In3.Cu" "In6.Cu" "In8.Cu")
		(hatch none 0.5)
		(connect_pads
			(clearance 0)
		)
		(min_thickness 0.25)
		(keepout
			(tracks not_allowed)
			(vias allowed)
			(pads allowed)
			(copperpour not_allowed)
			(footprints allowed)
		)
		(placement
			(enabled no)
			(sheetname "")
		)
		(fill yes
			(thermal_gap 0.5)
			(thermal_bridge_width 0.5)
			(island_removal_mode 0)
		)
		(polygon
			(pts
				(arc
					(start 336.0928 -55.3974)
					(mid 334.3148 -55.3974)
					(end 336.0928 -55.3974)
				)
			)
		)
	)
	(zone
		(layers "In1.Cu" "In3.Cu" "In6.Cu" "In8.Cu")
		(hatch none 0.5)
		(connect_pads
			(clearance 0)
		)
		(min_thickness 0.25)
		(keepout
			(tracks not_allowed)
			(vias allowed)
			(pads allowed)
			(copperpour not_allowed)
			(footprints allowed)
		)
		(placement
			(enabled no)
			(sheetname "")
		)
		(fill yes
			(thermal_gap 0.5)
			(thermal_bridge_width 0.5)
			(island_removal_mode 0)
		)
		(polygon
			(pts
				(arc
					(start 114.868452 -17.272)
					(mid 113.090452 -17.272)
					(end 114.868452 -17.272)
				)
			)
		)
	)
	(zone
		(layers "In1.Cu" "In3.Cu" "In6.Cu" "In8.Cu")
		(hatch none 0.5)
		(connect_pads
			(clearance 0)
		)
		(min_thickness 0.25)
		(keepout
			(tracks not_allowed)
			(vias allowed)
			(pads allowed)
			(copperpour not_allowed)
			(footprints allowed)
		)
		(placement
			(enabled no)
			(sheetname "")
		)
		(fill yes
			(thermal_gap 0.5)
			(thermal_bridge_width 0.5)
			(island_removal_mode 0)
		)
		(polygon
			(pts
				(arc
					(start 370.213128 -160.830006)
					(mid 367.78692 -160.830006)
					(end 370.213128 -160.830006)
				)
			)
		)
	)
	(zone
		(layers "In1.Cu" "In3.Cu" "In6.Cu" "In8.Cu")
		(hatch none 0.5)
		(connect_pads
			(clearance 0)
		)
		(min_thickness 0.25)
		(keepout
			(tracks not_allowed)
			(vias allowed)
			(pads allowed)
			(copperpour not_allowed)
			(footprints allowed)
		)
		(placement
			(enabled no)
			(sheetname "")
		)
		(fill yes
			(thermal_gap 0.5)
			(thermal_bridge_width 0.5)
			(island_removal_mode 0)
		)
		(polygon
			(pts
				(arc
					(start 85.09 -4.572)
					(mid 83.312 -4.572)
					(end 85.09 -4.572)
				)
			)
		)
	)
	(zone
		(layers "In1.Cu" "In3.Cu" "In6.Cu" "In8.Cu")
		(hatch none 0.5)
		(connect_pads
			(clearance 0)
		)
		(min_thickness 0.25)
		(keepout
			(tracks not_allowed)
			(vias allowed)
			(pads allowed)
			(copperpour not_allowed)
			(footprints allowed)
		)
		(placement
			(enabled no)
			(sheetname "")
		)
		(fill yes
			(thermal_gap 0.5)
			(thermal_bridge_width 0.5)
			(island_removal_mode 0)
		)
		(polygon
			(pts
				(arc
					(start 114.868452 -28.5496)
					(mid 113.090452 -28.5496)
					(end 114.868452 -28.5496)
				)
			)
		)
	)
	(zone
		(layers "In1.Cu" "In3.Cu" "In6.Cu" "In8.Cu")
		(hatch none 0.5)
		(connect_pads
			(clearance 0)
		)
		(min_thickness 0.25)
		(keepout
			(tracks not_allowed)
			(vias allowed)
			(pads allowed)
			(copperpour not_allowed)
			(footprints allowed)
		)
		(placement
			(enabled no)
			(sheetname "")
		)
		(fill yes
			(thermal_gap 0.5)
			(thermal_bridge_width 0.5)
			(island_removal_mode 0)
		)
		(polygon
			(pts
				(arc
					(start 114.868452 -27.0256)
					(mid 113.090452 -27.0256)
					(end 114.868452 -27.0256)
				)
			)
		)
	)
	(zone
		(layers "In1.Cu" "In3.Cu" "In6.Cu" "In8.Cu")
		(hatch none 0.5)
		(connect_pads
			(clearance 0)
		)
		(min_thickness 0.25)
		(keepout
			(tracks not_allowed)
			(vias allowed)
			(pads allowed)
			(copperpour not_allowed)
			(footprints allowed)
		)
		(placement
			(enabled no)
			(sheetname "")
		)
		(fill yes
			(thermal_gap 0.5)
			(thermal_bridge_width 0.5)
			(island_removal_mode 0)
		)
		(polygon
			(pts
				(arc
					(start 114.868452 -48.8188)
					(mid 113.090452 -48.8188)
					(end 114.868452 -48.8188)
				)
			)
		)
	)
	(zone
		(layers "In1.Cu" "In3.Cu" "In6.Cu" "In8.Cu")
		(hatch none 0.5)
		(connect_pads
			(clearance 0)
		)
		(min_thickness 0.25)
		(keepout
			(tracks not_allowed)
			(vias allowed)
			(pads allowed)
			(copperpour not_allowed)
			(footprints allowed)
		)
		(placement
			(enabled no)
			(sheetname "")
		)
		(fill yes
			(thermal_gap 0.5)
			(thermal_bridge_width 0.5)
			(island_removal_mode 0)
		)
		(polygon
			(pts
				(arc
					(start 115.630452 -49.5808)
					(mid 113.852452 -49.5808)
					(end 115.630452 -49.5808)
				)
			)
		)
	)
	(zone
		(layers "In1.Cu" "In3.Cu" "In6.Cu" "In8.Cu")
		(hatch none 0.5)
		(connect_pads
			(clearance 0)
		)
		(min_thickness 0.25)
		(keepout
			(tracks not_allowed)
			(vias allowed)
			(pads allowed)
			(copperpour not_allowed)
			(footprints allowed)
		)
		(placement
			(enabled no)
			(sheetname "")
		)
		(fill yes
			(thermal_gap 0.5)
			(thermal_bridge_width 0.5)
			(island_removal_mode 0)
		)
		(polygon
			(pts
				(arc
					(start 470.329768 -76.309982)
					(mid 467.510368 -76.309982)
					(end 470.329768 -76.309982)
				)
			)
		)
	)
	(zone
		(layers "In1.Cu" "In3.Cu" "In6.Cu" "In8.Cu")
		(hatch none 0.5)
		(connect_pads
			(clearance 0)
		)
		(min_thickness 0.25)
		(keepout
			(tracks not_allowed)
			(vias allowed)
			(pads allowed)
			(copperpour not_allowed)
			(footprints allowed)
		)
		(placement
			(enabled no)
			(sheetname "")
		)
		(fill yes
			(thermal_gap 0.5)
			(thermal_bridge_width 0.5)
			(island_removal_mode 0)
		)
		(polygon
			(pts
				(arc
					(start 473.029788 -71.229982)
					(mid 470.210388 -71.229982)
					(end 473.029788 -71.229982)
				)
			)
		)
	)
	(zone
		(layers "In1.Cu" "In3.Cu" "In6.Cu" "In8.Cu")
		(hatch none 0.5)
		(connect_pads
			(clearance 0)
		)
		(min_thickness 0.25)
		(keepout
			(tracks not_allowed)
			(vias allowed)
			(pads allowed)
			(copperpour not_allowed)
			(footprints allowed)
		)
		(placement
			(enabled no)
			(sheetname "")
		)
		(fill yes
			(thermal_gap 0.5)
			(thermal_bridge_width 0.5)
			(island_removal_mode 0)
		)
		(polygon
			(pts
				(arc
					(start 334.5688 -45.6438)
					(mid 332.7908 -45.6438)
					(end 334.5688 -45.6438)
				)
			)
		)
	)
	(zone
		(layers "In1.Cu" "In3.Cu" "In6.Cu" "In8.Cu")
		(hatch none 0.5)
		(connect_pads
			(clearance 0)
		)
		(min_thickness 0.25)
		(keepout
			(tracks not_allowed)
			(vias allowed)
			(pads allowed)
			(copperpour not_allowed)
			(footprints allowed)
		)
		(placement
			(enabled no)
			(sheetname "")
		)
		(fill yes
			(thermal_gap 0.5)
			(thermal_bridge_width 0.5)
			(island_removal_mode 0)
		)
		(polygon
			(pts
				(arc
					(start 113.344452 -39.8272)
					(mid 111.566452 -39.8272)
					(end 113.344452 -39.8272)
				)
			)
		)
	)
	(zone
		(layers "In1.Cu" "In3.Cu" "In6.Cu" "In8.Cu")
		(hatch none 0.5)
		(connect_pads
			(clearance 0)
		)
		(min_thickness 0.25)
		(keepout
			(tracks not_allowed)
			(vias allowed)
			(pads allowed)
			(copperpour not_allowed)
			(footprints allowed)
		)
		(placement
			(enabled no)
			(sheetname "")
		)
		(fill yes
			(thermal_gap 0.5)
			(thermal_bridge_width 0.5)
			(island_removal_mode 0)
		)
		(polygon
			(pts
				(arc
					(start 333.8068 -68.199)
					(mid 332.0288 -68.199)
					(end 333.8068 -68.199)
				)
			)
		)
	)
	(zone
		(layers "In1.Cu" "In3.Cu" "In6.Cu" "In8.Cu")
		(hatch none 0.5)
		(connect_pads
			(clearance 0)
		)
		(min_thickness 0.25)
		(keepout
			(tracks not_allowed)
			(vias allowed)
			(pads allowed)
			(copperpour not_allowed)
			(footprints allowed)
		)
		(placement
			(enabled no)
			(sheetname "")
		)
		(fill yes
			(thermal_gap 0.5)
			(thermal_bridge_width 0.5)
			(island_removal_mode 0)
		)
		(polygon
			(pts
				(arc
					(start 333.0448 -54.6354)
					(mid 331.2668 -54.6354)
					(end 333.0448 -54.6354)
				)
			)
		)
	)
	(zone
		(layers "In1.Cu" "In3.Cu" "In6.Cu" "In8.Cu")
		(hatch none 0.5)
		(connect_pads
			(clearance 0)
		)
		(min_thickness 0.25)
		(keepout
			(tracks not_allowed)
			(vias allowed)
			(pads allowed)
			(copperpour not_allowed)
			(footprints allowed)
		)
		(placement
			(enabled no)
			(sheetname "")
		)
		(fill yes
			(thermal_gap 0.5)
			(thermal_bridge_width 0.5)
			(island_removal_mode 0)
		)
		(polygon
			(pts
				(arc
					(start 116.392452 -71.374)
					(mid 114.614452 -71.374)
					(end 116.392452 -71.374)
				)
			)
		)
	)
	(zone
		(layers "In1.Cu" "In3.Cu" "In6.Cu" "In8.Cu")
		(hatch none 0.5)
		(connect_pads
			(clearance 0)
		)
		(min_thickness 0.25)
		(keepout
			(tracks not_allowed)
			(vias allowed)
			(pads allowed)
			(copperpour not_allowed)
			(footprints allowed)
		)
		(placement
			(enabled no)
			(sheetname "")
		)
		(fill yes
			(thermal_gap 0.5)
			(thermal_bridge_width 0.5)
			(island_removal_mode 0)
		)
		(polygon
			(pts
				(arc
					(start 336.0928 -65.913)
					(mid 334.3148 -65.913)
					(end 336.0928 -65.913)
				)
			)
		)
	)
	(zone
		(layers "In1.Cu" "In3.Cu" "In6.Cu" "In8.Cu")
		(hatch none 0.5)
		(connect_pads
			(clearance 0)
		)
		(min_thickness 0.25)
		(keepout
			(tracks not_allowed)
			(vias allowed)
			(pads allowed)
			(copperpour not_allowed)
			(footprints allowed)
		)
		(placement
			(enabled no)
			(sheetname "")
		)
		(fill yes
			(thermal_gap 0.5)
			(thermal_bridge_width 0.5)
			(island_removal_mode 0)
		)
		(polygon
			(pts
				(arc
					(start 64.213232 -158.83001)
					(mid 61.787024 -158.83001)
					(end 64.213232 -158.83001)
				)
			)
		)
	)
	(zone
		(layers "In1.Cu" "In3.Cu" "In6.Cu" "In8.Cu")
		(hatch none 0.5)
		(connect_pads
			(clearance 0)
		)
		(min_thickness 0.25)
		(keepout
			(tracks not_allowed)
			(vias allowed)
			(pads allowed)
			(copperpour not_allowed)
			(footprints allowed)
		)
		(placement
			(enabled no)
			(sheetname "")
		)
		(fill yes
			(thermal_gap 0.5)
			(thermal_bridge_width 0.5)
			(island_removal_mode 0)
		)
		(polygon
			(pts
				(arc
					(start 390.412986 -156.830014)
					(mid 387.986778 -156.830014)
					(end 390.412986 -156.830014)
				)
			)
		)
	)
	(zone
		(layers "In1.Cu" "In3.Cu" "In6.Cu" "In8.Cu")
		(hatch none 0.5)
		(connect_pads
			(clearance 0)
		)
		(min_thickness 0.25)
		(keepout
			(tracks not_allowed)
			(vias allowed)
			(pads allowed)
			(copperpour not_allowed)
			(footprints allowed)
		)
		(placement
			(enabled no)
			(sheetname "")
		)
		(fill yes
			(thermal_gap 0.5)
			(thermal_bridge_width 0.5)
			(island_removal_mode 0)
		)
		(polygon
			(pts
				(arc
					(start 113.344452 -27.7876)
					(mid 111.566452 -27.7876)
					(end 113.344452 -27.7876)
				)
			)
		)
	)
	(zone
		(layers "In1.Cu" "In3.Cu" "In6.Cu" "In8.Cu")
		(hatch none 0.5)
		(connect_pads
			(clearance 0)
		)
		(min_thickness 0.25)
		(keepout
			(tracks not_allowed)
			(vias allowed)
			(pads allowed)
			(copperpour not_allowed)
			(footprints allowed)
		)
		(placement
			(enabled no)
			(sheetname "")
		)
		(fill yes
			(thermal_gap 0.5)
			(thermal_bridge_width 0.5)
			(island_removal_mode 0)
		)
		(polygon
			(pts
				(arc
					(start 336.0928 -66.675)
					(mid 334.3148 -66.675)
					(end 336.0928 -66.675)
				)
			)
		)
	)
	(zone
		(layers "In1.Cu" "In3.Cu" "In6.Cu" "In8.Cu")
		(hatch none 0.5)
		(connect_pads
			(clearance 0)
		)
		(min_thickness 0.25)
		(keepout
			(tracks not_allowed)
			(vias allowed)
			(pads allowed)
			(copperpour not_allowed)
			(footprints allowed)
		)
		(placement
			(enabled no)
			(sheetname "")
		)
		(fill yes
			(thermal_gap 0.5)
			(thermal_bridge_width 0.5)
			(island_removal_mode 0)
		)
		(polygon
			(pts
				(arc
					(start 376.213116 -158.83001)
					(mid 373.786908 -158.83001)
					(end 376.213116 -158.83001)
				)
			)
		)
	)
	(zone
		(layers "In1.Cu" "In3.Cu" "In6.Cu" "In8.Cu")
		(hatch none 0.5)
		(connect_pads
			(clearance 0)
		)
		(min_thickness 0.25)
		(keepout
			(tracks not_allowed)
			(vias allowed)
			(pads allowed)
			(copperpour not_allowed)
			(footprints allowed)
		)
		(placement
			(enabled no)
			(sheetname "")
		)
		(fill yes
			(thermal_gap 0.5)
			(thermal_bridge_width 0.5)
			(island_removal_mode 0)
		)
		(polygon
			(pts
				(arc
					(start 114.106452 -36.7792)
					(mid 112.328452 -36.7792)
					(end 114.106452 -36.7792)
				)
			)
		)
	)
	(zone
		(layers "In1.Cu" "In3.Cu" "In6.Cu" "In8.Cu")
		(hatch none 0.5)
		(connect_pads
			(clearance 0)
		)
		(min_thickness 0.25)
		(keepout
			(tracks not_allowed)
			(vias allowed)
			(pads allowed)
			(copperpour not_allowed)
			(footprints allowed)
		)
		(placement
			(enabled no)
			(sheetname "")
		)
		(fill yes
			(thermal_gap 0.5)
			(thermal_bridge_width 0.5)
			(island_removal_mode 0)
		)
		(polygon
			(pts
				(arc
					(start 333.0448 -77.9526)
					(mid 331.2668 -77.9526)
					(end 333.0448 -77.9526)
				)
			)
		)
	)
	(zone
		(layers "In1.Cu" "In3.Cu" "In6.Cu" "In8.Cu")
		(hatch none 0.5)
		(connect_pads
			(clearance 0)
		)
		(min_thickness 0.25)
		(keepout
			(tracks not_allowed)
			(vias allowed)
			(pads allowed)
			(copperpour not_allowed)
			(footprints allowed)
		)
		(placement
			(enabled no)
			(sheetname "")
		)
		(fill yes
			(thermal_gap 0.5)
			(thermal_bridge_width 0.5)
			(island_removal_mode 0)
		)
		(polygon
			(pts
				(arc
					(start 114.106452 -70.612)
					(mid 112.328452 -70.612)
					(end 114.106452 -70.612)
				)
			)
		)
	)
	(zone
		(layers "In1.Cu" "In3.Cu" "In6.Cu" "In8.Cu")
		(hatch none 0.5)
		(connect_pads
			(clearance 0)
		)
		(min_thickness 0.25)
		(keepout
			(tracks not_allowed)
			(vias allowed)
			(pads allowed)
			(copperpour not_allowed)
			(footprints allowed)
		)
		(placement
			(enabled no)
			(sheetname "")
		)
		(fill yes
			(thermal_gap 0.5)
			(thermal_bridge_width 0.5)
			(island_removal_mode 0)
		)
		(polygon
			(pts
				(arc
					(start 114.868452 -72.898)
					(mid 113.090452 -72.898)
					(end 114.868452 -72.898)
				)
			)
		)
	)
	(zone
		(layers "In1.Cu" "In3.Cu" "In6.Cu" "In8.Cu")
		(hatch none 0.5)
		(connect_pads
			(clearance 0)
		)
		(min_thickness 0.25)
		(keepout
			(tracks not_allowed)
			(vias allowed)
			(pads allowed)
			(copperpour not_allowed)
			(footprints allowed)
		)
		(placement
			(enabled no)
			(sheetname "")
		)
		(fill yes
			(thermal_gap 0.5)
			(thermal_bridge_width 0.5)
			(island_removal_mode 0)
		)
		(polygon
			(pts
				(arc
					(start 333.8068 -45.6438)
					(mid 332.0288 -45.6438)
					(end 333.8068 -45.6438)
				)
			)
		)
	)
	(zone
		(layers "In1.Cu" "In3.Cu" "In6.Cu" "In8.Cu")
		(hatch none 0.5)
		(connect_pads
			(clearance 0)
		)
		(min_thickness 0.25)
		(keepout
			(tracks not_allowed)
			(vias allowed)
			(pads allowed)
			(copperpour not_allowed)
			(footprints allowed)
		)
		(placement
			(enabled no)
			(sheetname "")
		)
		(fill yes
			(thermal_gap 0.5)
			(thermal_bridge_width 0.5)
			(island_removal_mode 0)
		)
		(polygon
			(pts
				(arc
					(start 334.5688 -67.437)
					(mid 332.7908 -67.437)
					(end 334.5688 -67.437)
				)
			)
		)
	)
	(zone
		(layers "In1.Cu" "In3.Cu" "In6.Cu" "In8.Cu")
		(hatch none 0.5)
		(connect_pads
			(clearance 0)
		)
		(min_thickness 0.25)
		(keepout
			(tracks not_allowed)
			(vias allowed)
			(pads allowed)
			(copperpour not_allowed)
			(footprints allowed)
		)
		(placement
			(enabled no)
			(sheetname "")
		)
		(fill yes
			(thermal_gap 0.5)
			(thermal_bridge_width 0.5)
			(island_removal_mode 0)
		)
		(polygon
			(pts
				(arc
					(start 336.0928 -43.3578)
					(mid 334.3148 -43.3578)
					(end 336.0928 -43.3578)
				)
			)
		)
	)
	(zone
		(layers "In1.Cu" "In3.Cu" "In6.Cu" "In8.Cu")
		(hatch none 0.5)
		(connect_pads
			(clearance 0)
		)
		(min_thickness 0.25)
		(keepout
			(tracks not_allowed)
			(vias allowed)
			(pads allowed)
			(copperpour not_allowed)
			(footprints allowed)
		)
		(placement
			(enabled no)
			(sheetname "")
		)
		(fill yes
			(thermal_gap 0.5)
			(thermal_bridge_width 0.5)
			(island_removal_mode 0)
		)
		(polygon
			(pts
				(arc
					(start 43.379898 -71.239888)
					(mid 41.346882 -71.239888)
					(end 43.379898 -71.239888)
				)
			)
		)
	)
	(zone
		(layers "In1.Cu" "In3.Cu" "In6.Cu" "In8.Cu")
		(hatch none 0.5)
		(connect_pads
			(clearance 0)
		)
		(min_thickness 0.25)
		(keepout
			(tracks not_allowed)
			(vias allowed)
			(pads allowed)
			(copperpour not_allowed)
			(footprints allowed)
		)
		(placement
			(enabled no)
			(sheetname "")
		)
		(fill yes
			(thermal_gap 0.5)
			(thermal_bridge_width 0.5)
			(island_removal_mode 0)
		)
		(polygon
			(pts
				(arc
					(start 364.21314 -158.83001)
					(mid 361.786932 -158.83001)
					(end 364.21314 -158.83001)
				)
			)
		)
	)
	(zone
		(layers "In1.Cu" "In3.Cu" "In6.Cu" "In8.Cu")
		(hatch none 0.5)
		(connect_pads
			(clearance 0)
		)
		(min_thickness 0.25)
		(keepout
			(tracks not_allowed)
			(vias allowed)
			(pads allowed)
			(copperpour not_allowed)
			(footprints allowed)
		)
		(placement
			(enabled no)
			(sheetname "")
		)
		(fill yes
			(thermal_gap 0.5)
			(thermal_bridge_width 0.5)
			(island_removal_mode 0)
		)
		(polygon
			(pts
				(arc
					(start 334.5688 -42.5958)
					(mid 332.7908 -42.5958)
					(end 334.5688 -42.5958)
				)
			)
		)
	)
	(zone
		(layers "In1.Cu" "In3.Cu" "In6.Cu" "In8.Cu")
		(hatch none 0.5)
		(connect_pads
			(clearance 0)
		)
		(min_thickness 0.25)
		(keepout
			(tracks not_allowed)
			(vias allowed)
			(pads allowed)
			(copperpour not_allowed)
			(footprints allowed)
		)
		(placement
			(enabled no)
			(sheetname "")
		)
		(fill yes
			(thermal_gap 0.5)
			(thermal_bridge_width 0.5)
			(island_removal_mode 0)
		)
		(polygon
			(pts
				(arc
					(start 333.0448 -67.437)
					(mid 331.2668 -67.437)
					(end 333.0448 -67.437)
				)
			)
		)
	)
	(zone
		(layers "In1.Cu" "In3.Cu" "In6.Cu" "In8.Cu")
		(hatch none 0.5)
		(connect_pads
			(clearance 0)
		)
		(min_thickness 0.25)
		(keepout
			(tracks not_allowed)
			(vias allowed)
			(pads allowed)
			(copperpour not_allowed)
			(footprints allowed)
		)
		(placement
			(enabled no)
			(sheetname "")
		)
		(fill yes
			(thermal_gap 0.5)
			(thermal_bridge_width 0.5)
			(island_removal_mode 0)
		)
		(polygon
			(pts
				(arc
					(start 333.8068 -65.151)
					(mid 332.0288 -65.151)
					(end 333.8068 -65.151)
				)
			)
		)
	)
	(zone
		(layers "In1.Cu" "In3.Cu" "In6.Cu" "In8.Cu")
		(hatch none 0.5)
		(connect_pads
			(clearance 0)
		)
		(min_thickness 0.25)
		(keepout
			(tracks not_allowed)
			(vias allowed)
			(pads allowed)
			(copperpour not_allowed)
			(footprints allowed)
		)
		(placement
			(enabled no)
			(sheetname "")
		)
		(fill yes
			(thermal_gap 0.5)
			(thermal_bridge_width 0.5)
			(island_removal_mode 0)
		)
		(polygon
			(pts
				(arc
					(start 38.088062 -160.830006)
					(mid 35.661854 -160.830006)
					(end 38.088062 -160.830006)
				)
			)
		)
	)
	(zone
		(layers "In1.Cu" "In3.Cu" "In6.Cu" "In8.Cu")
		(hatch none 0.5)
		(connect_pads
			(clearance 0)
		)
		(min_thickness 0.25)
		(keepout
			(tracks not_allowed)
			(vias allowed)
			(pads allowed)
			(copperpour not_allowed)
			(footprints allowed)
		)
		(placement
			(enabled no)
			(sheetname "")
		)
		(fill yes
			(thermal_gap 0.5)
			(thermal_bridge_width 0.5)
			(island_removal_mode 0)
		)
		(polygon
			(pts
				(arc
					(start 58.013092 -160.830006)
					(mid 55.586884 -160.830006)
					(end 58.013092 -160.830006)
				)
			)
		)
	)
	(zone
		(layers "In1.Cu" "In3.Cu" "In6.Cu" "In8.Cu")
		(hatch none 0.5)
		(connect_pads
			(clearance 0)
		)
		(min_thickness 0.25)
		(keepout
			(tracks not_allowed)
			(vias allowed)
			(pads allowed)
			(copperpour not_allowed)
			(footprints allowed)
		)
		(placement
			(enabled no)
			(sheetname "")
		)
		(fill yes
			(thermal_gap 0.5)
			(thermal_bridge_width 0.5)
			(island_removal_mode 0)
		)
		(polygon
			(pts
				(arc
					(start 370.213128 -156.830014)
					(mid 367.78692 -156.830014)
					(end 370.213128 -156.830014)
				)
			)
		)
	)
	(zone
		(layers "In1.Cu" "In3.Cu" "In6.Cu" "In8.Cu")
		(hatch none 0.5)
		(connect_pads
			(clearance 0)
		)
		(min_thickness 0.25)
		(keepout
			(tracks not_allowed)
			(vias allowed)
			(pads allowed)
			(copperpour not_allowed)
			(footprints allowed)
		)
		(placement
			(enabled no)
			(sheetname "")
		)
		(fill yes
			(thermal_gap 0.5)
			(thermal_bridge_width 0.5)
			(island_removal_mode 0)
		)
		(polygon
			(pts
				(arc
					(start 473.029788 -68.689982)
					(mid 470.210388 -68.689982)
					(end 473.029788 -68.689982)
				)
			)
		)
	)
	(zone
		(layers "In1.Cu" "In3.Cu" "In6.Cu" "In8.Cu")
		(hatch none 0.5)
		(connect_pads
			(clearance 0)
		)
		(min_thickness 0.25)
		(keepout
			(tracks not_allowed)
			(vias allowed)
			(pads allowed)
			(copperpour not_allowed)
			(footprints allowed)
		)
		(placement
			(enabled no)
			(sheetname "")
		)
		(fill yes
			(thermal_gap 0.5)
			(thermal_bridge_width 0.5)
			(island_removal_mode 0)
		)
		(polygon
			(pts
				(arc
					(start 66.213228 -160.830006)
					(mid 63.78702 -160.830006)
					(end 66.213228 -160.830006)
				)
			)
		)
	)
	(zone
		(layers "In1.Cu" "In3.Cu" "In6.Cu" "In8.Cu")
		(hatch none 0.5)
		(connect_pads
			(clearance 0)
		)
		(min_thickness 0.25)
		(keepout
			(tracks not_allowed)
			(vias allowed)
			(pads allowed)
			(copperpour not_allowed)
			(footprints allowed)
		)
		(placement
			(enabled no)
			(sheetname "")
		)
		(fill yes
			(thermal_gap 0.5)
			(thermal_bridge_width 0.5)
			(island_removal_mode 0)
		)
		(polygon
			(pts
				(arc
					(start 87.376 -4.572)
					(mid 85.598 -4.572)
					(end 87.376 -4.572)
				)
			)
		)
	)
	(zone
		(layers "In1.Cu" "In3.Cu" "In6.Cu" "In8.Cu")
		(hatch none 0.5)
		(connect_pads
			(clearance 0)
		)
		(min_thickness 0.25)
		(keepout
			(tracks not_allowed)
			(vias allowed)
			(pads allowed)
			(copperpour not_allowed)
			(footprints allowed)
		)
		(placement
			(enabled no)
			(sheetname "")
		)
		(fill yes
			(thermal_gap 0.5)
			(thermal_bridge_width 0.5)
			(island_removal_mode 0)
		)
		(polygon
			(pts
				(arc
					(start 115.630452 -61.6204)
					(mid 113.852452 -61.6204)
					(end 115.630452 -61.6204)
				)
			)
		)
	)
	(zone
		(layers "In1.Cu" "In3.Cu" "In6.Cu" "In8.Cu")
		(hatch none 0.5)
		(connect_pads
			(clearance 0)
		)
		(min_thickness 0.25)
		(keepout
			(tracks not_allowed)
			(vias allowed)
			(pads allowed)
			(copperpour not_allowed)
			(footprints allowed)
		)
		(placement
			(enabled no)
			(sheetname "")
		)
		(fill yes
			(thermal_gap 0.5)
			(thermal_bridge_width 0.5)
			(island_removal_mode 0)
		)
		(polygon
			(pts
				(arc
					(start 335.3308 -20.0406)
					(mid 333.5528 -20.0406)
					(end 335.3308 -20.0406)
				)
			)
		)
	)
	(zone
		(layers "In1.Cu" "In3.Cu" "In6.Cu" "In8.Cu")
		(hatch none 0.5)
		(connect_pads
			(clearance 0)
		)
		(min_thickness 0.25)
		(keepout
			(tracks not_allowed)
			(vias allowed)
			(pads allowed)
			(copperpour not_allowed)
			(footprints allowed)
		)
		(placement
			(enabled no)
			(sheetname "")
		)
		(fill yes
			(thermal_gap 0.5)
			(thermal_bridge_width 0.5)
			(island_removal_mode 0)
		)
		(polygon
			(pts
				(arc
					(start 114.868452 -26.2636)
					(mid 113.090452 -26.2636)
					(end 114.868452 -26.2636)
				)
			)
		)
	)
	(zone
		(layers "In1.Cu" "In3.Cu" "In6.Cu" "In8.Cu")
		(hatch none 0.5)
		(connect_pads
			(clearance 0)
		)
		(min_thickness 0.25)
		(keepout
			(tracks not_allowed)
			(vias allowed)
			(pads allowed)
			(copperpour not_allowed)
			(footprints allowed)
		)
		(placement
			(enabled no)
			(sheetname "")
		)
		(fill yes
			(thermal_gap 0.5)
			(thermal_bridge_width 0.5)
			(island_removal_mode 0)
		)
		(polygon
			(pts
				(arc
					(start 399.161 -119.38)
					(mid 396.113 -119.38)
					(end 399.161 -119.38)
				)
			)
		)
	)
	(zone
		(layers "In1.Cu" "In3.Cu" "In6.Cu" "In8.Cu")
		(hatch none 0.5)
		(connect_pads
			(clearance 0)
		)
		(min_thickness 0.25)
		(keepout
			(tracks not_allowed)
			(vias allowed)
			(pads allowed)
			(copperpour not_allowed)
			(footprints allowed)
		)
		(placement
			(enabled no)
			(sheetname "")
		)
		(fill yes
			(thermal_gap 0.5)
			(thermal_bridge_width 0.5)
			(island_removal_mode 0)
		)
		(polygon
			(pts
				(arc
					(start 333.8068 -44.8818)
					(mid 332.0288 -44.8818)
					(end 333.8068 -44.8818)
				)
			)
		)
	)
	(zone
		(layers "In1.Cu" "In3.Cu" "In6.Cu" "In8.Cu")
		(hatch none 0.5)
		(connect_pads
			(clearance 0)
		)
		(min_thickness 0.25)
		(keepout
			(tracks not_allowed)
			(vias allowed)
			(pads allowed)
			(copperpour not_allowed)
			(footprints allowed)
		)
		(placement
			(enabled no)
			(sheetname "")
		)
		(fill yes
			(thermal_gap 0.5)
			(thermal_bridge_width 0.5)
			(island_removal_mode 0)
		)
		(polygon
			(pts
				(arc
					(start 114.868452 -48.0568)
					(mid 113.090452 -48.0568)
					(end 114.868452 -48.0568)
				)
			)
		)
	)
	(zone
		(layers "In1.Cu" "In3.Cu" "In6.Cu" "In8.Cu")
		(hatch none 0.5)
		(connect_pads
			(clearance 0)
		)
		(min_thickness 0.25)
		(keepout
			(tracks not_allowed)
			(vias allowed)
			(pads allowed)
			(copperpour not_allowed)
			(footprints allowed)
		)
		(placement
			(enabled no)
			(sheetname "")
		)
		(fill yes
			(thermal_gap 0.5)
			(thermal_bridge_width 0.5)
			(island_removal_mode 0)
		)
		(polygon
			(pts
				(arc
					(start 398.653508 -91.559888)
					(mid 396.620492 -91.559888)
					(end 398.653508 -91.559888)
				)
			)
		)
	)
	(zone
		(layers "In1.Cu" "In3.Cu" "In6.Cu" "In8.Cu")
		(hatch none 0.5)
		(connect_pads
			(clearance 0)
		)
		(min_thickness 0.25)
		(keepout
			(tracks not_allowed)
			(vias allowed)
			(pads allowed)
			(copperpour not_allowed)
			(footprints allowed)
		)
		(placement
			(enabled no)
			(sheetname "")
		)
		(fill yes
			(thermal_gap 0.5)
			(thermal_bridge_width 0.5)
			(island_removal_mode 0)
		)
		(polygon
			(pts
				(arc
					(start 113.344452 -14.986)
					(mid 111.566452 -14.986)
					(end 113.344452 -14.986)
				)
			)
		)
	)
	(zone
		(layers "In1.Cu" "In3.Cu" "In6.Cu" "In8.Cu")
		(hatch none 0.5)
		(connect_pads
			(clearance 0)
		)
		(min_thickness 0.25)
		(keepout
			(tracks not_allowed)
			(vias allowed)
			(pads allowed)
			(copperpour not_allowed)
			(footprints allowed)
		)
		(placement
			(enabled no)
			(sheetname "")
		)
		(fill yes
			(thermal_gap 0.5)
			(thermal_bridge_width 0.5)
			(island_removal_mode 0)
		)
		(polygon
			(pts
				(arc
					(start 116.392452 -27.7876)
					(mid 114.614452 -27.7876)
					(end 116.392452 -27.7876)
				)
			)
		)
	)
	(zone
		(layers "In1.Cu" "In3.Cu" "In6.Cu" "In8.Cu")
		(hatch none 0.5)
		(connect_pads
			(clearance 0)
		)
		(min_thickness 0.25)
		(keepout
			(tracks not_allowed)
			(vias allowed)
			(pads allowed)
			(copperpour not_allowed)
			(footprints allowed)
		)
		(placement
			(enabled no)
			(sheetname "")
		)
		(fill yes
			(thermal_gap 0.5)
			(thermal_bridge_width 0.5)
			(island_removal_mode 0)
		)
		(polygon
			(pts
				(arc
					(start 116.392452 -72.136)
					(mid 114.614452 -72.136)
					(end 116.392452 -72.136)
				)
			)
		)
	)
	(zone
		(layers "In1.Cu" "In3.Cu" "In6.Cu" "In8.Cu")
		(hatch none 0.5)
		(connect_pads
			(clearance 0)
		)
		(min_thickness 0.25)
		(keepout
			(tracks not_allowed)
			(vias allowed)
			(pads allowed)
			(copperpour not_allowed)
			(footprints allowed)
		)
		(placement
			(enabled no)
			(sheetname "")
		)
		(fill yes
			(thermal_gap 0.5)
			(thermal_bridge_width 0.5)
			(island_removal_mode 0)
		)
		(polygon
			(pts
				(arc
					(start 43.88739 -139.7)
					(mid 40.83939 -139.7)
					(end 43.88739 -139.7)
				)
			)
		)
	)
	(zone
		(layers "In1.Cu" "In3.Cu" "In6.Cu" "In8.Cu")
		(hatch none 0.5)
		(connect_pads
			(clearance 0)
		)
		(min_thickness 0.25)
		(keepout
			(tracks not_allowed)
			(vias allowed)
			(pads allowed)
			(copperpour not_allowed)
			(footprints allowed)
		)
		(placement
			(enabled no)
			(sheetname "")
		)
		(fill yes
			(thermal_gap 0.5)
			(thermal_bridge_width 0.5)
			(island_removal_mode 0)
		)
		(polygon
			(pts
				(arc
					(start 399.588228 -154.830018)
					(mid 397.16202 -154.830018)
					(end 399.588228 -154.830018)
				)
			)
		)
	)
	(zone
		(layers "In1.Cu" "In3.Cu" "In6.Cu" "In8.Cu")
		(hatch none 0.5)
		(connect_pads
			(clearance 0)
		)
		(min_thickness 0.25)
		(keepout
			(tracks not_allowed)
			(vias allowed)
			(pads allowed)
			(copperpour not_allowed)
			(footprints allowed)
		)
		(placement
			(enabled no)
			(sheetname "")
		)
		(fill yes
			(thermal_gap 0.5)
			(thermal_bridge_width 0.5)
			(island_removal_mode 0)
		)
		(polygon
			(pts
				(arc
					(start 333.0448 -33.6042)
					(mid 331.2668 -33.6042)
					(end 333.0448 -33.6042)
				)
			)
		)
	)
	(zone
		(layers "In1.Cu" "In3.Cu" "In6.Cu" "In8.Cu")
		(hatch none 0.5)
		(connect_pads
			(clearance 0)
		)
		(min_thickness 0.25)
		(keepout
			(tracks not_allowed)
			(vias allowed)
			(pads allowed)
			(copperpour not_allowed)
			(footprints allowed)
		)
		(placement
			(enabled no)
			(sheetname "")
		)
		(fill yes
			(thermal_gap 0.5)
			(thermal_bridge_width 0.5)
			(island_removal_mode 0)
		)
		(polygon
			(pts
				(arc
					(start 390.412986 -158.83001)
					(mid 387.986778 -158.83001)
					(end 390.412986 -158.83001)
				)
			)
		)
	)
	(zone
		(layers "In1.Cu" "In3.Cu" "In6.Cu" "In8.Cu")
		(hatch none 0.5)
		(connect_pads
			(clearance 0)
		)
		(min_thickness 0.25)
		(keepout
			(tracks not_allowed)
			(vias allowed)
			(pads allowed)
			(copperpour not_allowed)
			(footprints allowed)
		)
		(placement
			(enabled no)
			(sheetname "")
		)
		(fill yes
			(thermal_gap 0.5)
			(thermal_bridge_width 0.5)
			(island_removal_mode 0)
		)
		(polygon
			(pts
				(arc
					(start 357.30942 -3.829304)
					(mid 355.53142 -3.829304)
					(end 357.30942 -3.829304)
				)
			)
		)
	)
	(zone
		(layers "In1.Cu" "In3.Cu" "In6.Cu" "In8.Cu")
		(hatch none 0.5)
		(connect_pads
			(clearance 0)
		)
		(min_thickness 0.25)
		(keepout
			(tracks not_allowed)
			(vias allowed)
			(pads allowed)
			(copperpour not_allowed)
			(footprints allowed)
		)
		(placement
			(enabled no)
			(sheetname "")
		)
		(fill yes
			(thermal_gap 0.5)
			(thermal_bridge_width 0.5)
			(island_removal_mode 0)
		)
		(polygon
			(pts
				(arc
					(start 56.013096 -156.830014)
					(mid 53.586888 -156.830014)
					(end 56.013096 -156.830014)
				)
			)
		)
	)
	(zone
		(layers "In1.Cu" "In3.Cu" "In6.Cu" "In8.Cu")
		(hatch none 0.5)
		(connect_pads
			(clearance 0)
		)
		(min_thickness 0.25)
		(keepout
			(tracks not_allowed)
			(vias allowed)
			(pads allowed)
			(copperpour not_allowed)
			(footprints allowed)
		)
		(placement
			(enabled no)
			(sheetname "")
		)
		(fill yes
			(thermal_gap 0.5)
			(thermal_bridge_width 0.5)
			(island_removal_mode 0)
		)
		(polygon
			(pts
				(arc
					(start 43.379898 -91.559888)
					(mid 41.346882 -91.559888)
					(end 43.379898 -91.559888)
				)
			)
		)
	)
	(zone
		(layers "In1.Cu" "In3.Cu" "In6.Cu" "In8.Cu")
		(hatch none 0.5)
		(connect_pads
			(clearance 0)
		)
		(min_thickness 0.25)
		(keepout
			(tracks not_allowed)
			(vias allowed)
			(pads allowed)
			(copperpour not_allowed)
			(footprints allowed)
		)
		(placement
			(enabled no)
			(sheetname "")
		)
		(fill yes
			(thermal_gap 0.5)
			(thermal_bridge_width 0.5)
			(island_removal_mode 0)
		)
		(polygon
			(pts
				(arc
					(start 392.412982 -160.830006)
					(mid 389.986774 -160.830006)
					(end 392.412982 -160.830006)
				)
			)
		)
	)
	(zone
		(layers "In1.Cu" "In3.Cu" "In6.Cu" "In8.Cu")
		(hatch none 0.5)
		(connect_pads
			(clearance 0)
		)
		(min_thickness 0.25)
		(keepout
			(tracks not_allowed)
			(vias allowed)
			(pads allowed)
			(copperpour not_allowed)
			(footprints allowed)
		)
		(placement
			(enabled no)
			(sheetname "")
		)
		(fill yes
			(thermal_gap 0.5)
			(thermal_bridge_width 0.5)
			(island_removal_mode 0)
		)
		(polygon
			(pts
				(arc
					(start 115.630452 -73.66)
					(mid 113.852452 -73.66)
					(end 115.630452 -73.66)
				)
			)
		)
	)
	(zone
		(layers "In1.Cu" "In3.Cu" "In6.Cu" "In8.Cu")
		(hatch none 0.5)
		(connect_pads
			(clearance 0)
		)
		(min_thickness 0.25)
		(keepout
			(tracks not_allowed)
			(vias allowed)
			(pads allowed)
			(copperpour not_allowed)
			(footprints allowed)
		)
		(placement
			(enabled no)
			(sheetname "")
		)
		(fill yes
			(thermal_gap 0.5)
			(thermal_bridge_width 0.5)
			(island_removal_mode 0)
		)
		(polygon
			(pts
				(arc
					(start 470.329768 -73.769982)
					(mid 467.510368 -73.769982)
					(end 470.329768 -73.769982)
				)
			)
		)
	)
	(zone
		(layers "In1.Cu" "In3.Cu" "In6.Cu" "In8.Cu")
		(hatch none 0.5)
		(connect_pads
			(clearance 0)
		)
		(min_thickness 0.25)
		(keepout
			(tracks not_allowed)
			(vias allowed)
			(pads allowed)
			(copperpour not_allowed)
			(footprints allowed)
		)
		(placement
			(enabled no)
			(sheetname "")
		)
		(fill yes
			(thermal_gap 0.5)
			(thermal_bridge_width 0.5)
			(island_removal_mode 0)
		)
		(polygon
			(pts
				(arc
					(start 113.344452 -28.5496)
					(mid 111.566452 -28.5496)
					(end 113.344452 -28.5496)
				)
			)
		)
	)
	(zone
		(layers "In1.Cu" "In3.Cu" "In6.Cu" "In8.Cu")
		(hatch none 0.5)
		(connect_pads
			(clearance 0)
		)
		(min_thickness 0.25)
		(keepout
			(tracks not_allowed)
			(vias allowed)
			(pads allowed)
			(copperpour not_allowed)
			(footprints allowed)
		)
		(placement
			(enabled no)
			(sheetname "")
		)
		(fill yes
			(thermal_gap 0.5)
			(thermal_bridge_width 0.5)
			(island_removal_mode 0)
		)
		(polygon
			(pts
				(arc
					(start 85.09 -5.334)
					(mid 83.312 -5.334)
					(end 85.09 -5.334)
				)
			)
		)
	)
	(zone
		(layers "In1.Cu" "In3.Cu" "In6.Cu" "In8.Cu")
		(hatch none 0.5)
		(connect_pads
			(clearance 0)
		)
		(min_thickness 0.25)
		(keepout
			(tracks not_allowed)
			(vias allowed)
			(pads allowed)
			(copperpour not_allowed)
			(footprints allowed)
		)
		(placement
			(enabled no)
			(sheetname "")
		)
		(fill yes
			(thermal_gap 0.5)
			(thermal_bridge_width 0.5)
			(island_removal_mode 0)
		)
		(polygon
			(pts
				(arc
					(start 333.8068 -33.6042)
					(mid 332.0288 -33.6042)
					(end 333.8068 -33.6042)
				)
			)
		)
	)
	(zone
		(layers "In1.Cu" "In3.Cu" "In6.Cu" "In8.Cu")
		(hatch none 0.5)
		(connect_pads
			(clearance 0)
		)
		(min_thickness 0.25)
		(keepout
			(tracks not_allowed)
			(vias allowed)
			(pads allowed)
			(copperpour not_allowed)
			(footprints allowed)
		)
		(placement
			(enabled no)
			(sheetname "")
		)
		(fill yes
			(thermal_gap 0.5)
			(thermal_bridge_width 0.5)
			(island_removal_mode 0)
		)
		(polygon
			(pts
				(arc
					(start 116.392452 -37.5412)
					(mid 114.614452 -37.5412)
					(end 116.392452 -37.5412)
				)
			)
		)
	)
	(zone
		(layers "In1.Cu" "In3.Cu" "In6.Cu" "In8.Cu")
		(hatch none 0.5)
		(connect_pads
			(clearance 0)
		)
		(min_thickness 0.25)
		(keepout
			(tracks not_allowed)
			(vias allowed)
			(pads allowed)
			(copperpour not_allowed)
			(footprints allowed)
		)
		(placement
			(enabled no)
			(sheetname "")
		)
		(fill yes
			(thermal_gap 0.5)
			(thermal_bridge_width 0.5)
			(island_removal_mode 0)
		)
		(polygon
			(pts
				(arc
					(start 335.3308 -77.9526)
					(mid 333.5528 -77.9526)
					(end 335.3308 -77.9526)
				)
			)
		)
	)
	(zone
		(layers "In1.Cu" "In3.Cu" "In6.Cu" "In8.Cu")
		(hatch none 0.5)
		(connect_pads
			(clearance 0)
		)
		(min_thickness 0.25)
		(keepout
			(tracks not_allowed)
			(vias allowed)
			(pads allowed)
			(copperpour not_allowed)
			(footprints allowed)
		)
		(placement
			(enabled no)
			(sheetname "")
		)
		(fill yes
			(thermal_gap 0.5)
			(thermal_bridge_width 0.5)
			(island_removal_mode 0)
		)
		(polygon
			(pts
				(arc
					(start 115.630452 -60.8584)
					(mid 113.852452 -60.8584)
					(end 115.630452 -60.8584)
				)
			)
		)
	)
	(zone
		(layers "In1.Cu" "In3.Cu" "In6.Cu" "In8.Cu")
		(hatch none 0.5)
		(connect_pads
			(clearance 0)
		)
		(min_thickness 0.25)
		(keepout
			(tracks not_allowed)
			(vias allowed)
			(pads allowed)
			(copperpour not_allowed)
			(footprints allowed)
		)
		(placement
			(enabled no)
			(sheetname "")
		)
		(fill yes
			(thermal_gap 0.5)
			(thermal_bridge_width 0.5)
			(island_removal_mode 0)
		)
		(polygon
			(pts
				(arc
					(start 336.0928 -44.1198)
					(mid 334.3148 -44.1198)
					(end 336.0928 -44.1198)
				)
			)
		)
	)
	(zone
		(layers "In1.Cu" "In3.Cu" "In6.Cu" "In8.Cu")
		(hatch none 0.5)
		(connect_pads
			(clearance 0)
		)
		(min_thickness 0.25)
		(keepout
			(tracks not_allowed)
			(vias allowed)
			(pads allowed)
			(copperpour not_allowed)
			(footprints allowed)
		)
		(placement
			(enabled no)
			(sheetname "")
		)
		(fill yes
			(thermal_gap 0.5)
			(thermal_bridge_width 0.5)
			(island_removal_mode 0)
		)
		(polygon
			(pts
				(arc
					(start 334.5688 -77.9526)
					(mid 332.7908 -77.9526)
					(end 334.5688 -77.9526)
				)
			)
		)
	)
	(zone
		(layers "In1.Cu" "In3.Cu" "In6.Cu" "In8.Cu")
		(hatch none 0.5)
		(connect_pads
			(clearance 0)
		)
		(min_thickness 0.25)
		(keepout
			(tracks not_allowed)
			(vias allowed)
			(pads allowed)
			(copperpour not_allowed)
			(footprints allowed)
		)
		(placement
			(enabled no)
			(sheetname "")
		)
		(fill yes
			(thermal_gap 0.5)
			(thermal_bridge_width 0.5)
			(island_removal_mode 0)
		)
		(polygon
			(pts
				(arc
					(start 336.0928 -20.0406)
					(mid 334.3148 -20.0406)
					(end 336.0928 -20.0406)
				)
			)
		)
	)
	(zone
		(layers "In1.Cu" "In3.Cu" "In6.Cu" "In8.Cu")
		(hatch none 0.5)
		(connect_pads
			(clearance 0)
		)
		(min_thickness 0.25)
		(keepout
			(tracks not_allowed)
			(vias allowed)
			(pads allowed)
			(copperpour not_allowed)
			(footprints allowed)
		)
		(placement
			(enabled no)
			(sheetname "")
		)
		(fill yes
			(thermal_gap 0.5)
			(thermal_bridge_width 0.5)
			(island_removal_mode 0)
		)
		(polygon
			(pts
				(arc
					(start 84.328 -3.81)
					(mid 82.55 -3.81)
					(end 84.328 -3.81)
				)
			)
		)
	)
	(zone
		(layers "In1.Cu" "In3.Cu" "In6.Cu" "In8.Cu")
		(hatch none 0.5)
		(connect_pads
			(clearance 0)
		)
		(min_thickness 0.25)
		(keepout
			(tracks not_allowed)
			(vias allowed)
			(pads allowed)
			(copperpour not_allowed)
			(footprints allowed)
		)
		(placement
			(enabled no)
			(sheetname "")
		)
		(fill yes
			(thermal_gap 0.5)
			(thermal_bridge_width 0.5)
			(island_removal_mode 0)
		)
		(polygon
			(pts
				(arc
					(start 398.653508 -71.239888)
					(mid 396.620492 -71.239888)
					(end 398.653508 -71.239888)
				)
			)
		)
	)
	(zone
		(layers "In1.Cu" "In3.Cu" "In6.Cu" "In8.Cu")
		(hatch none 0.5)
		(connect_pads
			(clearance 0)
		)
		(min_thickness 0.25)
		(keepout
			(tracks not_allowed)
			(vias allowed)
			(pads allowed)
			(copperpour not_allowed)
			(footprints allowed)
		)
		(placement
			(enabled no)
			(sheetname "")
		)
		(fill yes
			(thermal_gap 0.5)
			(thermal_bridge_width 0.5)
			(island_removal_mode 0)
		)
		(polygon
			(pts
				(arc
					(start 401.588224 -168.82999)
					(mid 399.162016 -168.82999)
					(end 401.588224 -168.82999)
				)
			)
		)
	)
	(zone
		(layers "In1.Cu" "In3.Cu" "In6.Cu" "In8.Cu")
		(hatch none 0.5)
		(connect_pads
			(clearance 0)
		)
		(min_thickness 0.25)
		(keepout
			(tracks not_allowed)
			(vias allowed)
			(pads allowed)
			(copperpour not_allowed)
			(footprints allowed)
		)
		(placement
			(enabled no)
			(sheetname "")
		)
		(fill yes
			(thermal_gap 0.5)
			(thermal_bridge_width 0.5)
			(island_removal_mode 0)
		)
		(polygon
			(pts
				(arc
					(start 116.392452 -49.5808)
					(mid 114.614452 -49.5808)
					(end 116.392452 -49.5808)
				)
			)
		)
	)
	(zone
		(layers "In1.Cu" "In3.Cu" "In6.Cu" "In8.Cu")
		(hatch none 0.5)
		(connect_pads
			(clearance 0)
		)
		(min_thickness 0.25)
		(keepout
			(tracks not_allowed)
			(vias allowed)
			(pads allowed)
			(copperpour not_allowed)
			(footprints allowed)
		)
		(placement
			(enabled no)
			(sheetname "")
		)
		(fill yes
			(thermal_gap 0.5)
			(thermal_bridge_width 0.5)
			(island_removal_mode 0)
		)
		(polygon
			(pts
				(arc
					(start 333.0448 -20.0406)
					(mid 331.2668 -20.0406)
					(end 333.0448 -20.0406)
				)
			)
		)
	)
	(zone
		(layers "In1.Cu" "In3.Cu" "In6.Cu" "In8.Cu")
		(hatch none 0.5)
		(connect_pads
			(clearance 0)
		)
		(min_thickness 0.25)
		(keepout
			(tracks not_allowed)
			(vias allowed)
			(pads allowed)
			(copperpour not_allowed)
			(footprints allowed)
		)
		(placement
			(enabled no)
			(sheetname "")
		)
		(fill yes
			(thermal_gap 0.5)
			(thermal_bridge_width 0.5)
			(island_removal_mode 0)
		)
		(polygon
			(pts
				(arc
					(start 114.868452 -39.8272)
					(mid 113.090452 -39.8272)
					(end 114.868452 -39.8272)
				)
			)
		)
	)
	(zone
		(layers "In1.Cu" "In3.Cu" "In6.Cu" "In8.Cu")
		(hatch none 0.5)
		(connect_pads
			(clearance 0)
		)
		(min_thickness 0.25)
		(keepout
			(tracks not_allowed)
			(vias allowed)
			(pads allowed)
			(copperpour not_allowed)
			(footprints allowed)
		)
		(placement
			(enabled no)
			(sheetname "")
		)
		(fill yes
			(thermal_gap 0.5)
			(thermal_bridge_width 0.5)
			(island_removal_mode 0)
		)
		(polygon
			(pts
				(arc
					(start 66.213228 -156.830014)
					(mid 63.78702 -156.830014)
					(end 66.213228 -156.830014)
				)
			)
		)
	)
	(zone
		(layers "In1.Cu" "In3.Cu" "In6.Cu" "In8.Cu")
		(hatch none 0.5)
		(connect_pads
			(clearance 0)
		)
		(min_thickness 0.25)
		(keepout
			(tracks not_allowed)
			(vias allowed)
			(pads allowed)
			(copperpour not_allowed)
			(footprints allowed)
		)
		(placement
			(enabled no)
			(sheetname "")
		)
		(fill yes
			(thermal_gap 0.5)
			(thermal_bridge_width 0.5)
			(island_removal_mode 0)
		)
		(polygon
			(pts
				(arc
					(start 379.095508 -50.919888)
					(mid 377.062492 -50.919888)
					(end 379.095508 -50.919888)
				)
			)
		)
	)
	(zone
		(layers "In1.Cu" "In3.Cu" "In6.Cu" "In8.Cu")
		(hatch none 0.5)
		(connect_pads
			(clearance 0)
		)
		(min_thickness 0.25)
		(keepout
			(tracks not_allowed)
			(vias allowed)
			(pads allowed)
			(copperpour not_allowed)
			(footprints allowed)
		)
		(placement
			(enabled no)
			(sheetname "")
		)
		(fill yes
			(thermal_gap 0.5)
			(thermal_bridge_width 0.5)
			(island_removal_mode 0)
		)
		(polygon
			(pts
				(arc
					(start 86.614 -5.334)
					(mid 84.836 -5.334)
					(end 86.614 -5.334)
				)
			)
		)
	)
	(zone
		(layers "In1.Cu" "In3.Cu" "In6.Cu" "In8.Cu")
		(hatch none 0.5)
		(connect_pads
			(clearance 0)
		)
		(min_thickness 0.25)
		(keepout
			(tracks not_allowed)
			(vias allowed)
			(pads allowed)
			(copperpour not_allowed)
			(footprints allowed)
		)
		(placement
			(enabled no)
			(sheetname "")
		)
		(fill yes
			(thermal_gap 0.5)
			(thermal_bridge_width 0.5)
			(island_removal_mode 0)
		)
		(polygon
			(pts
				(arc
					(start 113.344452 -17.272)
					(mid 111.566452 -17.272)
					(end 113.344452 -17.272)
				)
			)
		)
	)
	(zone
		(layers "In1.Cu" "In3.Cu" "In6.Cu" "In8.Cu")
		(hatch none 0.5)
		(connect_pads
			(clearance 0)
		)
		(min_thickness 0.25)
		(keepout
			(tracks not_allowed)
			(vias allowed)
			(pads allowed)
			(copperpour not_allowed)
			(footprints allowed)
		)
		(placement
			(enabled no)
			(sheetname "")
		)
		(fill yes
			(thermal_gap 0.5)
			(thermal_bridge_width 0.5)
			(island_removal_mode 0)
		)
		(polygon
			(pts
				(arc
					(start 355.78542 -5.353304)
					(mid 354.00742 -5.353304)
					(end 355.78542 -5.353304)
				)
			)
		)
	)
	(zone
		(layers "In1.Cu" "In3.Cu" "In6.Cu" "In8.Cu")
		(hatch none 0.5)
		(connect_pads
			(clearance 0)
		)
		(min_thickness 0.25)
		(keepout
			(tracks not_allowed)
			(vias allowed)
			(pads allowed)
			(copperpour not_allowed)
			(footprints allowed)
		)
		(placement
			(enabled no)
			(sheetname "")
		)
		(fill yes
			(thermal_gap 0.5)
			(thermal_bridge_width 0.5)
			(island_removal_mode 0)
		)
		(polygon
			(pts
				(arc
					(start 399.161 -78.74)
					(mid 396.113 -78.74)
					(end 399.161 -78.74)
				)
			)
		)
	)
	(zone
		(layers "In1.Cu" "In3.Cu" "In6.Cu" "In8.Cu")
		(hatch none 0.5)
		(connect_pads
			(clearance 0)
		)
		(min_thickness 0.25)
		(keepout
			(tracks not_allowed)
			(vias allowed)
			(pads allowed)
			(copperpour not_allowed)
			(footprints allowed)
		)
		(placement
			(enabled no)
			(sheetname "")
		)
		(fill yes
			(thermal_gap 0.5)
			(thermal_bridge_width 0.5)
			(island_removal_mode 0)
		)
		(polygon
			(pts
				(arc
					(start 379.095508 -111.879888)
					(mid 377.062492 -111.879888)
					(end 379.095508 -111.879888)
				)
			)
		)
	)
	(zone
		(layers "In1.Cu" "In3.Cu" "In6.Cu" "In8.Cu")
		(hatch none 0.5)
		(connect_pads
			(clearance 0)
		)
		(min_thickness 0.25)
		(keepout
			(tracks not_allowed)
			(vias allowed)
			(pads allowed)
			(copperpour not_allowed)
			(footprints allowed)
		)
		(placement
			(enabled no)
			(sheetname "")
		)
		(fill yes
			(thermal_gap 0.5)
			(thermal_bridge_width 0.5)
			(island_removal_mode 0)
		)
		(polygon
			(pts
				(arc
					(start 36.088066 -160.830006)
					(mid 33.661858 -160.830006)
					(end 36.088066 -160.830006)
				)
			)
		)
	)
	(zone
		(layers "In1.Cu" "In3.Cu" "In6.Cu" "In8.Cu")
		(hatch none 0.5)
		(connect_pads
			(clearance 0)
		)
		(min_thickness 0.25)
		(keepout
			(tracks not_allowed)
			(vias allowed)
			(pads allowed)
			(copperpour not_allowed)
			(footprints allowed)
		)
		(placement
			(enabled no)
			(sheetname "")
		)
		(fill yes
			(thermal_gap 0.5)
			(thermal_bridge_width 0.5)
			(island_removal_mode 0)
		)
		(polygon
			(pts
				(arc
					(start 401.588224 -152.830022)
					(mid 399.162016 -152.830022)
					(end 401.588224 -152.830022)
				)
			)
		)
	)
	(zone
		(layers "In1.Cu" "In3.Cu" "In6.Cu" "In8.Cu")
		(hatch none 0.5)
		(connect_pads
			(clearance 0)
		)
		(min_thickness 0.25)
		(keepout
			(tracks not_allowed)
			(vias allowed)
			(pads allowed)
			(copperpour not_allowed)
			(footprints allowed)
		)
		(placement
			(enabled no)
			(sheetname "")
		)
		(fill yes
			(thermal_gap 0.5)
			(thermal_bridge_width 0.5)
			(island_removal_mode 0)
		)
		(polygon
			(pts
				(arc
					(start 115.630452 -25.5016)
					(mid 113.852452 -25.5016)
					(end 115.630452 -25.5016)
				)
			)
		)
	)
	(zone
		(layers "In1.Cu" "In3.Cu" "In6.Cu" "In8.Cu")
		(hatch none 0.5)
		(connect_pads
			(clearance 0)
		)
		(min_thickness 0.25)
		(keepout
			(tracks not_allowed)
			(vias allowed)
			(pads allowed)
			(copperpour not_allowed)
			(footprints allowed)
		)
		(placement
			(enabled no)
			(sheetname "")
		)
		(fill yes
			(thermal_gap 0.5)
			(thermal_bridge_width 0.5)
			(island_removal_mode 0)
		)
		(polygon
			(pts
				(arc
					(start 114.868452 -36.7792)
					(mid 113.090452 -36.7792)
					(end 114.868452 -36.7792)
				)
			)
		)
	)
	(zone
		(layers "In1.Cu" "In3.Cu" "In6.Cu" "In8.Cu")
		(hatch none 0.5)
		(connect_pads
			(clearance 0)
		)
		(min_thickness 0.25)
		(keepout
			(tracks not_allowed)
			(vias allowed)
			(pads allowed)
			(copperpour not_allowed)
			(footprints allowed)
		)
		(placement
			(enabled no)
			(sheetname "")
		)
		(fill yes
			(thermal_gap 0.5)
			(thermal_bridge_width 0.5)
			(island_removal_mode 0)
		)
		(polygon
			(pts
				(arc
					(start 64.213232 -156.830014)
					(mid 61.787024 -156.830014)
					(end 64.213232 -156.830014)
				)
			)
		)
	)
	(zone
		(layers "In1.Cu" "In3.Cu" "In6.Cu" "In8.Cu")
		(hatch none 0.5)
		(connect_pads
			(clearance 0)
		)
		(min_thickness 0.25)
		(keepout
			(tracks not_allowed)
			(vias allowed)
			(pads allowed)
			(copperpour not_allowed)
			(footprints allowed)
		)
		(placement
			(enabled no)
			(sheetname "")
		)
		(fill yes
			(thermal_gap 0.5)
			(thermal_bridge_width 0.5)
			(island_removal_mode 0)
		)
		(polygon
			(pts
				(arc
					(start 333.8068 -20.8026)
					(mid 332.0288 -20.8026)
					(end 333.8068 -20.8026)
				)
			)
		)
	)
	(zone
		(layers "In1.Cu" "In3.Cu" "In6.Cu" "In8.Cu")
		(hatch none 0.5)
		(connect_pads
			(clearance 0)
		)
		(min_thickness 0.25)
		(keepout
			(tracks not_allowed)
			(vias allowed)
			(pads allowed)
			(copperpour not_allowed)
			(footprints allowed)
		)
		(placement
			(enabled no)
			(sheetname "")
		)
		(fill yes
			(thermal_gap 0.5)
			(thermal_bridge_width 0.5)
			(island_removal_mode 0)
		)
		(polygon
			(pts
				(arc
					(start 334.5688 -31.3182)
					(mid 332.7908 -31.3182)
					(end 334.5688 -31.3182)
				)
			)
		)
	)
	(zone
		(layers "In1.Cu" "In3.Cu" "In6.Cu" "In8.Cu")
		(hatch none 0.5)
		(connect_pads
			(clearance 0)
		)
		(min_thickness 0.25)
		(keepout
			(tracks not_allowed)
			(vias allowed)
			(pads allowed)
			(copperpour not_allowed)
			(footprints allowed)
		)
		(placement
			(enabled no)
			(sheetname "")
		)
		(fill yes
			(thermal_gap 0.5)
			(thermal_bridge_width 0.5)
			(island_removal_mode 0)
		)
		(polygon
			(pts
				(arc
					(start 335.3308 -56.9214)
					(mid 333.5528 -56.9214)
					(end 335.3308 -56.9214)
				)
			)
		)
	)
	(zone
		(layers "In1.Cu" "In3.Cu" "In6.Cu" "In8.Cu")
		(hatch none 0.5)
		(connect_pads
			(clearance 0)
		)
		(min_thickness 0.25)
		(keepout
			(tracks not_allowed)
			(vias allowed)
			(pads allowed)
			(copperpour not_allowed)
			(footprints allowed)
		)
		(placement
			(enabled no)
			(sheetname "")
		)
		(fill yes
			(thermal_gap 0.5)
			(thermal_bridge_width 0.5)
			(island_removal_mode 0)
		)
		(polygon
			(pts
				(arc
					(start 336.0928 -31.3182)
					(mid 334.3148 -31.3182)
					(end 336.0928 -31.3182)
				)
			)
		)
	)
	(zone
		(layers "In1.Cu" "In3.Cu" "In6.Cu" "In8.Cu")
		(hatch none 0.5)
		(connect_pads
			(clearance 0)
		)
		(min_thickness 0.25)
		(keepout
			(tracks not_allowed)
			(vias allowed)
			(pads allowed)
			(copperpour not_allowed)
			(footprints allowed)
		)
		(placement
			(enabled no)
			(sheetname "")
		)
		(fill yes
			(thermal_gap 0.5)
			(thermal_bridge_width 0.5)
			(island_removal_mode 0)
		)
		(polygon
			(pts
				(arc
					(start 114.106452 -49.5808)
					(mid 112.328452 -49.5808)
					(end 114.106452 -49.5808)
				)
			)
		)
	)
	(zone
		(layers "In1.Cu" "In3.Cu" "In6.Cu" "In8.Cu")
		(hatch none 0.5)
		(connect_pads
			(clearance 0)
		)
		(min_thickness 0.25)
		(keepout
			(tracks not_allowed)
			(vias allowed)
			(pads allowed)
			(copperpour not_allowed)
			(footprints allowed)
		)
		(placement
			(enabled no)
			(sheetname "")
		)
		(fill yes
			(thermal_gap 0.5)
			(thermal_bridge_width 0.5)
			(island_removal_mode 0)
		)
		(polygon
			(pts
				(arc
					(start 113.344452 -37.5412)
					(mid 111.566452 -37.5412)
					(end 113.344452 -37.5412)
				)
			)
		)
	)
	(zone
		(layers "In1.Cu" "In3.Cu" "In6.Cu" "In8.Cu")
		(hatch none 0.5)
		(connect_pads
			(clearance 0)
		)
		(min_thickness 0.25)
		(keepout
			(tracks not_allowed)
			(vias allowed)
			(pads allowed)
			(copperpour not_allowed)
			(footprints allowed)
		)
		(placement
			(enabled no)
			(sheetname "")
		)
		(fill yes
			(thermal_gap 0.5)
			(thermal_bridge_width 0.5)
			(island_removal_mode 0)
		)
		(polygon
			(pts
				(arc
					(start 334.5688 -78.7146)
					(mid 332.7908 -78.7146)
					(end 334.5688 -78.7146)
				)
			)
		)
	)
	(zone
		(layers "In1.Cu" "In3.Cu" "In6.Cu" "In8.Cu")
		(hatch none 0.5)
		(connect_pads
			(clearance 0)
		)
		(min_thickness 0.25)
		(keepout
			(tracks not_allowed)
			(vias allowed)
			(pads allowed)
			(copperpour not_allowed)
			(footprints allowed)
		)
		(placement
			(enabled no)
			(sheetname "")
		)
		(fill yes
			(thermal_gap 0.5)
			(thermal_bridge_width 0.5)
			(island_removal_mode 0)
		)
		(polygon
			(pts
				(arc
					(start 115.630452 -36.7792)
					(mid 113.852452 -36.7792)
					(end 115.630452 -36.7792)
				)
			)
		)
	)
	(zone
		(layers "In1.Cu" "In3.Cu" "In6.Cu" "In8.Cu")
		(hatch none 0.5)
		(connect_pads
			(clearance 0)
		)
		(min_thickness 0.25)
		(keepout
			(tracks not_allowed)
			(vias allowed)
			(pads allowed)
			(copperpour not_allowed)
			(footprints allowed)
		)
		(placement
			(enabled no)
			(sheetname "")
		)
		(fill yes
			(thermal_gap 0.5)
			(thermal_bridge_width 0.5)
			(island_removal_mode 0)
		)
		(polygon
			(pts
				(arc
					(start 115.630452 -71.374)
					(mid 113.852452 -71.374)
					(end 115.630452 -71.374)
				)
			)
		)
	)
	(zone
		(layers "In1.Cu" "In3.Cu" "In6.Cu" "In8.Cu")
		(hatch none 0.5)
		(connect_pads
			(clearance 0)
		)
		(min_thickness 0.25)
		(keepout
			(tracks not_allowed)
			(vias allowed)
			(pads allowed)
			(copperpour not_allowed)
			(footprints allowed)
		)
		(placement
			(enabled no)
			(sheetname "")
		)
		(fill yes
			(thermal_gap 0.5)
			(thermal_bridge_width 0.5)
			(island_removal_mode 0)
		)
		(polygon
			(pts
				(arc
					(start 401.588224 -160.830006)
					(mid 399.162016 -160.830006)
					(end 401.588224 -160.830006)
				)
			)
		)
	)
	(zone
		(layers "In1.Cu" "In3.Cu" "In6.Cu" "In8.Cu")
		(hatch none 0.5)
		(connect_pads
			(clearance 0)
		)
		(min_thickness 0.25)
		(keepout
			(tracks not_allowed)
			(vias allowed)
			(pads allowed)
			(copperpour not_allowed)
			(footprints allowed)
		)
		(placement
			(enabled no)
			(sheetname "")
		)
		(fill yes
			(thermal_gap 0.5)
			(thermal_bridge_width 0.5)
			(island_removal_mode 0)
		)
		(polygon
			(pts
				(arc
					(start 333.8068 -21.5646)
					(mid 332.0288 -21.5646)
					(end 333.8068 -21.5646)
				)
			)
		)
	)
	(zone
		(layers "In1.Cu" "In3.Cu" "In6.Cu" "In8.Cu")
		(hatch none 0.5)
		(connect_pads
			(clearance 0)
		)
		(min_thickness 0.25)
		(keepout
			(tracks not_allowed)
			(vias allowed)
			(pads allowed)
			(copperpour not_allowed)
			(footprints allowed)
		)
		(placement
			(enabled no)
			(sheetname "")
		)
		(fill yes
			(thermal_gap 0.5)
			(thermal_bridge_width 0.5)
			(island_removal_mode 0)
		)
		(polygon
			(pts
				(arc
					(start 333.0448 -53.8734)
					(mid 331.2668 -53.8734)
					(end 333.0448 -53.8734)
				)
			)
		)
	)
	(zone
		(layers "In1.Cu" "In3.Cu" "In6.Cu" "In8.Cu")
		(hatch none 0.5)
		(connect_pads
			(clearance 0)
		)
		(min_thickness 0.25)
		(keepout
			(tracks not_allowed)
			(vias allowed)
			(pads allowed)
			(copperpour not_allowed)
			(footprints allowed)
		)
		(placement
			(enabled no)
			(sheetname "")
		)
		(fill yes
			(thermal_gap 0.5)
			(thermal_bridge_width 0.5)
			(island_removal_mode 0)
		)
		(polygon
			(pts
				(arc
					(start 333.0448 -79.4766)
					(mid 331.2668 -79.4766)
					(end 333.0448 -79.4766)
				)
			)
		)
	)
	(zone
		(layers "In1.Cu" "In3.Cu" "In6.Cu" "In8.Cu")
		(hatch none 0.5)
		(connect_pads
			(clearance 0)
		)
		(min_thickness 0.25)
		(keepout
			(tracks not_allowed)
			(vias allowed)
			(pads allowed)
			(copperpour not_allowed)
			(footprints allowed)
		)
		(placement
			(enabled no)
			(sheetname "")
		)
		(fill yes
			(thermal_gap 0.5)
			(thermal_bridge_width 0.5)
			(island_removal_mode 0)
		)
		(polygon
			(pts
				(arc
					(start 336.0928 -54.6354)
					(mid 334.3148 -54.6354)
					(end 336.0928 -54.6354)
				)
			)
		)
	)
	(zone
		(layers "In1.Cu" "In3.Cu" "In6.Cu" "In8.Cu")
		(hatch none 0.5)
		(connect_pads
			(clearance 0)
		)
		(min_thickness 0.25)
		(keepout
			(tracks not_allowed)
			(vias allowed)
			(pads allowed)
			(copperpour not_allowed)
			(footprints allowed)
		)
		(placement
			(enabled no)
			(sheetname "")
		)
		(fill yes
			(thermal_gap 0.5)
			(thermal_bridge_width 0.5)
			(island_removal_mode 0)
		)
		(polygon
			(pts
				(arc
					(start 50.013108 -156.830014)
					(mid 47.5869 -156.830014)
					(end 50.013108 -156.830014)
				)
			)
		)
	)
	(zone
		(layers "In1.Cu" "In3.Cu" "In6.Cu" "In8.Cu")
		(hatch none 0.5)
		(connect_pads
			(clearance 0)
		)
		(min_thickness 0.25)
		(keepout
			(tracks not_allowed)
			(vias allowed)
			(pads allowed)
			(copperpour not_allowed)
			(footprints allowed)
		)
		(placement
			(enabled no)
			(sheetname "")
		)
		(fill yes
			(thermal_gap 0.5)
			(thermal_bridge_width 0.5)
			(island_removal_mode 0)
		)
		(polygon
			(pts
				(arc
					(start 114.868452 -14.224)
					(mid 113.090452 -14.224)
					(end 114.868452 -14.224)
				)
			)
		)
	)
	(zone
		(layers "In1.Cu" "In3.Cu" "In6.Cu" "In8.Cu")
		(hatch none 0.5)
		(connect_pads
			(clearance 0)
		)
		(min_thickness 0.25)
		(keepout
			(tracks not_allowed)
			(vias allowed)
			(pads allowed)
			(copperpour not_allowed)
			(footprints allowed)
		)
		(placement
			(enabled no)
			(sheetname "")
		)
		(fill yes
			(thermal_gap 0.5)
			(thermal_bridge_width 0.5)
			(island_removal_mode 0)
		)
		(polygon
			(pts
				(arc
					(start 333.0448 -76.4286)
					(mid 331.2668 -76.4286)
					(end 333.0448 -76.4286)
				)
			)
		)
	)
	(zone
		(layers "In1.Cu" "In3.Cu" "In6.Cu" "In8.Cu")
		(hatch none 0.5)
		(connect_pads
			(clearance 0)
		)
		(min_thickness 0.25)
		(keepout
			(tracks not_allowed)
			(vias allowed)
			(pads allowed)
			(copperpour not_allowed)
			(footprints allowed)
		)
		(placement
			(enabled no)
			(sheetname "")
		)
		(fill yes
			(thermal_gap 0.5)
			(thermal_bridge_width 0.5)
			(island_removal_mode 0)
		)
		(polygon
			(pts
				(arc
					(start 85.852 -5.334)
					(mid 84.074 -5.334)
					(end 85.852 -5.334)
				)
			)
		)
	)
	(zone
		(layers "In1.Cu" "In3.Cu" "In6.Cu" "In8.Cu")
		(hatch none 0.5)
		(connect_pads
			(clearance 0)
		)
		(min_thickness 0.25)
		(keepout
			(tracks not_allowed)
			(vias allowed)
			(pads allowed)
			(copperpour not_allowed)
			(footprints allowed)
		)
		(placement
			(enabled no)
			(sheetname "")
		)
		(fill yes
			(thermal_gap 0.5)
			(thermal_bridge_width 0.5)
			(island_removal_mode 0)
		)
		(polygon
			(pts
				(arc
					(start 378.213112 -156.830014)
					(mid 375.786904 -156.830014)
					(end 378.213112 -156.830014)
				)
			)
		)
	)
	(zone
		(layers "In1.Cu" "In3.Cu" "In6.Cu" "In8.Cu")
		(hatch none 0.5)
		(connect_pads
			(clearance 0)
		)
		(min_thickness 0.25)
		(keepout
			(tracks not_allowed)
			(vias allowed)
			(pads allowed)
			(copperpour not_allowed)
			(footprints allowed)
		)
		(placement
			(enabled no)
			(sheetname "")
		)
		(fill yes
			(thermal_gap 0.5)
			(thermal_bridge_width 0.5)
			(island_removal_mode 0)
		)
		(polygon
			(pts
				(arc
					(start 398.653508 -50.919888)
					(mid 396.620492 -50.919888)
					(end 398.653508 -50.919888)
				)
			)
		)
	)
	(zone
		(layers "In1.Cu" "In3.Cu" "In6.Cu" "In8.Cu")
		(hatch none 0.5)
		(connect_pads
			(clearance 0)
		)
		(min_thickness 0.25)
		(keepout
			(tracks not_allowed)
			(vias allowed)
			(pads allowed)
			(copperpour not_allowed)
			(footprints allowed)
		)
		(placement
			(enabled no)
			(sheetname "")
		)
		(fill yes
			(thermal_gap 0.5)
			(thermal_bridge_width 0.5)
			(island_removal_mode 0)
		)
		(polygon
			(pts
				(arc
					(start 36.088066 -154.830018)
					(mid 33.661858 -154.830018)
					(end 36.088066 -154.830018)
				)
			)
		)
	)
	(zone
		(layers "In1.Cu" "In3.Cu" "In6.Cu" "In8.Cu")
		(hatch none 0.5)
		(connect_pads
			(clearance 0)
		)
		(min_thickness 0.25)
		(keepout
			(tracks not_allowed)
			(vias allowed)
			(pads allowed)
			(copperpour not_allowed)
			(footprints allowed)
		)
		(placement
			(enabled no)
			(sheetname "")
		)
		(fill yes
			(thermal_gap 0.5)
			(thermal_bridge_width 0.5)
			(island_removal_mode 0)
		)
		(polygon
			(pts
				(arc
					(start 357.30942 -4.591304)
					(mid 355.53142 -4.591304)
					(end 357.30942 -4.591304)
				)
			)
		)
	)
	(zone
		(layers "In1.Cu" "In3.Cu" "In6.Cu" "In8.Cu")
		(hatch none 0.5)
		(connect_pads
			(clearance 0)
		)
		(min_thickness 0.25)
		(keepout
			(tracks not_allowed)
			(vias allowed)
			(pads allowed)
			(copperpour not_allowed)
			(footprints allowed)
		)
		(placement
			(enabled no)
			(sheetname "")
		)
		(fill yes
			(thermal_gap 0.5)
			(thermal_bridge_width 0.5)
			(island_removal_mode 0)
		)
		(polygon
			(pts
				(arc
					(start 114.106452 -62.3824)
					(mid 112.328452 -62.3824)
					(end 114.106452 -62.3824)
				)
			)
		)
	)
	(zone
		(layers "In1.Cu" "In3.Cu" "In6.Cu" "In8.Cu")
		(hatch none 0.5)
		(connect_pads
			(clearance 0)
		)
		(min_thickness 0.25)
		(keepout
			(tracks not_allowed)
			(vias allowed)
			(pads allowed)
			(copperpour not_allowed)
			(footprints allowed)
		)
		(placement
			(enabled no)
			(sheetname "")
		)
		(fill yes
			(thermal_gap 0.5)
			(thermal_bridge_width 0.5)
			(island_removal_mode 0)
		)
		(polygon
			(pts
				(arc
					(start 336.0928 -21.5646)
					(mid 334.3148 -21.5646)
					(end 336.0928 -21.5646)
				)
			)
		)
	)
	(zone
		(layers "In1.Cu" "In3.Cu" "In6.Cu" "In8.Cu")
		(hatch none 0.5)
		(connect_pads
			(clearance 0)
		)
		(min_thickness 0.25)
		(keepout
			(tracks not_allowed)
			(vias allowed)
			(pads allowed)
			(copperpour not_allowed)
			(footprints allowed)
		)
		(placement
			(enabled no)
			(sheetname "")
		)
		(fill yes
			(thermal_gap 0.5)
			(thermal_bridge_width 0.5)
			(island_removal_mode 0)
		)
		(polygon
			(pts
				(arc
					(start 78.213204 -158.83001)
					(mid 75.786996 -158.83001)
					(end 78.213204 -158.83001)
				)
			)
		)
	)
	(zone
		(layers "In1.Cu" "In3.Cu" "In6.Cu" "In8.Cu")
		(hatch none 0.5)
		(connect_pads
			(clearance 0)
		)
		(min_thickness 0.25)
		(keepout
			(tracks not_allowed)
			(vias allowed)
			(pads allowed)
			(copperpour not_allowed)
			(footprints allowed)
		)
		(placement
			(enabled no)
			(sheetname "")
		)
		(fill yes
			(thermal_gap 0.5)
			(thermal_bridge_width 0.5)
			(island_removal_mode 0)
		)
		(polygon
			(pts
				(arc
					(start 401.588224 -164.829998)
					(mid 399.162016 -164.829998)
					(end 401.588224 -164.829998)
				)
			)
		)
	)
	(zone
		(layers "In1.Cu" "In3.Cu" "In6.Cu" "In8.Cu")
		(hatch none 0.5)
		(connect_pads
			(clearance 0)
		)
		(min_thickness 0.25)
		(keepout
			(tracks not_allowed)
			(vias allowed)
			(pads allowed)
			(copperpour not_allowed)
			(footprints allowed)
		)
		(placement
			(enabled no)
			(sheetname "")
		)
		(fill yes
			(thermal_gap 0.5)
			(thermal_bridge_width 0.5)
			(island_removal_mode 0)
		)
		(polygon
			(pts
				(arc
					(start 334.5688 -43.3578)
					(mid 332.7908 -43.3578)
					(end 334.5688 -43.3578)
				)
			)
		)
	)
	(zone
		(layers "In1.Cu" "In3.Cu" "In6.Cu" "In8.Cu")
		(hatch none 0.5)
		(connect_pads
			(clearance 0)
		)
		(min_thickness 0.25)
		(keepout
			(tracks not_allowed)
			(vias allowed)
			(pads allowed)
			(copperpour not_allowed)
			(footprints allowed)
		)
		(placement
			(enabled no)
			(sheetname "")
		)
		(fill yes
			(thermal_gap 0.5)
			(thermal_bridge_width 0.5)
			(island_removal_mode 0)
		)
		(polygon
			(pts
				(arc
					(start 116.392452 -16.51)
					(mid 114.614452 -16.51)
					(end 116.392452 -16.51)
				)
			)
		)
	)
	(zone
		(layers "In1.Cu" "In3.Cu" "In6.Cu" "In8.Cu")
		(hatch none 0.5)
		(connect_pads
			(clearance 0)
		)
		(min_thickness 0.25)
		(keepout
			(tracks not_allowed)
			(vias allowed)
			(pads allowed)
			(copperpour not_allowed)
			(footprints allowed)
		)
		(placement
			(enabled no)
			(sheetname "")
		)
		(fill yes
			(thermal_gap 0.5)
			(thermal_bridge_width 0.5)
			(island_removal_mode 0)
		)
		(polygon
			(pts
				(arc
					(start 358.83342 -5.353304)
					(mid 357.05542 -5.353304)
					(end 358.83342 -5.353304)
				)
			)
		)
	)
	(zone
		(layers "In1.Cu" "In3.Cu" "In6.Cu" "In8.Cu")
		(hatch none 0.5)
		(connect_pads
			(clearance 0)
		)
		(min_thickness 0.25)
		(keepout
			(tracks not_allowed)
			(vias allowed)
			(pads allowed)
			(copperpour not_allowed)
			(footprints allowed)
		)
		(placement
			(enabled no)
			(sheetname "")
		)
		(fill yes
			(thermal_gap 0.5)
			(thermal_bridge_width 0.5)
			(island_removal_mode 0)
		)
		(polygon
			(pts
				(arc
					(start 399.588228 -158.83001)
					(mid 397.16202 -158.83001)
					(end 399.588228 -158.83001)
				)
			)
		)
	)
	(zone
		(layers "In1.Cu" "In3.Cu" "In6.Cu" "In8.Cu")
		(hatch none 0.5)
		(connect_pads
			(clearance 0)
		)
		(min_thickness 0.25)
		(keepout
			(tracks not_allowed)
			(vias allowed)
			(pads allowed)
			(copperpour not_allowed)
			(footprints allowed)
		)
		(placement
			(enabled no)
			(sheetname "")
		)
		(fill yes
			(thermal_gap 0.5)
			(thermal_bridge_width 0.5)
			(island_removal_mode 0)
		)
		(polygon
			(pts
				(arc
					(start 36.088066 -166.829994)
					(mid 33.661858 -166.829994)
					(end 36.088066 -166.829994)
				)
			)
		)
	)
	(zone
		(layers "In1.Cu" "In3.Cu" "In6.Cu" "In8.Cu")
		(hatch none 0.5)
		(connect_pads
			(clearance 0)
		)
		(min_thickness 0.25)
		(keepout
			(tracks not_allowed)
			(vias allowed)
			(pads allowed)
			(copperpour not_allowed)
			(footprints allowed)
		)
		(placement
			(enabled no)
			(sheetname "")
		)
		(fill yes
			(thermal_gap 0.5)
			(thermal_bridge_width 0.5)
			(island_removal_mode 0)
		)
		(polygon
			(pts
				(arc
					(start 113.344452 -25.5016)
					(mid 111.566452 -25.5016)
					(end 113.344452 -25.5016)
				)
			)
		)
	)
	(zone
		(layers "In1.Cu" "In3.Cu" "In6.Cu" "In8.Cu")
		(hatch none 0.5)
		(connect_pads
			(clearance 0)
		)
		(min_thickness 0.25)
		(keepout
			(tracks not_allowed)
			(vias allowed)
			(pads allowed)
			(copperpour not_allowed)
			(footprints allowed)
		)
		(placement
			(enabled no)
			(sheetname "")
		)
		(fill yes
			(thermal_gap 0.5)
			(thermal_bridge_width 0.5)
			(island_removal_mode 0)
		)
		(polygon
			(pts
				(arc
					(start 333.0448 -42.5958)
					(mid 331.2668 -42.5958)
					(end 333.0448 -42.5958)
				)
			)
		)
	)
	(zone
		(layers "In1.Cu" "In3.Cu" "In6.Cu" "In8.Cu")
		(hatch none 0.5)
		(connect_pads
			(clearance 0)
		)
		(min_thickness 0.25)
		(keepout
			(tracks not_allowed)
			(vias allowed)
			(pads allowed)
			(copperpour not_allowed)
			(footprints allowed)
		)
		(placement
			(enabled no)
			(sheetname "")
		)
		(fill yes
			(thermal_gap 0.5)
			(thermal_bridge_width 0.5)
			(island_removal_mode 0)
		)
		(polygon
			(pts
				(arc
					(start 473.029788 -76.309982)
					(mid 470.210388 -76.309982)
					(end 473.029788 -76.309982)
				)
			)
		)
	)
	(zone
		(layers "In1.Cu" "In3.Cu" "In6.Cu" "In8.Cu")
		(hatch none 0.5)
		(connect_pads
			(clearance 0)
		)
		(min_thickness 0.25)
		(keepout
			(tracks not_allowed)
			(vias allowed)
			(pads allowed)
			(copperpour not_allowed)
			(footprints allowed)
		)
		(placement
			(enabled no)
			(sheetname "")
		)
		(fill yes
			(thermal_gap 0.5)
			(thermal_bridge_width 0.5)
			(island_removal_mode 0)
		)
		(polygon
			(pts
				(arc
					(start 333.0448 -66.675)
					(mid 331.2668 -66.675)
					(end 333.0448 -66.675)
				)
			)
		)
	)
	(zone
		(layers "In1.Cu" "In3.Cu" "In6.Cu" "In8.Cu")
		(hatch none 0.5)
		(connect_pads
			(clearance 0)
		)
		(min_thickness 0.25)
		(keepout
			(tracks not_allowed)
			(vias allowed)
			(pads allowed)
			(copperpour not_allowed)
			(footprints allowed)
		)
		(placement
			(enabled no)
			(sheetname "")
		)
		(fill yes
			(thermal_gap 0.5)
			(thermal_bridge_width 0.5)
			(island_removal_mode 0)
		)
		(polygon
			(pts
				(arc
					(start 70.21322 -160.830006)
					(mid 67.787012 -160.830006)
					(end 70.21322 -160.830006)
				)
			)
		)
	)
	(zone
		(layers "In1.Cu" "In3.Cu" "In6.Cu" "In8.Cu")
		(hatch none 0.5)
		(connect_pads
			(clearance 0)
		)
		(min_thickness 0.25)
		(keepout
			(tracks not_allowed)
			(vias allowed)
			(pads allowed)
			(copperpour not_allowed)
			(footprints allowed)
		)
		(placement
			(enabled no)
			(sheetname "")
		)
		(fill yes
			(thermal_gap 0.5)
			(thermal_bridge_width 0.5)
			(island_removal_mode 0)
		)
		(polygon
			(pts
				(arc
					(start 113.344452 -14.224)
					(mid 111.566452 -14.224)
					(end 113.344452 -14.224)
				)
			)
		)
	)
	(zone
		(layers "In1.Cu" "In3.Cu" "In6.Cu" "In8.Cu")
		(hatch none 0.5)
		(connect_pads
			(clearance 0)
		)
		(min_thickness 0.25)
		(keepout
			(tracks not_allowed)
			(vias allowed)
			(pads allowed)
			(copperpour not_allowed)
			(footprints allowed)
		)
		(placement
			(enabled no)
			(sheetname "")
		)
		(fill yes
			(thermal_gap 0.5)
			(thermal_bridge_width 0.5)
			(island_removal_mode 0)
		)
		(polygon
			(pts
				(arc
					(start 336.0928 -56.1594)
					(mid 334.3148 -56.1594)
					(end 336.0928 -56.1594)
				)
			)
		)
	)
	(zone
		(layers "In1.Cu" "In3.Cu" "In6.Cu" "In8.Cu")
		(hatch none 0.5)
		(connect_pads
			(clearance 0)
		)
		(min_thickness 0.25)
		(keepout
			(tracks not_allowed)
			(vias allowed)
			(pads allowed)
			(copperpour not_allowed)
			(footprints allowed)
		)
		(placement
			(enabled no)
			(sheetname "")
		)
		(fill yes
			(thermal_gap 0.5)
			(thermal_bridge_width 0.5)
			(island_removal_mode 0)
		)
		(polygon
			(pts
				(arc
					(start 376.213116 -156.830014)
					(mid 373.786908 -156.830014)
					(end 376.213116 -156.830014)
				)
			)
		)
	)
	(zone
		(layers "In1.Cu" "In3.Cu" "In6.Cu" "In8.Cu")
		(hatch none 0.5)
		(connect_pads
			(clearance 0)
		)
		(min_thickness 0.25)
		(keepout
			(tracks not_allowed)
			(vias allowed)
			(pads allowed)
			(copperpour not_allowed)
			(footprints allowed)
		)
		(placement
			(enabled no)
			(sheetname "")
		)
		(fill yes
			(thermal_gap 0.5)
			(thermal_bridge_width 0.5)
			(island_removal_mode 0)
		)
		(polygon
			(pts
				(arc
					(start 43.88739 -58.42)
					(mid 40.83939 -58.42)
					(end 43.88739 -58.42)
				)
			)
		)
	)
	(zone
		(layers "In1.Cu" "In3.Cu" "In6.Cu" "In8.Cu")
		(hatch none 0.5)
		(connect_pads
			(clearance 0)
		)
		(min_thickness 0.25)
		(keepout
			(tracks not_allowed)
			(vias allowed)
			(pads allowed)
			(copperpour not_allowed)
			(footprints allowed)
		)
		(placement
			(enabled no)
			(sheetname "")
		)
		(fill yes
			(thermal_gap 0.5)
			(thermal_bridge_width 0.5)
			(island_removal_mode 0)
		)
		(polygon
			(pts
				(arc
					(start 470.329768 -68.689982)
					(mid 467.510368 -68.689982)
					(end 470.329768 -68.689982)
				)
			)
		)
	)
	(zone
		(layers "In1.Cu" "In3.Cu" "In6.Cu" "In8.Cu")
		(hatch none 0.5)
		(connect_pads
			(clearance 0)
		)
		(min_thickness 0.25)
		(keepout
			(tracks not_allowed)
			(vias allowed)
			(pads allowed)
			(copperpour not_allowed)
			(footprints allowed)
		)
		(placement
			(enabled no)
			(sheetname "")
		)
		(fill yes
			(thermal_gap 0.5)
			(thermal_bridge_width 0.5)
			(island_removal_mode 0)
		)
		(polygon
			(pts
				(arc
					(start 333.0448 -34.3662)
					(mid 331.2668 -34.3662)
					(end 333.0448 -34.3662)
				)
			)
		)
	)
	(zone
		(layers "In1.Cu" "In3.Cu" "In6.Cu" "In8.Cu")
		(hatch none 0.5)
		(connect_pads
			(clearance 0)
		)
		(min_thickness 0.25)
		(keepout
			(tracks not_allowed)
			(vias allowed)
			(pads allowed)
			(copperpour not_allowed)
			(footprints allowed)
		)
		(placement
			(enabled no)
			(sheetname "")
		)
		(fill yes
			(thermal_gap 0.5)
			(thermal_bridge_width 0.5)
			(island_removal_mode 0)
		)
		(polygon
			(pts
				(arc
					(start 114.868452 -49.5808)
					(mid 113.090452 -49.5808)
					(end 114.868452 -49.5808)
				)
			)
		)
	)
	(zone
		(layers "In1.Cu" "In3.Cu" "In6.Cu" "In8.Cu")
		(hatch none 0.5)
		(connect_pads
			(clearance 0)
		)
		(min_thickness 0.25)
		(keepout
			(tracks not_allowed)
			(vias allowed)
			(pads allowed)
			(copperpour not_allowed)
			(footprints allowed)
		)
		(placement
			(enabled no)
			(sheetname "")
		)
		(fill yes
			(thermal_gap 0.5)
			(thermal_bridge_width 0.5)
			(island_removal_mode 0)
		)
		(polygon
			(pts
				(arc
					(start 62.937898 -91.559888)
					(mid 60.904882 -91.559888)
					(end 62.937898 -91.559888)
				)
			)
		)
	)
	(zone
		(layers "In1.Cu" "In3.Cu" "In6.Cu" "In8.Cu")
		(hatch none 0.5)
		(connect_pads
			(clearance 0)
		)
		(min_thickness 0.25)
		(keepout
			(tracks not_allowed)
			(vias allowed)
			(pads allowed)
			(copperpour not_allowed)
			(footprints allowed)
		)
		(placement
			(enabled no)
			(sheetname "")
		)
		(fill yes
			(thermal_gap 0.5)
			(thermal_bridge_width 0.5)
			(island_removal_mode 0)
		)
		(polygon
			(pts
				(arc
					(start 333.8068 -67.437)
					(mid 332.0288 -67.437)
					(end 333.8068 -67.437)
				)
			)
		)
	)
	(zone
		(layers "In1.Cu" "In3.Cu" "In6.Cu" "In8.Cu")
		(hatch none 0.5)
		(connect_pads
			(clearance 0)
		)
		(min_thickness 0.25)
		(keepout
			(tracks not_allowed)
			(vias allowed)
			(pads allowed)
			(copperpour not_allowed)
			(footprints allowed)
		)
		(placement
			(enabled no)
			(sheetname "")
		)
		(fill yes
			(thermal_gap 0.5)
			(thermal_bridge_width 0.5)
			(island_removal_mode 0)
		)
		(polygon
			(pts
				(arc
					(start 115.630452 -72.136)
					(mid 113.852452 -72.136)
					(end 115.630452 -72.136)
				)
			)
		)
	)
	(zone
		(layers "In1.Cu" "In3.Cu" "In6.Cu" "In8.Cu")
		(hatch none 0.5)
		(connect_pads
			(clearance 0)
		)
		(min_thickness 0.25)
		(keepout
			(tracks not_allowed)
			(vias allowed)
			(pads allowed)
			(copperpour not_allowed)
			(footprints allowed)
		)
		(placement
			(enabled no)
			(sheetname "")
		)
		(fill yes
			(thermal_gap 0.5)
			(thermal_bridge_width 0.5)
			(island_removal_mode 0)
		)
		(polygon
			(pts
				(arc
					(start 116.392452 -62.3824)
					(mid 114.614452 -62.3824)
					(end 116.392452 -62.3824)
				)
			)
		)
	)
	(zone
		(layers "In1.Cu" "In3.Cu" "In6.Cu" "In8.Cu")
		(hatch none 0.5)
		(connect_pads
			(clearance 0)
		)
		(min_thickness 0.25)
		(keepout
			(tracks not_allowed)
			(vias allowed)
			(pads allowed)
			(copperpour not_allowed)
			(footprints allowed)
		)
		(placement
			(enabled no)
			(sheetname "")
		)
		(fill yes
			(thermal_gap 0.5)
			(thermal_bridge_width 0.5)
			(island_removal_mode 0)
		)
		(polygon
			(pts
				(arc
					(start 379.603 -99.06)
					(mid 376.555 -99.06)
					(end 379.603 -99.06)
				)
			)
		)
	)
	(zone
		(layers "In1.Cu" "In3.Cu" "In6.Cu" "In8.Cu")
		(hatch none 0.5)
		(connect_pads
			(clearance 0)
		)
		(min_thickness 0.25)
		(keepout
			(tracks not_allowed)
			(vias allowed)
			(pads allowed)
			(copperpour not_allowed)
			(footprints allowed)
		)
		(placement
			(enabled no)
			(sheetname "")
		)
		(fill yes
			(thermal_gap 0.5)
			(thermal_bridge_width 0.5)
			(island_removal_mode 0)
		)
		(polygon
			(pts
				(arc
					(start 115.630452 -48.8188)
					(mid 113.852452 -48.8188)
					(end 115.630452 -48.8188)
				)
			)
		)
	)
	(zone
		(layers "In1.Cu" "In3.Cu" "In6.Cu" "In8.Cu")
		(hatch none 0.5)
		(connect_pads
			(clearance 0)
		)
		(min_thickness 0.25)
		(keepout
			(tracks not_allowed)
			(vias allowed)
			(pads allowed)
			(copperpour not_allowed)
			(footprints allowed)
		)
		(placement
			(enabled no)
			(sheetname "")
		)
		(fill yes
			(thermal_gap 0.5)
			(thermal_bridge_width 0.5)
			(island_removal_mode 0)
		)
		(polygon
			(pts
				(arc
					(start 399.588228 -166.829994)
					(mid 397.16202 -166.829994)
					(end 399.588228 -166.829994)
				)
			)
		)
	)
	(zone
		(layers "In1.Cu" "In3.Cu" "In6.Cu" "In8.Cu")
		(hatch none 0.5)
		(connect_pads
			(clearance 0)
		)
		(min_thickness 0.25)
		(keepout
			(tracks not_allowed)
			(vias allowed)
			(pads allowed)
			(copperpour not_allowed)
			(footprints allowed)
		)
		(placement
			(enabled no)
			(sheetname "")
		)
		(fill yes
			(thermal_gap 0.5)
			(thermal_bridge_width 0.5)
			(island_removal_mode 0)
		)
		(polygon
			(pts
				(arc
					(start 84.328 -4.572)
					(mid 82.55 -4.572)
					(end 84.328 -4.572)
				)
			)
		)
	)
	(zone
		(layers "In1.Cu" "In3.Cu" "In6.Cu" "In8.Cu")
		(hatch none 0.5)
		(connect_pads
			(clearance 0)
		)
		(min_thickness 0.25)
		(keepout
			(tracks not_allowed)
			(vias allowed)
			(pads allowed)
			(copperpour not_allowed)
			(footprints allowed)
		)
		(placement
			(enabled no)
			(sheetname "")
		)
		(fill yes
			(thermal_gap 0.5)
			(thermal_bridge_width 0.5)
			(island_removal_mode 0)
		)
		(polygon
			(pts
				(arc
					(start 335.3308 -65.913)
					(mid 333.5528 -65.913)
					(end 335.3308 -65.913)
				)
			)
		)
	)
	(zone
		(layers "In1.Cu" "In3.Cu" "In6.Cu" "In8.Cu")
		(hatch none 0.5)
		(connect_pads
			(clearance 0)
		)
		(min_thickness 0.25)
		(keepout
			(tracks not_allowed)
			(vias allowed)
			(pads allowed)
			(copperpour not_allowed)
			(footprints allowed)
		)
		(placement
			(enabled no)
			(sheetname "")
		)
		(fill yes
			(thermal_gap 0.5)
			(thermal_bridge_width 0.5)
			(island_removal_mode 0)
		)
		(polygon
			(pts
				(arc
					(start 56.013096 -160.830006)
					(mid 53.586888 -160.830006)
					(end 56.013096 -160.830006)
				)
			)
		)
	)
	(zone
		(layers "In1.Cu" "In3.Cu" "In6.Cu" "In8.Cu")
		(hatch none 0.5)
		(connect_pads
			(clearance 0)
		)
		(min_thickness 0.25)
		(keepout
			(tracks not_allowed)
			(vias allowed)
			(pads allowed)
			(copperpour not_allowed)
			(footprints allowed)
		)
		(placement
			(enabled no)
			(sheetname "")
		)
		(fill yes
			(thermal_gap 0.5)
			(thermal_bridge_width 0.5)
			(island_removal_mode 0)
		)
		(polygon
			(pts
				(arc
					(start 116.392452 -14.986)
					(mid 114.614452 -14.986)
					(end 116.392452 -14.986)
				)
			)
		)
	)
	(zone
		(layers "In1.Cu" "In3.Cu" "In6.Cu" "In8.Cu")
		(hatch none 0.5)
		(connect_pads
			(clearance 0)
		)
		(min_thickness 0.25)
		(keepout
			(tracks not_allowed)
			(vias allowed)
			(pads allowed)
			(copperpour not_allowed)
			(footprints allowed)
		)
		(placement
			(enabled no)
			(sheetname "")
		)
		(fill yes
			(thermal_gap 0.5)
			(thermal_bridge_width 0.5)
			(island_removal_mode 0)
		)
		(polygon
			(pts
				(arc
					(start 116.392452 -14.224)
					(mid 114.614452 -14.224)
					(end 116.392452 -14.224)
				)
			)
		)
	)
	(zone
		(layers "In1.Cu" "In3.Cu" "In6.Cu" "In8.Cu")
		(hatch none 0.5)
		(connect_pads
			(clearance 0)
		)
		(min_thickness 0.25)
		(keepout
			(tracks not_allowed)
			(vias allowed)
			(pads allowed)
			(copperpour not_allowed)
			(footprints allowed)
		)
		(placement
			(enabled no)
			(sheetname "")
		)
		(fill yes
			(thermal_gap 0.5)
			(thermal_bridge_width 0.5)
			(island_removal_mode 0)
		)
		(polygon
			(pts
				(arc
					(start 333.8068 -76.4286)
					(mid 332.0288 -76.4286)
					(end 333.8068 -76.4286)
				)
			)
		)
	)
	(zone
		(layers "In1.Cu" "In3.Cu" "In6.Cu" "In8.Cu")
		(hatch none 0.5)
		(connect_pads
			(clearance 0)
		)
		(min_thickness 0.25)
		(keepout
			(tracks not_allowed)
			(vias allowed)
			(pads allowed)
			(copperpour not_allowed)
			(footprints allowed)
		)
		(placement
			(enabled no)
			(sheetname "")
		)
		(fill yes
			(thermal_gap 0.5)
			(thermal_bridge_width 0.5)
			(island_removal_mode 0)
		)
		(polygon
			(pts
				(arc
					(start 38.088062 -166.829994)
					(mid 35.661854 -166.829994)
					(end 38.088062 -166.829994)
				)
			)
		)
	)
	(zone
		(layers "In1.Cu" "In3.Cu" "In6.Cu" "In8.Cu")
		(hatch none 0.5)
		(connect_pads
			(clearance 0)
		)
		(min_thickness 0.25)
		(keepout
			(tracks not_allowed)
			(vias allowed)
			(pads allowed)
			(copperpour not_allowed)
			(footprints allowed)
		)
		(placement
			(enabled no)
			(sheetname "")
		)
		(fill yes
			(thermal_gap 0.5)
			(thermal_bridge_width 0.5)
			(island_removal_mode 0)
		)
		(polygon
			(pts
				(arc
					(start 114.868452 -70.612)
					(mid 113.090452 -70.612)
					(end 114.868452 -70.612)
				)
			)
		)
	)
	(zone
		(layers "In1.Cu" "In3.Cu" "In6.Cu" "In8.Cu")
		(hatch none 0.5)
		(connect_pads
			(clearance 0)
		)
		(min_thickness 0.25)
		(keepout
			(tracks not_allowed)
			(vias allowed)
			(pads allowed)
			(copperpour not_allowed)
			(footprints allowed)
		)
		(placement
			(enabled no)
			(sheetname "")
		)
		(fill yes
			(thermal_gap 0.5)
			(thermal_bridge_width 0.5)
			(island_removal_mode 0)
		)
		(polygon
			(pts
				(arc
					(start 335.3308 -44.1198)
					(mid 333.5528 -44.1198)
					(end 335.3308 -44.1198)
				)
			)
		)
	)
	(zone
		(layers "In1.Cu" "In3.Cu" "In6.Cu" "In8.Cu")
		(hatch none 0.5)
		(connect_pads
			(clearance 0)
		)
		(min_thickness 0.25)
		(keepout
			(tracks not_allowed)
			(vias allowed)
			(pads allowed)
			(copperpour not_allowed)
			(footprints allowed)
		)
		(placement
			(enabled no)
			(sheetname "")
		)
		(fill yes
			(thermal_gap 0.5)
			(thermal_bridge_width 0.5)
			(island_removal_mode 0)
		)
		(polygon
			(pts
				(arc
					(start 113.344452 -71.374)
					(mid 111.566452 -71.374)
					(end 113.344452 -71.374)
				)
			)
		)
	)
	(zone
		(layers "In1.Cu" "In3.Cu" "In6.Cu" "In8.Cu")
		(hatch none 0.5)
		(connect_pads
			(clearance 0)
		)
		(min_thickness 0.25)
		(keepout
			(tracks not_allowed)
			(vias allowed)
			(pads allowed)
			(copperpour not_allowed)
			(footprints allowed)
		)
		(placement
			(enabled no)
			(sheetname "")
		)
		(fill yes
			(thermal_gap 0.5)
			(thermal_bridge_width 0.5)
			(island_removal_mode 0)
		)
		(polygon
			(pts
				(arc
					(start 113.344452 -16.51)
					(mid 111.566452 -16.51)
					(end 113.344452 -16.51)
				)
			)
		)
	)
	(zone
		(layers "In1.Cu" "In3.Cu" "In6.Cu" "In8.Cu")
		(hatch none 0.5)
		(connect_pads
			(clearance 0)
		)
		(min_thickness 0.25)
		(keepout
			(tracks not_allowed)
			(vias allowed)
			(pads allowed)
			(copperpour not_allowed)
			(footprints allowed)
		)
		(placement
			(enabled no)
			(sheetname "")
		)
		(fill yes
			(thermal_gap 0.5)
			(thermal_bridge_width 0.5)
			(island_removal_mode 0)
		)
		(polygon
			(pts
				(arc
					(start 379.603 -119.38)
					(mid 376.555 -119.38)
					(end 379.603 -119.38)
				)
			)
		)
	)
	(zone
		(layers "In1.Cu" "In3.Cu" "In6.Cu" "In8.Cu")
		(hatch none 0.5)
		(connect_pads
			(clearance 0)
		)
		(min_thickness 0.25)
		(keepout
			(tracks not_allowed)
			(vias allowed)
			(pads allowed)
			(copperpour not_allowed)
			(footprints allowed)
		)
		(placement
			(enabled no)
			(sheetname "")
		)
		(fill yes
			(thermal_gap 0.5)
			(thermal_bridge_width 0.5)
			(island_removal_mode 0)
		)
		(polygon
			(pts
				(arc
					(start 401.588224 -154.830018)
					(mid 399.162016 -154.830018)
					(end 401.588224 -154.830018)
				)
			)
		)
	)
	(zone
		(layers "In1.Cu" "In3.Cu" "In6.Cu" "In8.Cu")
		(hatch none 0.5)
		(connect_pads
			(clearance 0)
		)
		(min_thickness 0.25)
		(keepout
			(tracks not_allowed)
			(vias allowed)
			(pads allowed)
			(copperpour not_allowed)
			(footprints allowed)
		)
		(placement
			(enabled no)
			(sheetname "")
		)
		(fill yes
			(thermal_gap 0.5)
			(thermal_bridge_width 0.5)
			(island_removal_mode 0)
		)
		(polygon
			(pts
				(arc
					(start 358.07142 -3.829304)
					(mid 356.29342 -3.829304)
					(end 358.07142 -3.829304)
				)
			)
		)
	)
	(zone
		(layers "In1.Cu" "In3.Cu" "In6.Cu" "In8.Cu")
		(hatch none 0.5)
		(connect_pads
			(clearance 0)
		)
		(min_thickness 0.25)
		(keepout
			(tracks not_allowed)
			(vias allowed)
			(pads allowed)
			(copperpour not_allowed)
			(footprints allowed)
		)
		(placement
			(enabled no)
			(sheetname "")
		)
		(fill yes
			(thermal_gap 0.5)
			(thermal_bridge_width 0.5)
			(island_removal_mode 0)
		)
		(polygon
			(pts
				(arc
					(start 334.5688 -32.8422)
					(mid 332.7908 -32.8422)
					(end 334.5688 -32.8422)
				)
			)
		)
	)
	(zone
		(layers "In1.Cu" "In3.Cu" "In6.Cu" "In8.Cu")
		(hatch none 0.5)
		(connect_pads
			(clearance 0)
		)
		(min_thickness 0.25)
		(keepout
			(tracks not_allowed)
			(vias allowed)
			(pads allowed)
			(copperpour not_allowed)
			(footprints allowed)
		)
		(placement
			(enabled no)
			(sheetname "")
		)
		(fill yes
			(thermal_gap 0.5)
			(thermal_bridge_width 0.5)
			(island_removal_mode 0)
		)
		(polygon
			(pts
				(arc
					(start 369.873022 -2.590038)
					(mid 367.446814 -2.590038)
					(end 369.873022 -2.590038)
				)
			)
		)
	)
	(zone
		(layers "In1.Cu" "In3.Cu" "In6.Cu" "In8.Cu")
		(hatch none 0.5)
		(connect_pads
			(clearance 0)
		)
		(min_thickness 0.25)
		(keepout
			(tracks not_allowed)
			(vias allowed)
			(pads allowed)
			(copperpour not_allowed)
			(footprints allowed)
		)
		(placement
			(enabled no)
			(sheetname "")
		)
		(fill yes
			(thermal_gap 0.5)
			(thermal_bridge_width 0.5)
			(island_removal_mode 0)
		)
		(polygon
			(pts
				(arc
					(start 334.5688 -44.1198)
					(mid 332.7908 -44.1198)
					(end 334.5688 -44.1198)
				)
			)
		)
	)
	(zone
		(layers "In1.Cu" "In3.Cu" "In6.Cu" "In8.Cu")
		(hatch none 0.5)
		(connect_pads
			(clearance 0)
		)
		(min_thickness 0.25)
		(keepout
			(tracks not_allowed)
			(vias allowed)
			(pads allowed)
			(copperpour not_allowed)
			(footprints allowed)
		)
		(placement
			(enabled no)
			(sheetname "")
		)
		(fill yes
			(thermal_gap 0.5)
			(thermal_bridge_width 0.5)
			(island_removal_mode 0)
		)
		(polygon
			(pts
				(arc
					(start 333.0448 -68.199)
					(mid 331.2668 -68.199)
					(end 333.0448 -68.199)
				)
			)
		)
	)
	(zone
		(layers "In1.Cu" "In3.Cu" "In6.Cu" "In8.Cu")
		(hatch none 0.5)
		(connect_pads
			(clearance 0)
		)
		(min_thickness 0.25)
		(keepout
			(tracks not_allowed)
			(vias allowed)
			(pads allowed)
			(copperpour not_allowed)
			(footprints allowed)
		)
		(placement
			(enabled no)
			(sheetname "")
		)
		(fill yes
			(thermal_gap 0.5)
			(thermal_bridge_width 0.5)
			(island_removal_mode 0)
		)
		(polygon
			(pts
				(arc
					(start 398.653508 -132.199888)
					(mid 396.620492 -132.199888)
					(end 398.653508 -132.199888)
				)
			)
		)
	)
	(zone
		(layers "In1.Cu" "In3.Cu" "In6.Cu" "In8.Cu")
		(hatch none 0.5)
		(connect_pads
			(clearance 0)
		)
		(min_thickness 0.25)
		(keepout
			(tracks not_allowed)
			(vias allowed)
			(pads allowed)
			(copperpour not_allowed)
			(footprints allowed)
		)
		(placement
			(enabled no)
			(sheetname "")
		)
		(fill yes
			(thermal_gap 0.5)
			(thermal_bridge_width 0.5)
			(island_removal_mode 0)
		)
		(polygon
			(pts
				(arc
					(start 76.213208 -158.83001)
					(mid 73.787 -158.83001)
					(end 76.213208 -158.83001)
				)
			)
		)
	)
	(zone
		(layers "In1.Cu" "In3.Cu" "In6.Cu" "In8.Cu")
		(hatch none 0.5)
		(connect_pads
			(clearance 0)
		)
		(min_thickness 0.25)
		(keepout
			(tracks not_allowed)
			(vias allowed)
			(pads allowed)
			(copperpour not_allowed)
			(footprints allowed)
		)
		(placement
			(enabled no)
			(sheetname "")
		)
		(fill yes
			(thermal_gap 0.5)
			(thermal_bridge_width 0.5)
			(island_removal_mode 0)
		)
		(polygon
			(pts
				(arc
					(start 116.392452 -36.7792)
					(mid 114.614452 -36.7792)
					(end 116.392452 -36.7792)
				)
			)
		)
	)
	(zone
		(layers "In1.Cu" "In3.Cu" "In6.Cu" "In8.Cu")
		(hatch none 0.5)
		(connect_pads
			(clearance 0)
		)
		(min_thickness 0.25)
		(keepout
			(tracks not_allowed)
			(vias allowed)
			(pads allowed)
			(copperpour not_allowed)
			(footprints allowed)
		)
		(placement
			(enabled no)
			(sheetname "")
		)
		(fill yes
			(thermal_gap 0.5)
			(thermal_bridge_width 0.5)
			(island_removal_mode 0)
		)
		(polygon
			(pts
				(arc
					(start 43.379898 -50.919888)
					(mid 41.346882 -50.919888)
					(end 43.379898 -50.919888)
				)
			)
		)
	)
	(zone
		(layers "In1.Cu" "In3.Cu" "In6.Cu" "In8.Cu")
		(hatch none 0.5)
		(connect_pads
			(clearance 0)
		)
		(min_thickness 0.25)
		(keepout
			(tracks not_allowed)
			(vias allowed)
			(pads allowed)
			(copperpour not_allowed)
			(footprints allowed)
		)
		(placement
			(enabled no)
			(sheetname "")
		)
		(fill yes
			(thermal_gap 0.5)
			(thermal_bridge_width 0.5)
			(island_removal_mode 0)
		)
		(polygon
			(pts
				(arc
					(start 114.868452 -37.5412)
					(mid 113.090452 -37.5412)
					(end 114.868452 -37.5412)
				)
			)
		)
	)
	(zone
		(layers "In1.Cu" "In3.Cu" "In6.Cu" "In8.Cu")
		(hatch none 0.5)
		(connect_pads
			(clearance 0)
		)
		(min_thickness 0.25)
		(keepout
			(tracks not_allowed)
			(vias allowed)
			(pads allowed)
			(copperpour not_allowed)
			(footprints allowed)
		)
		(placement
			(enabled no)
			(sheetname "")
		)
		(fill yes
			(thermal_gap 0.5)
			(thermal_bridge_width 0.5)
			(island_removal_mode 0)
		)
		(polygon
			(pts
				(arc
					(start 113.344452 -72.898)
					(mid 111.566452 -72.898)
					(end 113.344452 -72.898)
				)
			)
		)
	)
	(zone
		(layers "In1.Cu" "In3.Cu" "In6.Cu" "In8.Cu")
		(hatch none 0.5)
		(connect_pads
			(clearance 0)
		)
		(min_thickness 0.25)
		(keepout
			(tracks not_allowed)
			(vias allowed)
			(pads allowed)
			(copperpour not_allowed)
			(footprints allowed)
		)
		(placement
			(enabled no)
			(sheetname "")
		)
		(fill yes
			(thermal_gap 0.5)
			(thermal_bridge_width 0.5)
			(island_removal_mode 0)
		)
		(polygon
			(pts
				(arc
					(start 401.588224 -166.829994)
					(mid 399.162016 -166.829994)
					(end 401.588224 -166.829994)
				)
			)
		)
	)
	(zone
		(layers "In1.Cu" "In3.Cu" "In6.Cu" "In8.Cu")
		(hatch none 0.5)
		(connect_pads
			(clearance 0)
		)
		(min_thickness 0.25)
		(keepout
			(tracks not_allowed)
			(vias allowed)
			(pads allowed)
			(copperpour not_allowed)
			(footprints allowed)
		)
		(placement
			(enabled no)
			(sheetname "")
		)
		(fill yes
			(thermal_gap 0.5)
			(thermal_bridge_width 0.5)
			(island_removal_mode 0)
		)
		(polygon
			(pts
				(arc
					(start 116.392452 -38.3032)
					(mid 114.614452 -38.3032)
					(end 116.392452 -38.3032)
				)
			)
		)
	)
	(zone
		(layers "In1.Cu" "In3.Cu" "In6.Cu" "In8.Cu")
		(hatch none 0.5)
		(connect_pads
			(clearance 0)
		)
		(min_thickness 0.25)
		(keepout
			(tracks not_allowed)
			(vias allowed)
			(pads allowed)
			(copperpour not_allowed)
			(footprints allowed)
		)
		(placement
			(enabled no)
			(sheetname "")
		)
		(fill yes
			(thermal_gap 0.5)
			(thermal_bridge_width 0.5)
			(island_removal_mode 0)
		)
		(polygon
			(pts
				(arc
					(start 113.344452 -26.2636)
					(mid 111.566452 -26.2636)
					(end 113.344452 -26.2636)
				)
			)
		)
	)
	(zone
		(layers "In1.Cu" "In3.Cu" "In6.Cu" "In8.Cu")
		(hatch none 0.5)
		(connect_pads
			(clearance 0)
		)
		(min_thickness 0.25)
		(keepout
			(tracks not_allowed)
			(vias allowed)
			(pads allowed)
			(copperpour not_allowed)
			(footprints allowed)
		)
		(placement
			(enabled no)
			(sheetname "")
		)
		(fill yes
			(thermal_gap 0.5)
			(thermal_bridge_width 0.5)
			(island_removal_mode 0)
		)
		(polygon
			(pts
				(arc
					(start 358.83342 -4.591304)
					(mid 357.05542 -4.591304)
					(end 358.83342 -4.591304)
				)
			)
		)
	)
	(zone
		(layers "In1.Cu" "In3.Cu" "In6.Cu" "In8.Cu")
		(hatch none 0.5)
		(connect_pads
			(clearance 0)
		)
		(min_thickness 0.25)
		(keepout
			(tracks not_allowed)
			(vias allowed)
			(pads allowed)
			(copperpour not_allowed)
			(footprints allowed)
		)
		(placement
			(enabled no)
			(sheetname "")
		)
		(fill yes
			(thermal_gap 0.5)
			(thermal_bridge_width 0.5)
			(island_removal_mode 0)
		)
		(polygon
			(pts
				(arc
					(start 334.5688 -33.6042)
					(mid 332.7908 -33.6042)
					(end 334.5688 -33.6042)
				)
			)
		)
	)
	(zone
		(layers "In1.Cu" "In3.Cu" "In6.Cu" "In8.Cu")
		(hatch none 0.5)
		(connect_pads
			(clearance 0)
		)
		(min_thickness 0.25)
		(keepout
			(tracks not_allowed)
			(vias allowed)
			(pads allowed)
			(copperpour not_allowed)
			(footprints allowed)
		)
		(placement
			(enabled no)
			(sheetname "")
		)
		(fill yes
			(thermal_gap 0.5)
			(thermal_bridge_width 0.5)
			(island_removal_mode 0)
		)
		(polygon
			(pts
				(arc
					(start 115.630452 -62.3824)
					(mid 113.852452 -62.3824)
					(end 115.630452 -62.3824)
				)
			)
		)
	)
	(zone
		(layers "In1.Cu" "In3.Cu" "In6.Cu" "In8.Cu")
		(hatch none 0.5)
		(connect_pads
			(clearance 0)
		)
		(min_thickness 0.25)
		(keepout
			(tracks not_allowed)
			(vias allowed)
			(pads allowed)
			(copperpour not_allowed)
			(footprints allowed)
		)
		(placement
			(enabled no)
			(sheetname "")
		)
		(fill yes
			(thermal_gap 0.5)
			(thermal_bridge_width 0.5)
			(island_removal_mode 0)
		)
		(polygon
			(pts
				(arc
					(start 333.8068 -78.7146)
					(mid 332.0288 -78.7146)
					(end 333.8068 -78.7146)
				)
			)
		)
	)
	(zone
		(layers "In1.Cu" "In3.Cu" "In6.Cu" "In8.Cu")
		(hatch none 0.5)
		(connect_pads
			(clearance 0)
		)
		(min_thickness 0.25)
		(keepout
			(tracks not_allowed)
			(vias allowed)
			(pads allowed)
			(copperpour not_allowed)
			(footprints allowed)
		)
		(placement
			(enabled no)
			(sheetname "")
		)
		(fill yes
			(thermal_gap 0.5)
			(thermal_bridge_width 0.5)
			(island_removal_mode 0)
		)
		(polygon
			(pts
				(arc
					(start 335.3308 -34.3662)
					(mid 333.5528 -34.3662)
					(end 335.3308 -34.3662)
				)
			)
		)
	)
	(zone
		(layers "In1.Cu" "In3.Cu" "In6.Cu" "In8.Cu")
		(hatch none 0.5)
		(connect_pads
			(clearance 0)
		)
		(min_thickness 0.25)
		(keepout
			(tracks not_allowed)
			(vias allowed)
			(pads allowed)
			(copperpour not_allowed)
			(footprints allowed)
		)
		(placement
			(enabled no)
			(sheetname "")
		)
		(fill yes
			(thermal_gap 0.5)
			(thermal_bridge_width 0.5)
			(island_removal_mode 0)
		)
		(polygon
			(pts
				(arc
					(start 116.392452 -60.0964)
					(mid 114.614452 -60.0964)
					(end 116.392452 -60.0964)
				)
			)
		)
	)
	(zone
		(layers "In1.Cu" "In3.Cu" "In6.Cu" "In8.Cu")
		(hatch none 0.5)
		(connect_pads
			(clearance 0)
		)
		(min_thickness 0.25)
		(keepout
			(tracks not_allowed)
			(vias allowed)
			(pads allowed)
			(copperpour not_allowed)
			(footprints allowed)
		)
		(placement
			(enabled no)
			(sheetname "")
		)
		(fill yes
			(thermal_gap 0.5)
			(thermal_bridge_width 0.5)
			(island_removal_mode 0)
		)
		(polygon
			(pts
				(arc
					(start 333.0448 -56.9214)
					(mid 331.2668 -56.9214)
					(end 333.0448 -56.9214)
				)
			)
		)
	)
	(zone
		(layers "In1.Cu" "In3.Cu" "In6.Cu" "In8.Cu")
		(hatch none 0.5)
		(connect_pads
			(clearance 0)
		)
		(min_thickness 0.25)
		(keepout
			(tracks not_allowed)
			(vias allowed)
			(pads allowed)
			(copperpour not_allowed)
			(footprints allowed)
		)
		(placement
			(enabled no)
			(sheetname "")
		)
		(fill yes
			(thermal_gap 0.5)
			(thermal_bridge_width 0.5)
			(island_removal_mode 0)
		)
		(polygon
			(pts
				(arc
					(start 399.588228 -168.82999)
					(mid 397.16202 -168.82999)
					(end 399.588228 -168.82999)
				)
			)
		)
	)
	(zone
		(layers "In1.Cu" "In3.Cu" "In6.Cu" "In8.Cu")
		(hatch none 0.5)
		(connect_pads
			(clearance 0)
		)
		(min_thickness 0.25)
		(keepout
			(tracks not_allowed)
			(vias allowed)
			(pads allowed)
			(copperpour not_allowed)
			(footprints allowed)
		)
		(placement
			(enabled no)
			(sheetname "")
		)
		(fill yes
			(thermal_gap 0.5)
			(thermal_bridge_width 0.5)
			(island_removal_mode 0)
		)
		(polygon
			(pts
				(arc
					(start 113.344452 -60.8584)
					(mid 111.566452 -60.8584)
					(end 113.344452 -60.8584)
				)
			)
		)
	)
	(zone
		(layers "In1.Cu" "In3.Cu" "In6.Cu" "In8.Cu")
		(hatch none 0.5)
		(connect_pads
			(clearance 0)
		)
		(min_thickness 0.25)
		(keepout
			(tracks not_allowed)
			(vias allowed)
			(pads allowed)
			(copperpour not_allowed)
			(footprints allowed)
		)
		(placement
			(enabled no)
			(sheetname "")
		)
		(fill yes
			(thermal_gap 0.5)
			(thermal_bridge_width 0.5)
			(island_removal_mode 0)
		)
		(polygon
			(pts
				(arc
					(start 114.106452 -16.51)
					(mid 112.328452 -16.51)
					(end 114.106452 -16.51)
				)
			)
		)
	)
	(zone
		(layers "In1.Cu" "In3.Cu" "In6.Cu" "In8.Cu")
		(hatch none 0.5)
		(connect_pads
			(clearance 0)
		)
		(min_thickness 0.25)
		(keepout
			(tracks not_allowed)
			(vias allowed)
			(pads allowed)
			(copperpour not_allowed)
			(footprints allowed)
		)
		(placement
			(enabled no)
			(sheetname "")
		)
		(fill yes
			(thermal_gap 0.5)
			(thermal_bridge_width 0.5)
			(island_removal_mode 0)
		)
		(polygon
			(pts
				(arc
					(start 366.213136 -160.830006)
					(mid 363.786928 -160.830006)
					(end 366.213136 -160.830006)
				)
			)
		)
	)
	(zone
		(layers "In1.Cu" "In3.Cu" "In6.Cu" "In8.Cu")
		(hatch none 0.5)
		(connect_pads
			(clearance 0)
		)
		(min_thickness 0.25)
		(keepout
			(tracks not_allowed)
			(vias allowed)
			(pads allowed)
			(copperpour not_allowed)
			(footprints allowed)
		)
		(placement
			(enabled no)
			(sheetname "")
		)
		(fill yes
			(thermal_gap 0.5)
			(thermal_bridge_width 0.5)
			(island_removal_mode 0)
		)
		(polygon
			(pts
				(arc
					(start 36.088066 -156.830014)
					(mid 33.661858 -156.830014)
					(end 36.088066 -156.830014)
				)
			)
		)
	)
	(zone
		(layers "In1.Cu" "In3.Cu" "In6.Cu" "In8.Cu")
		(hatch none 0.5)
		(connect_pads
			(clearance 0)
		)
		(min_thickness 0.25)
		(keepout
			(tracks not_allowed)
			(vias allowed)
			(pads allowed)
			(copperpour not_allowed)
			(footprints allowed)
		)
		(placement
			(enabled no)
			(sheetname "")
		)
		(fill yes
			(thermal_gap 0.5)
			(thermal_bridge_width 0.5)
			(island_removal_mode 0)
		)
		(polygon
			(pts
				(arc
					(start 115.630452 -14.224)
					(mid 113.852452 -14.224)
					(end 115.630452 -14.224)
				)
			)
		)
	)
	(zone
		(layers "In1.Cu" "In3.Cu" "In6.Cu" "In8.Cu")
		(hatch none 0.5)
		(connect_pads
			(clearance 0)
		)
		(min_thickness 0.25)
		(keepout
			(tracks not_allowed)
			(vias allowed)
			(pads allowed)
			(copperpour not_allowed)
			(footprints allowed)
		)
		(placement
			(enabled no)
			(sheetname "")
		)
		(fill yes
			(thermal_gap 0.5)
			(thermal_bridge_width 0.5)
			(island_removal_mode 0)
		)
		(polygon
			(pts
				(arc
					(start 115.630452 -37.5412)
					(mid 113.852452 -37.5412)
					(end 115.630452 -37.5412)
				)
			)
		)
	)
	(zone
		(layers "In1.Cu" "In3.Cu" "In6.Cu" "In8.Cu")
		(hatch none 0.5)
		(connect_pads
			(clearance 0)
		)
		(min_thickness 0.25)
		(keepout
			(tracks not_allowed)
			(vias allowed)
			(pads allowed)
			(copperpour not_allowed)
			(footprints allowed)
		)
		(placement
			(enabled no)
			(sheetname "")
		)
		(fill yes
			(thermal_gap 0.5)
			(thermal_bridge_width 0.5)
			(island_removal_mode 0)
		)
		(polygon
			(pts
				(arc
					(start 115.630452 -60.0964)
					(mid 113.852452 -60.0964)
					(end 115.630452 -60.0964)
				)
			)
		)
	)
	(zone
		(layers "In1.Cu" "In3.Cu" "In6.Cu" "In8.Cu")
		(hatch none 0.5)
		(connect_pads
			(clearance 0)
		)
		(min_thickness 0.25)
		(keepout
			(tracks not_allowed)
			(vias allowed)
			(pads allowed)
			(copperpour not_allowed)
			(footprints allowed)
		)
		(placement
			(enabled no)
			(sheetname "")
		)
		(fill yes
			(thermal_gap 0.5)
			(thermal_bridge_width 0.5)
			(island_removal_mode 0)
		)
		(polygon
			(pts
				(arc
					(start 116.392452 -48.8188)
					(mid 114.614452 -48.8188)
					(end 116.392452 -48.8188)
				)
			)
		)
	)
	(zone
		(layers "In1.Cu" "In3.Cu" "In6.Cu" "In8.Cu")
		(hatch none 0.5)
		(connect_pads
			(clearance 0)
		)
		(min_thickness 0.25)
		(keepout
			(tracks not_allowed)
			(vias allowed)
			(pads allowed)
			(copperpour not_allowed)
			(footprints allowed)
		)
		(placement
			(enabled no)
			(sheetname "")
		)
		(fill yes
			(thermal_gap 0.5)
			(thermal_bridge_width 0.5)
			(island_removal_mode 0)
		)
		(polygon
			(pts
				(arc
					(start 392.412982 -156.830014)
					(mid 389.986774 -156.830014)
					(end 392.412982 -156.830014)
				)
			)
		)
	)
	(zone
		(layers "In1.Cu" "In3.Cu" "In6.Cu" "In8.Cu")
		(hatch none 0.5)
		(connect_pads
			(clearance 0)
		)
		(min_thickness 0.25)
		(keepout
			(tracks not_allowed)
			(vias allowed)
			(pads allowed)
			(copperpour not_allowed)
			(footprints allowed)
		)
		(placement
			(enabled no)
			(sheetname "")
		)
		(fill yes
			(thermal_gap 0.5)
			(thermal_bridge_width 0.5)
			(island_removal_mode 0)
		)
		(polygon
			(pts
				(arc
					(start 116.392452 -70.612)
					(mid 114.614452 -70.612)
					(end 116.392452 -70.612)
				)
			)
		)
	)
	(zone
		(layers "In1.Cu" "In3.Cu" "In6.Cu" "In8.Cu")
		(hatch none 0.5)
		(connect_pads
			(clearance 0)
		)
		(min_thickness 0.25)
		(keepout
			(tracks not_allowed)
			(vias allowed)
			(pads allowed)
			(copperpour not_allowed)
			(footprints allowed)
		)
		(placement
			(enabled no)
			(sheetname "")
		)
		(fill yes
			(thermal_gap 0.5)
			(thermal_bridge_width 0.5)
			(island_removal_mode 0)
		)
		(polygon
			(pts
				(arc
					(start 85.852 -4.572)
					(mid 84.074 -4.572)
					(end 85.852 -4.572)
				)
			)
		)
	)
	(zone
		(layers "In1.Cu" "In3.Cu" "In6.Cu" "In8.Cu")
		(hatch none 0.5)
		(connect_pads
			(clearance 0)
		)
		(min_thickness 0.25)
		(keepout
			(tracks not_allowed)
			(vias allowed)
			(pads allowed)
			(copperpour not_allowed)
			(footprints allowed)
		)
		(placement
			(enabled no)
			(sheetname "")
		)
		(fill yes
			(thermal_gap 0.5)
			(thermal_bridge_width 0.5)
			(island_removal_mode 0)
		)
		(polygon
			(pts
				(arc
					(start 379.095508 -91.559888)
					(mid 377.062492 -91.559888)
					(end 379.095508 -91.559888)
				)
			)
		)
	)
	(zone
		(layers "In1.Cu" "In3.Cu" "In6.Cu" "In8.Cu")
		(hatch none 0.5)
		(connect_pads
			(clearance 0)
		)
		(min_thickness 0.25)
		(keepout
			(tracks not_allowed)
			(vias allowed)
			(pads allowed)
			(copperpour not_allowed)
			(footprints allowed)
		)
		(placement
			(enabled no)
			(sheetname "")
		)
		(fill yes
			(thermal_gap 0.5)
			(thermal_bridge_width 0.5)
			(island_removal_mode 0)
		)
		(polygon
			(pts
				(arc
					(start 355.78542 -4.591304)
					(mid 354.00742 -4.591304)
					(end 355.78542 -4.591304)
				)
			)
		)
	)
	(zone
		(layers "In1.Cu" "In3.Cu" "In6.Cu" "In8.Cu")
		(hatch none 0.5)
		(connect_pads
			(clearance 0)
		)
		(min_thickness 0.25)
		(keepout
			(tracks not_allowed)
			(vias allowed)
			(pads allowed)
			(copperpour not_allowed)
			(footprints allowed)
		)
		(placement
			(enabled no)
			(sheetname "")
		)
		(fill yes
			(thermal_gap 0.5)
			(thermal_bridge_width 0.5)
			(island_removal_mode 0)
		)
		(polygon
			(pts
				(arc
					(start 63.44539 -119.38)
					(mid 60.39739 -119.38)
					(end 63.44539 -119.38)
				)
			)
		)
	)
	(zone
		(layers "In1.Cu" "In3.Cu" "In6.Cu" "In8.Cu")
		(hatch none 0.5)
		(connect_pads
			(clearance 0)
		)
		(min_thickness 0.25)
		(keepout
			(tracks not_allowed)
			(vias allowed)
			(pads allowed)
			(copperpour not_allowed)
			(footprints allowed)
		)
		(placement
			(enabled no)
			(sheetname "")
		)
		(fill yes
			(thermal_gap 0.5)
			(thermal_bridge_width 0.5)
			(island_removal_mode 0)
		)
		(polygon
			(pts
				(arc
					(start 76.213208 -160.830006)
					(mid 73.787 -160.830006)
					(end 76.213208 -160.830006)
				)
			)
		)
	)
	(zone
		(layers "In1.Cu" "In3.Cu" "In6.Cu" "In8.Cu")
		(hatch none 0.5)
		(connect_pads
			(clearance 0)
		)
		(min_thickness 0.25)
		(keepout
			(tracks not_allowed)
			(vias allowed)
			(pads allowed)
			(copperpour not_allowed)
			(footprints allowed)
		)
		(placement
			(enabled no)
			(sheetname "")
		)
		(fill yes
			(thermal_gap 0.5)
			(thermal_bridge_width 0.5)
			(island_removal_mode 0)
		)
		(polygon
			(pts
				(arc
					(start 113.344452 -59.3344)
					(mid 111.566452 -59.3344)
					(end 113.344452 -59.3344)
				)
			)
		)
	)
	(zone
		(layers "In1.Cu" "In3.Cu" "In6.Cu" "In8.Cu")
		(hatch none 0.5)
		(connect_pads
			(clearance 0)
		)
		(min_thickness 0.25)
		(keepout
			(tracks not_allowed)
			(vias allowed)
			(pads allowed)
			(copperpour not_allowed)
			(footprints allowed)
		)
		(placement
			(enabled no)
			(sheetname "")
		)
		(fill yes
			(thermal_gap 0.5)
			(thermal_bridge_width 0.5)
			(island_removal_mode 0)
		)
		(polygon
			(pts
				(arc
					(start 114.106452 -72.898)
					(mid 112.328452 -72.898)
					(end 114.106452 -72.898)
				)
			)
		)
	)
	(zone
		(layers "In1.Cu" "In3.Cu" "In6.Cu" "In8.Cu")
		(hatch none 0.5)
		(connect_pads
			(clearance 0)
		)
		(min_thickness 0.25)
		(keepout
			(tracks not_allowed)
			(vias allowed)
			(pads allowed)
			(copperpour not_allowed)
			(footprints allowed)
		)
		(placement
			(enabled no)
			(sheetname "")
		)
		(fill yes
			(thermal_gap 0.5)
			(thermal_bridge_width 0.5)
			(island_removal_mode 0)
		)
		(polygon
			(pts
				(arc
					(start 114.106452 -48.0568)
					(mid 112.328452 -48.0568)
					(end 114.106452 -48.0568)
				)
			)
		)
	)
	(zone
		(layers "In1.Cu" "In3.Cu" "In6.Cu" "In8.Cu")
		(hatch none 0.5)
		(connect_pads
			(clearance 0)
		)
		(min_thickness 0.25)
		(keepout
			(tracks not_allowed)
			(vias allowed)
			(pads allowed)
			(copperpour not_allowed)
			(footprints allowed)
		)
		(placement
			(enabled no)
			(sheetname "")
		)
		(fill yes
			(thermal_gap 0.5)
			(thermal_bridge_width 0.5)
			(island_removal_mode 0)
		)
		(polygon
			(pts
				(arc
					(start 114.106452 -72.136)
					(mid 112.328452 -72.136)
					(end 114.106452 -72.136)
				)
			)
		)
	)
	(zone
		(layers "In1.Cu" "In3.Cu" "In6.Cu" "In8.Cu")
		(hatch none 0.5)
		(connect_pads
			(clearance 0)
		)
		(min_thickness 0.25)
		(keepout
			(tracks not_allowed)
			(vias allowed)
			(pads allowed)
			(copperpour not_allowed)
			(footprints allowed)
		)
		(placement
			(enabled no)
			(sheetname "")
		)
		(fill yes
			(thermal_gap 0.5)
			(thermal_bridge_width 0.5)
			(island_removal_mode 0)
		)
		(polygon
			(pts
				(arc
					(start 334.5688 -32.0802)
					(mid 332.7908 -32.0802)
					(end 334.5688 -32.0802)
				)
			)
		)
	)
	(zone
		(layers "In1.Cu" "In3.Cu" "In6.Cu" "In8.Cu")
		(hatch none 0.5)
		(connect_pads
			(clearance 0)
		)
		(min_thickness 0.25)
		(keepout
			(tracks not_allowed)
			(vias allowed)
			(pads allowed)
			(copperpour not_allowed)
			(footprints allowed)
		)
		(placement
			(enabled no)
			(sheetname "")
		)
		(fill yes
			(thermal_gap 0.5)
			(thermal_bridge_width 0.5)
			(island_removal_mode 0)
		)
		(polygon
			(pts
				(arc
					(start 84.328 -5.334)
					(mid 82.55 -5.334)
					(end 84.328 -5.334)
				)
			)
		)
	)
	(zone
		(layers "In1.Cu" "In3.Cu" "In6.Cu" "In8.Cu")
		(hatch none 0.5)
		(connect_pads
			(clearance 0)
		)
		(min_thickness 0.25)
		(keepout
			(tracks not_allowed)
			(vias allowed)
			(pads allowed)
			(copperpour not_allowed)
			(footprints allowed)
		)
		(placement
			(enabled no)
			(sheetname "")
		)
		(fill yes
			(thermal_gap 0.5)
			(thermal_bridge_width 0.5)
			(island_removal_mode 0)
		)
		(polygon
			(pts
				(arc
					(start 64.933068 -2.590038)
					(mid 62.50686 -2.590038)
					(end 64.933068 -2.590038)
				)
			)
		)
	)
	(zone
		(layers "In1.Cu" "In3.Cu" "In6.Cu" "In8.Cu")
		(hatch none 0.5)
		(connect_pads
			(clearance 0)
		)
		(min_thickness 0.25)
		(keepout
			(tracks not_allowed)
			(vias allowed)
			(pads allowed)
			(copperpour not_allowed)
			(footprints allowed)
		)
		(placement
			(enabled no)
			(sheetname "")
		)
		(fill yes
			(thermal_gap 0.5)
			(thermal_bridge_width 0.5)
			(island_removal_mode 0)
		)
		(polygon
			(pts
				(arc
					(start 50.013108 -160.830006)
					(mid 47.5869 -160.830006)
					(end 50.013108 -160.830006)
				)
			)
		)
	)
	(zone
		(layers "In1.Cu" "In3.Cu" "In6.Cu" "In8.Cu")
		(hatch none 0.5)
		(connect_pads
			(clearance 0)
		)
		(min_thickness 0.25)
		(keepout
			(tracks not_allowed)
			(vias allowed)
			(pads allowed)
			(copperpour not_allowed)
			(footprints allowed)
		)
		(placement
			(enabled no)
			(sheetname "")
		)
		(fill yes
			(thermal_gap 0.5)
			(thermal_bridge_width 0.5)
			(island_removal_mode 0)
		)
		(polygon
			(pts
				(arc
					(start 378.213112 -158.83001)
					(mid 375.786904 -158.83001)
					(end 378.213112 -158.83001)
				)
			)
		)
	)
	(zone
		(layers "In1.Cu" "In3.Cu" "In6.Cu" "In8.Cu")
		(hatch none 0.5)
		(connect_pads
			(clearance 0)
		)
		(min_thickness 0.25)
		(keepout
			(tracks not_allowed)
			(vias allowed)
			(pads allowed)
			(copperpour not_allowed)
			(footprints allowed)
		)
		(placement
			(enabled no)
			(sheetname "")
		)
		(fill yes
			(thermal_gap 0.5)
			(thermal_bridge_width 0.5)
			(island_removal_mode 0)
		)
		(polygon
			(pts
				(arc
					(start 379.095508 -132.199888)
					(mid 377.062492 -132.199888)
					(end 379.095508 -132.199888)
				)
			)
		)
	)
	(zone
		(layers "In1.Cu" "In3.Cu" "In6.Cu" "In8.Cu")
		(hatch none 0.5)
		(connect_pads
			(clearance 0)
		)
		(min_thickness 0.25)
		(keepout
			(tracks not_allowed)
			(vias allowed)
			(pads allowed)
			(copperpour not_allowed)
			(footprints allowed)
		)
		(placement
			(enabled no)
			(sheetname "")
		)
		(fill yes
			(thermal_gap 0.5)
			(thermal_bridge_width 0.5)
			(island_removal_mode 0)
		)
		(polygon
			(pts
				(arc
					(start 333.0448 -32.8422)
					(mid 331.2668 -32.8422)
					(end 333.0448 -32.8422)
				)
			)
		)
	)
	(zone
		(layers "In1.Cu" "In3.Cu" "In6.Cu" "In8.Cu")
		(hatch none 0.5)
		(connect_pads
			(clearance 0)
		)
		(min_thickness 0.25)
		(keepout
			(tracks not_allowed)
			(vias allowed)
			(pads allowed)
			(copperpour not_allowed)
			(footprints allowed)
		)
		(placement
			(enabled no)
			(sheetname "")
		)
		(fill yes
			(thermal_gap 0.5)
			(thermal_bridge_width 0.5)
			(island_removal_mode 0)
		)
		(polygon
			(pts
				(arc
					(start 116.392452 -39.0652)
					(mid 114.614452 -39.0652)
					(end 116.392452 -39.0652)
				)
			)
		)
	)
	(zone
		(layers "In1.Cu" "In3.Cu" "In6.Cu" "In8.Cu")
		(hatch none 0.5)
		(connect_pads
			(clearance 0)
		)
		(min_thickness 0.25)
		(keepout
			(tracks not_allowed)
			(vias allowed)
			(pads allowed)
			(copperpour not_allowed)
			(footprints allowed)
		)
		(placement
			(enabled no)
			(sheetname "")
		)
		(fill yes
			(thermal_gap 0.5)
			(thermal_bridge_width 0.5)
			(island_removal_mode 0)
		)
		(polygon
			(pts
				(arc
					(start 115.630452 -48.0568)
					(mid 113.852452 -48.0568)
					(end 115.630452 -48.0568)
				)
			)
		)
	)
	(zone
		(layers "In1.Cu" "In3.Cu" "In6.Cu" "In8.Cu")
		(hatch none 0.5)
		(connect_pads
			(clearance 0)
		)
		(min_thickness 0.25)
		(keepout
			(tracks not_allowed)
			(vias allowed)
			(pads allowed)
			(copperpour not_allowed)
			(footprints allowed)
		)
		(placement
			(enabled no)
			(sheetname "")
		)
		(fill yes
			(thermal_gap 0.5)
			(thermal_bridge_width 0.5)
			(island_removal_mode 0)
		)
		(polygon
			(pts
				(arc
					(start 335.3308 -53.8734)
					(mid 333.5528 -53.8734)
					(end 335.3308 -53.8734)
				)
			)
		)
	)
	(zone
		(layers "In1.Cu" "In3.Cu" "In6.Cu" "In8.Cu")
		(hatch none 0.5)
		(connect_pads
			(clearance 0)
		)
		(min_thickness 0.25)
		(keepout
			(tracks not_allowed)
			(vias allowed)
			(pads allowed)
			(copperpour not_allowed)
			(footprints allowed)
		)
		(placement
			(enabled no)
			(sheetname "")
		)
		(fill yes
			(thermal_gap 0.5)
			(thermal_bridge_width 0.5)
			(island_removal_mode 0)
		)
		(polygon
			(pts
				(arc
					(start 62.937898 -132.199888)
					(mid 60.904882 -132.199888)
					(end 62.937898 -132.199888)
				)
			)
		)
	)
	(zone
		(layers "In1.Cu" "In3.Cu" "In6.Cu" "In8.Cu")
		(hatch none 0.5)
		(connect_pads
			(clearance 0)
		)
		(min_thickness 0.25)
		(keepout
			(tracks not_allowed)
			(vias allowed)
			(pads allowed)
			(copperpour not_allowed)
			(footprints allowed)
		)
		(placement
			(enabled no)
			(sheetname "")
		)
		(fill yes
			(thermal_gap 0.5)
			(thermal_bridge_width 0.5)
			(island_removal_mode 0)
		)
		(polygon
			(pts
				(arc
					(start 113.344452 -62.3824)
					(mid 111.566452 -62.3824)
					(end 113.344452 -62.3824)
				)
			)
		)
	)
	(zone
		(layers "In1.Cu" "In3.Cu" "In6.Cu" "In8.Cu")
		(hatch none 0.5)
		(connect_pads
			(clearance 0)
		)
		(min_thickness 0.25)
		(keepout
			(tracks not_allowed)
			(vias allowed)
			(pads allowed)
			(copperpour not_allowed)
			(footprints allowed)
		)
		(placement
			(enabled no)
			(sheetname "")
		)
		(fill yes
			(thermal_gap 0.5)
			(thermal_bridge_width 0.5)
			(island_removal_mode 0)
		)
		(polygon
			(pts
				(arc
					(start 372.213124 -160.830006)
					(mid 369.786916 -160.830006)
					(end 372.213124 -160.830006)
				)
			)
		)
	)
	(zone
		(layers "In1.Cu" "In3.Cu" "In6.Cu" "In8.Cu")
		(hatch none 0.5)
		(connect_pads
			(clearance 0)
		)
		(min_thickness 0.25)
		(keepout
			(tracks not_allowed)
			(vias allowed)
			(pads allowed)
			(copperpour not_allowed)
			(footprints allowed)
		)
		(placement
			(enabled no)
			(sheetname "")
		)
		(fill yes
			(thermal_gap 0.5)
			(thermal_bridge_width 0.5)
			(island_removal_mode 0)
		)
		(polygon
			(pts
				(arc
					(start 114.106452 -39.8272)
					(mid 112.328452 -39.8272)
					(end 114.106452 -39.8272)
				)
			)
		)
	)
	(zone
		(layers "In1.Cu" "In3.Cu" "In6.Cu" "In8.Cu")
		(hatch none 0.5)
		(connect_pads
			(clearance 0)
		)
		(min_thickness 0.25)
		(keepout
			(tracks not_allowed)
			(vias allowed)
			(pads allowed)
			(copperpour not_allowed)
			(footprints allowed)
		)
		(placement
			(enabled no)
			(sheetname "")
		)
		(fill yes
			(thermal_gap 0.5)
			(thermal_bridge_width 0.5)
			(island_removal_mode 0)
		)
		(polygon
			(pts
				(arc
					(start 356.54742 -3.829304)
					(mid 354.76942 -3.829304)
					(end 356.54742 -3.829304)
				)
			)
		)
	)
	(zone
		(layers "In1.Cu" "In3.Cu" "In6.Cu" "In8.Cu")
		(hatch none 0.5)
		(connect_pads
			(clearance 0)
		)
		(min_thickness 0.25)
		(keepout
			(tracks not_allowed)
			(vias allowed)
			(pads allowed)
			(copperpour not_allowed)
			(footprints allowed)
		)
		(placement
			(enabled no)
			(sheetname "")
		)
		(fill yes
			(thermal_gap 0.5)
			(thermal_bridge_width 0.5)
			(island_removal_mode 0)
		)
		(polygon
			(pts
				(arc
					(start 36.088066 -152.830022)
					(mid 33.661858 -152.830022)
					(end 36.088066 -152.830022)
				)
			)
		)
	)
	(zone
		(layers "In1.Cu" "In3.Cu" "In6.Cu" "In8.Cu")
		(hatch none 0.5)
		(connect_pads
			(clearance 0)
		)
		(min_thickness 0.25)
		(keepout
			(tracks not_allowed)
			(vias allowed)
			(pads allowed)
			(copperpour not_allowed)
			(footprints allowed)
		)
		(placement
			(enabled no)
			(sheetname "")
		)
		(fill yes
			(thermal_gap 0.5)
			(thermal_bridge_width 0.5)
			(island_removal_mode 0)
		)
		(polygon
			(pts
				(arc
					(start 116.392452 -61.6204)
					(mid 114.614452 -61.6204)
					(end 116.392452 -61.6204)
				)
			)
		)
	)
	(zone
		(layers "In1.Cu" "In3.Cu" "In6.Cu" "In8.Cu")
		(hatch none 0.5)
		(connect_pads
			(clearance 0)
		)
		(min_thickness 0.25)
		(keepout
			(tracks not_allowed)
			(vias allowed)
			(pads allowed)
			(copperpour not_allowed)
			(footprints allowed)
		)
		(placement
			(enabled no)
			(sheetname "")
		)
		(fill yes
			(thermal_gap 0.5)
			(thermal_bridge_width 0.5)
			(island_removal_mode 0)
		)
		(polygon
			(pts
				(arc
					(start 358.07142 -4.591304)
					(mid 356.29342 -4.591304)
					(end 358.07142 -4.591304)
				)
			)
		)
	)
	(zone
		(layers "In1.Cu" "In3.Cu" "In6.Cu" "In8.Cu")
		(hatch none 0.5)
		(connect_pads
			(clearance 0)
		)
		(min_thickness 0.25)
		(keepout
			(tracks not_allowed)
			(vias allowed)
			(pads allowed)
			(copperpour not_allowed)
			(footprints allowed)
		)
		(placement
			(enabled no)
			(sheetname "")
		)
		(fill yes
			(thermal_gap 0.5)
			(thermal_bridge_width 0.5)
			(island_removal_mode 0)
		)
		(polygon
			(pts
				(arc
					(start 398.653508 -111.879888)
					(mid 396.620492 -111.879888)
					(end 398.653508 -111.879888)
				)
			)
		)
	)
	(zone
		(layers "In1.Cu" "In3.Cu" "In6.Cu" "In8.Cu")
		(hatch none 0.5)
		(connect_pads
			(clearance 0)
		)
		(min_thickness 0.25)
		(keepout
			(tracks not_allowed)
			(vias allowed)
			(pads allowed)
			(copperpour not_allowed)
			(footprints allowed)
		)
		(placement
			(enabled no)
			(sheetname "")
		)
		(fill yes
			(thermal_gap 0.5)
			(thermal_bridge_width 0.5)
			(island_removal_mode 0)
		)
		(polygon
			(pts
				(arc
					(start 62.937898 -111.879888)
					(mid 60.904882 -111.879888)
					(end 62.937898 -111.879888)
				)
			)
		)
	)
	(zone
		(layers "In1.Cu" "In3.Cu" "In6.Cu" "In8.Cu")
		(hatch none 0.5)
		(connect_pads
			(clearance 0)
		)
		(min_thickness 0.25)
		(keepout
			(tracks not_allowed)
			(vias allowed)
			(pads allowed)
			(copperpour not_allowed)
			(footprints allowed)
		)
		(placement
			(enabled no)
			(sheetname "")
		)
		(fill yes
			(thermal_gap 0.5)
			(thermal_bridge_width 0.5)
			(island_removal_mode 0)
		)
		(polygon
			(pts
				(arc
					(start 334.5688 -55.3974)
					(mid 332.7908 -55.3974)
					(end 334.5688 -55.3974)
				)
			)
		)
	)
	(zone
		(layers "In1.Cu" "In3.Cu" "In6.Cu" "In8.Cu")
		(hatch none 0.5)
		(connect_pads
			(clearance 0)
		)
		(min_thickness 0.25)
		(keepout
			(tracks not_allowed)
			(vias allowed)
			(pads allowed)
			(copperpour not_allowed)
			(footprints allowed)
		)
		(placement
			(enabled no)
			(sheetname "")
		)
		(fill yes
			(thermal_gap 0.5)
			(thermal_bridge_width 0.5)
			(island_removal_mode 0)
		)
		(polygon
			(pts
				(arc
					(start 399.161 -58.42)
					(mid 396.113 -58.42)
					(end 399.161 -58.42)
				)
			)
		)
	)
	(zone
		(layers "In1.Cu" "In3.Cu" "In6.Cu" "In8.Cu")
		(hatch none 0.5)
		(connect_pads
			(clearance 0)
		)
		(min_thickness 0.25)
		(keepout
			(tracks not_allowed)
			(vias allowed)
			(pads allowed)
			(copperpour not_allowed)
			(footprints allowed)
		)
		(placement
			(enabled no)
			(sheetname "")
		)
		(fill yes
			(thermal_gap 0.5)
			(thermal_bridge_width 0.5)
			(island_removal_mode 0)
		)
		(polygon
			(pts
				(arc
					(start 333.8068 -55.3974)
					(mid 332.0288 -55.3974)
					(end 333.8068 -55.3974)
				)
			)
		)
	)
	(zone
		(layers "In1.Cu" "In3.Cu" "In6.Cu" "In8.Cu")
		(hatch none 0.5)
		(connect_pads
			(clearance 0)
		)
		(min_thickness 0.25)
		(keepout
			(tracks not_allowed)
			(vias allowed)
			(pads allowed)
			(copperpour not_allowed)
			(footprints allowed)
		)
		(placement
			(enabled no)
			(sheetname "")
		)
		(fill yes
			(thermal_gap 0.5)
			(thermal_bridge_width 0.5)
			(island_removal_mode 0)
		)
		(polygon
			(pts
				(arc
					(start 38.088062 -154.830018)
					(mid 35.661854 -154.830018)
					(end 38.088062 -154.830018)
				)
			)
		)
	)
	(zone
		(layers "In1.Cu" "In3.Cu" "In6.Cu" "In8.Cu")
		(hatch none 0.5)
		(connect_pads
			(clearance 0)
		)
		(min_thickness 0.25)
		(keepout
			(tracks not_allowed)
			(vias allowed)
			(pads allowed)
			(copperpour not_allowed)
			(footprints allowed)
		)
		(placement
			(enabled no)
			(sheetname "")
		)
		(fill yes
			(thermal_gap 0.5)
			(thermal_bridge_width 0.5)
			(island_removal_mode 0)
		)
		(polygon
			(pts
				(arc
					(start 333.8068 -44.1198)
					(mid 332.0288 -44.1198)
					(end 333.8068 -44.1198)
				)
			)
		)
	)
	(zone
		(layers "In1.Cu" "In3.Cu" "In6.Cu" "In8.Cu")
		(hatch none 0.5)
		(connect_pads
			(clearance 0)
		)
		(min_thickness 0.25)
		(keepout
			(tracks not_allowed)
			(vias allowed)
			(pads allowed)
			(copperpour not_allowed)
			(footprints allowed)
		)
		(placement
			(enabled no)
			(sheetname "")
		)
		(fill yes
			(thermal_gap 0.5)
			(thermal_bridge_width 0.5)
			(island_removal_mode 0)
		)
		(polygon
			(pts
				(arc
					(start 116.392452 -50.3428)
					(mid 114.614452 -50.3428)
					(end 116.392452 -50.3428)
				)
			)
		)
	)
	(zone
		(layers "In1.Cu" "In3.Cu" "In6.Cu" "In8.Cu")
		(hatch none 0.5)
		(connect_pads
			(clearance 0)
		)
		(min_thickness 0.25)
		(keepout
			(tracks not_allowed)
			(vias allowed)
			(pads allowed)
			(copperpour not_allowed)
			(footprints allowed)
		)
		(placement
			(enabled no)
			(sheetname "")
		)
		(fill yes
			(thermal_gap 0.5)
			(thermal_bridge_width 0.5)
			(island_removal_mode 0)
		)
		(polygon
			(pts
				(arc
					(start 63.44539 -99.06)
					(mid 60.39739 -99.06)
					(end 63.44539 -99.06)
				)
			)
		)
	)
	(zone
		(layers "In1.Cu" "In3.Cu" "In6.Cu" "In8.Cu")
		(hatch none 0.5)
		(connect_pads
			(clearance 0)
		)
		(min_thickness 0.25)
		(keepout
			(tracks not_allowed)
			(vias allowed)
			(pads allowed)
			(copperpour not_allowed)
			(footprints allowed)
		)
		(placement
			(enabled no)
			(sheetname "")
		)
		(fill yes
			(thermal_gap 0.5)
			(thermal_bridge_width 0.5)
			(island_removal_mode 0)
		)
		(polygon
			(pts
				(arc
					(start 335.3308 -76.4286)
					(mid 333.5528 -76.4286)
					(end 335.3308 -76.4286)
				)
			)
		)
	)
	(zone
		(layers "In1.Cu" "In3.Cu" "In6.Cu" "In8.Cu")
		(hatch none 0.5)
		(connect_pads
			(clearance 0)
		)
		(min_thickness 0.25)
		(keepout
			(tracks not_allowed)
			(vias allowed)
			(pads allowed)
			(copperpour not_allowed)
			(footprints allowed)
		)
		(placement
			(enabled no)
			(sheetname "")
		)
		(fill yes
			(thermal_gap 0.5)
			(thermal_bridge_width 0.5)
			(island_removal_mode 0)
		)
		(polygon
			(pts
				(arc
					(start 85.09 -3.81)
					(mid 83.312 -3.81)
					(end 85.09 -3.81)
				)
			)
		)
	)
	(zone
		(layers "In1.Cu" "In3.Cu" "In6.Cu" "In8.Cu")
		(hatch none 0.5)
		(connect_pads
			(clearance 0)
		)
		(min_thickness 0.25)
		(keepout
			(tracks not_allowed)
			(vias allowed)
			(pads allowed)
			(copperpour not_allowed)
			(footprints allowed)
		)
		(placement
			(enabled no)
			(sheetname "")
		)
		(fill yes
			(thermal_gap 0.5)
			(thermal_bridge_width 0.5)
			(island_removal_mode 0)
		)
		(polygon
			(pts
				(arc
					(start 113.344452 -61.6204)
					(mid 111.566452 -61.6204)
					(end 113.344452 -61.6204)
				)
			)
		)
	)
	(zone
		(layers "In1.Cu" "In3.Cu" "In6.Cu" "In8.Cu")
		(hatch none 0.5)
		(connect_pads
			(clearance 0)
		)
		(min_thickness 0.25)
		(keepout
			(tracks not_allowed)
			(vias allowed)
			(pads allowed)
			(copperpour not_allowed)
			(footprints allowed)
		)
		(placement
			(enabled no)
			(sheetname "")
		)
		(fill yes
			(thermal_gap 0.5)
			(thermal_bridge_width 0.5)
			(island_removal_mode 0)
		)
		(polygon
			(pts
				(arc
					(start 333.0448 -56.1594)
					(mid 331.2668 -56.1594)
					(end 333.0448 -56.1594)
				)
			)
		)
	)
	(zone
		(layers "In1.Cu" "In3.Cu" "In6.Cu" "In8.Cu")
		(hatch none 0.5)
		(connect_pads
			(clearance 0)
		)
		(min_thickness 0.25)
		(keepout
			(tracks not_allowed)
			(vias allowed)
			(pads allowed)
			(copperpour not_allowed)
			(footprints allowed)
		)
		(placement
			(enabled no)
			(sheetname "")
		)
		(fill yes
			(thermal_gap 0.5)
			(thermal_bridge_width 0.5)
			(island_removal_mode 0)
		)
		(polygon
			(pts
				(arc
					(start 115.630452 -51.1048)
					(mid 113.852452 -51.1048)
					(end 115.630452 -51.1048)
				)
			)
		)
	)
	(zone
		(layers "In1.Cu" "In3.Cu" "In6.Cu" "In8.Cu")
		(hatch none 0.5)
		(connect_pads
			(clearance 0)
		)
		(min_thickness 0.25)
		(keepout
			(tracks not_allowed)
			(vias allowed)
			(pads allowed)
			(copperpour not_allowed)
			(footprints allowed)
		)
		(placement
			(enabled no)
			(sheetname "")
		)
		(fill yes
			(thermal_gap 0.5)
			(thermal_bridge_width 0.5)
			(island_removal_mode 0)
		)
		(polygon
			(pts
				(arc
					(start 367.333022 -2.590038)
					(mid 364.906814 -2.590038)
					(end 367.333022 -2.590038)
				)
			)
		)
	)
	(zone
		(layers "In1.Cu" "In3.Cu" "In6.Cu" "In8.Cu")
		(hatch none 0.5)
		(connect_pads
			(clearance 0)
		)
		(min_thickness 0.25)
		(keepout
			(tracks not_allowed)
			(vias allowed)
			(pads allowed)
			(copperpour not_allowed)
			(footprints allowed)
		)
		(placement
			(enabled no)
			(sheetname "")
		)
		(fill yes
			(thermal_gap 0.5)
			(thermal_bridge_width 0.5)
			(island_removal_mode 0)
		)
		(polygon
			(pts
				(arc
					(start 66.213228 -158.83001)
					(mid 63.78702 -158.83001)
					(end 66.213228 -158.83001)
				)
			)
		)
	)
	(zone
		(layers "In1.Cu" "In3.Cu" "In6.Cu" "In8.Cu")
		(hatch none 0.5)
		(connect_pads
			(clearance 0)
		)
		(min_thickness 0.25)
		(keepout
			(tracks not_allowed)
			(vias allowed)
			(pads allowed)
			(copperpour not_allowed)
			(footprints allowed)
		)
		(placement
			(enabled no)
			(sheetname "")
		)
		(fill yes
			(thermal_gap 0.5)
			(thermal_bridge_width 0.5)
			(island_removal_mode 0)
		)
		(polygon
			(pts
				(arc
					(start 334.5688 -66.675)
					(mid 332.7908 -66.675)
					(end 334.5688 -66.675)
				)
			)
		)
	)
	(zone
		(layers "In1.Cu" "In3.Cu" "In6.Cu" "In8.Cu")
		(hatch none 0.5)
		(connect_pads
			(clearance 0)
		)
		(min_thickness 0.25)
		(keepout
			(tracks not_allowed)
			(vias allowed)
			(pads allowed)
			(copperpour not_allowed)
			(footprints allowed)
		)
		(placement
			(enabled no)
			(sheetname "")
		)
		(fill yes
			(thermal_gap 0.5)
			(thermal_bridge_width 0.5)
			(island_removal_mode 0)
		)
		(polygon
			(pts
				(arc
					(start 113.344452 -27.0256)
					(mid 111.566452 -27.0256)
					(end 113.344452 -27.0256)
				)
			)
		)
	)
	(zone
		(layers "In1.Cu" "In3.Cu" "In6.Cu" "In8.Cu")
		(hatch none 0.5)
		(connect_pads
			(clearance 0)
		)
		(min_thickness 0.25)
		(keepout
			(tracks not_allowed)
			(vias allowed)
			(pads allowed)
			(copperpour not_allowed)
			(footprints allowed)
		)
		(placement
			(enabled no)
			(sheetname "")
		)
		(fill yes
			(thermal_gap 0.5)
			(thermal_bridge_width 0.5)
			(island_removal_mode 0)
		)
		(polygon
			(pts
				(arc
					(start 72.213216 -158.83001)
					(mid 69.787008 -158.83001)
					(end 72.213216 -158.83001)
				)
			)
		)
	)
	(zone
		(layers "In1.Cu" "In3.Cu" "In6.Cu" "In8.Cu")
		(hatch none 0.5)
		(connect_pads
			(clearance 0)
		)
		(min_thickness 0.25)
		(keepout
			(tracks not_allowed)
			(vias allowed)
			(pads allowed)
			(copperpour not_allowed)
			(footprints allowed)
		)
		(placement
			(enabled no)
			(sheetname "")
		)
		(fill yes
			(thermal_gap 0.5)
			(thermal_bridge_width 0.5)
			(island_removal_mode 0)
		)
		(polygon
			(pts
				(arc
					(start 333.8068 -77.9526)
					(mid 332.0288 -77.9526)
					(end 333.8068 -77.9526)
				)
			)
		)
	)
	(zone
		(layers "In1.Cu" "In3.Cu" "In6.Cu" "In8.Cu")
		(hatch none 0.5)
		(connect_pads
			(clearance 0)
		)
		(min_thickness 0.25)
		(keepout
			(tracks not_allowed)
			(vias allowed)
			(pads allowed)
			(copperpour not_allowed)
			(footprints allowed)
		)
		(placement
			(enabled no)
			(sheetname "")
		)
		(fill yes
			(thermal_gap 0.5)
			(thermal_bridge_width 0.5)
			(island_removal_mode 0)
		)
		(polygon
			(pts
				(arc
					(start 333.8068 -22.3266)
					(mid 332.0288 -22.3266)
					(end 333.8068 -22.3266)
				)
			)
		)
	)
	(zone
		(layers "In1.Cu" "In3.Cu" "In6.Cu" "In8.Cu")
		(hatch none 0.5)
		(connect_pads
			(clearance 0)
		)
		(min_thickness 0.25)
		(keepout
			(tracks not_allowed)
			(vias allowed)
			(pads allowed)
			(copperpour not_allowed)
			(footprints allowed)
		)
		(placement
			(enabled no)
			(sheetname "")
		)
		(fill yes
			(thermal_gap 0.5)
			(thermal_bridge_width 0.5)
			(island_removal_mode 0)
		)
		(polygon
			(pts
				(arc
					(start 333.0448 -44.1198)
					(mid 331.2668 -44.1198)
					(end 333.0448 -44.1198)
				)
			)
		)
	)
	(zone
		(layers "In1.Cu" "In3.Cu" "In6.Cu" "In8.Cu")
		(hatch none 0.5)
		(connect_pads
			(clearance 0)
		)
		(min_thickness 0.25)
		(keepout
			(tracks not_allowed)
			(vias allowed)
			(pads allowed)
			(copperpour not_allowed)
			(footprints allowed)
		)
		(placement
			(enabled no)
			(sheetname "")
		)
		(fill yes
			(thermal_gap 0.5)
			(thermal_bridge_width 0.5)
			(island_removal_mode 0)
		)
		(polygon
			(pts
				(arc
					(start 114.106452 -50.3428)
					(mid 112.328452 -50.3428)
					(end 114.106452 -50.3428)
				)
			)
		)
	)
	(zone
		(layers "In1.Cu" "In3.Cu" "In6.Cu" "In8.Cu")
		(hatch none 0.5)
		(connect_pads
			(clearance 0)
		)
		(min_thickness 0.25)
		(keepout
			(tracks not_allowed)
			(vias allowed)
			(pads allowed)
			(copperpour not_allowed)
			(footprints allowed)
		)
		(placement
			(enabled no)
			(sheetname "")
		)
		(fill yes
			(thermal_gap 0.5)
			(thermal_bridge_width 0.5)
			(island_removal_mode 0)
		)
		(polygon
			(pts
				(arc
					(start 38.088062 -168.82999)
					(mid 35.661854 -168.82999)
					(end 38.088062 -168.82999)
				)
			)
		)
	)
	(zone
		(layers "In1.Cu" "In3.Cu" "In6.Cu" "In8.Cu")
		(hatch none 0.5)
		(connect_pads
			(clearance 0)
		)
		(min_thickness 0.25)
		(keepout
			(tracks not_allowed)
			(vias allowed)
			(pads allowed)
			(copperpour not_allowed)
			(footprints allowed)
		)
		(placement
			(enabled no)
			(sheetname "")
		)
		(fill yes
			(thermal_gap 0.5)
			(thermal_bridge_width 0.5)
			(island_removal_mode 0)
		)
		(polygon
			(pts
				(arc
					(start 114.868452 -25.5016)
					(mid 113.090452 -25.5016)
					(end 114.868452 -25.5016)
				)
			)
		)
	)
	(zone
		(layers "In1.Cu" "In3.Cu" "In6.Cu" "In8.Cu")
		(hatch none 0.5)
		(connect_pads
			(clearance 0)
		)
		(min_thickness 0.25)
		(keepout
			(tracks not_allowed)
			(vias allowed)
			(pads allowed)
			(copperpour not_allowed)
			(footprints allowed)
		)
		(placement
			(enabled no)
			(sheetname "")
		)
		(fill yes
			(thermal_gap 0.5)
			(thermal_bridge_width 0.5)
			(island_removal_mode 0)
		)
		(polygon
			(pts
				(arc
					(start 392.412982 -158.83001)
					(mid 389.986774 -158.83001)
					(end 392.412982 -158.83001)
				)
			)
		)
	)
	(zone
		(layers "In1.Cu" "In3.Cu" "In6.Cu" "In8.Cu")
		(hatch none 0.5)
		(connect_pads
			(clearance 0)
		)
		(min_thickness 0.25)
		(keepout
			(tracks not_allowed)
			(vias allowed)
			(pads allowed)
			(copperpour not_allowed)
			(footprints allowed)
		)
		(placement
			(enabled no)
			(sheetname "")
		)
		(fill yes
			(thermal_gap 0.5)
			(thermal_bridge_width 0.5)
			(island_removal_mode 0)
		)
		(polygon
			(pts
				(arc
					(start 335.3308 -77.1906)
					(mid 333.5528 -77.1906)
					(end 335.3308 -77.1906)
				)
			)
		)
	)
	(zone
		(layers "In1.Cu" "In3.Cu" "In6.Cu" "In8.Cu")
		(hatch none 0.5)
		(connect_pads
			(clearance 0)
		)
		(min_thickness 0.25)
		(keepout
			(tracks not_allowed)
			(vias allowed)
			(pads allowed)
			(copperpour not_allowed)
			(footprints allowed)
		)
		(placement
			(enabled no)
			(sheetname "")
		)
		(fill yes
			(thermal_gap 0.5)
			(thermal_bridge_width 0.5)
			(island_removal_mode 0)
		)
		(polygon
			(pts
				(arc
					(start 334.5688 -20.0406)
					(mid 332.7908 -20.0406)
					(end 334.5688 -20.0406)
				)
			)
		)
	)
	(zone
		(layers "In1.Cu" "In3.Cu" "In6.Cu" "In8.Cu")
		(hatch none 0.5)
		(connect_pads
			(clearance 0)
		)
		(min_thickness 0.25)
		(keepout
			(tracks not_allowed)
			(vias allowed)
			(pads allowed)
			(copperpour not_allowed)
			(footprints allowed)
		)
		(placement
			(enabled no)
			(sheetname "")
		)
		(fill yes
			(thermal_gap 0.5)
			(thermal_bridge_width 0.5)
			(island_removal_mode 0)
		)
		(polygon
			(pts
				(arc
					(start 335.3308 -32.8422)
					(mid 333.5528 -32.8422)
					(end 335.3308 -32.8422)
				)
			)
		)
	)
	(zone
		(layers "In1.Cu" "In3.Cu" "In6.Cu" "In8.Cu")
		(hatch none 0.5)
		(connect_pads
			(clearance 0)
		)
		(min_thickness 0.25)
		(keepout
			(tracks not_allowed)
			(vias allowed)
			(pads allowed)
			(copperpour not_allowed)
			(footprints allowed)
		)
		(placement
			(enabled no)
			(sheetname "")
		)
		(fill yes
			(thermal_gap 0.5)
			(thermal_bridge_width 0.5)
			(island_removal_mode 0)
		)
		(polygon
			(pts
				(arc
					(start 336.0928 -20.8026)
					(mid 334.3148 -20.8026)
					(end 336.0928 -20.8026)
				)
			)
		)
	)
	(zone
		(layers "In1.Cu" "In3.Cu" "In6.Cu" "In8.Cu")
		(hatch none 0.5)
		(connect_pads
			(clearance 0)
		)
		(min_thickness 0.25)
		(keepout
			(tracks not_allowed)
			(vias allowed)
			(pads allowed)
			(copperpour not_allowed)
			(footprints allowed)
		)
		(placement
			(enabled no)
			(sheetname "")
		)
		(fill yes
			(thermal_gap 0.5)
			(thermal_bridge_width 0.5)
			(island_removal_mode 0)
		)
		(polygon
			(pts
				(arc
					(start 115.630452 -38.3032)
					(mid 113.852452 -38.3032)
					(end 115.630452 -38.3032)
				)
			)
		)
	)
	(zone
		(layers "In1.Cu" "In3.Cu" "In6.Cu" "In8.Cu")
		(hatch none 0.5)
		(connect_pads
			(clearance 0)
		)
		(min_thickness 0.25)
		(keepout
			(tracks not_allowed)
			(vias allowed)
			(pads allowed)
			(copperpour not_allowed)
			(footprints allowed)
		)
		(placement
			(enabled no)
			(sheetname "")
		)
		(fill yes
			(thermal_gap 0.5)
			(thermal_bridge_width 0.5)
			(island_removal_mode 0)
		)
		(polygon
			(pts
				(arc
					(start 399.588228 -164.829998)
					(mid 397.16202 -164.829998)
					(end 399.588228 -164.829998)
				)
			)
		)
	)
	(zone
		(layers "In1.Cu" "In3.Cu" "In6.Cu" "In8.Cu")
		(hatch none 0.5)
		(connect_pads
			(clearance 0)
		)
		(min_thickness 0.25)
		(keepout
			(tracks not_allowed)
			(vias allowed)
			(pads allowed)
			(copperpour not_allowed)
			(footprints allowed)
		)
		(placement
			(enabled no)
			(sheetname "")
		)
		(fill yes
			(thermal_gap 0.5)
			(thermal_bridge_width 0.5)
			(island_removal_mode 0)
		)
		(polygon
			(pts
				(arc
					(start 114.106452 -48.8188)
					(mid 112.328452 -48.8188)
					(end 114.106452 -48.8188)
				)
			)
		)
	)
	(zone
		(layers "In1.Cu" "In3.Cu" "In6.Cu" "In8.Cu")
		(hatch none 0.5)
		(connect_pads
			(clearance 0)
		)
		(min_thickness 0.25)
		(keepout
			(tracks not_allowed)
			(vias allowed)
			(pads allowed)
			(copperpour not_allowed)
			(footprints allowed)
		)
		(placement
			(enabled no)
			(sheetname "")
		)
		(fill yes
			(thermal_gap 0.5)
			(thermal_bridge_width 0.5)
			(island_removal_mode 0)
		)
		(polygon
			(pts
				(arc
					(start 63.44539 -58.42)
					(mid 60.39739 -58.42)
					(end 63.44539 -58.42)
				)
			)
		)
	)
	(zone
		(layers "In1.Cu" "In3.Cu" "In6.Cu" "In8.Cu")
		(hatch none 0.5)
		(connect_pads
			(clearance 0)
		)
		(min_thickness 0.25)
		(keepout
			(tracks not_allowed)
			(vias allowed)
			(pads allowed)
			(copperpour not_allowed)
			(footprints allowed)
		)
		(placement
			(enabled no)
			(sheetname "")
		)
		(fill yes
			(thermal_gap 0.5)
			(thermal_bridge_width 0.5)
			(island_removal_mode 0)
		)
		(polygon
			(pts
				(arc
					(start 76.213208 -156.830014)
					(mid 73.787 -156.830014)
					(end 76.213208 -156.830014)
				)
			)
		)
	)
	(zone
		(layers "In1.Cu" "In3.Cu" "In6.Cu" "In8.Cu")
		(hatch none 0.5)
		(connect_pads
			(clearance 0)
		)
		(min_thickness 0.25)
		(keepout
			(tracks not_allowed)
			(vias allowed)
			(pads allowed)
			(copperpour not_allowed)
			(footprints allowed)
		)
		(placement
			(enabled no)
			(sheetname "")
		)
		(fill yes
			(thermal_gap 0.5)
			(thermal_bridge_width 0.5)
			(island_removal_mode 0)
		)
		(polygon
			(pts
				(arc
					(start 115.630452 -16.51)
					(mid 113.852452 -16.51)
					(end 115.630452 -16.51)
				)
			)
		)
	)
	(zone
		(layers "In1.Cu" "In3.Cu" "In6.Cu" "In8.Cu")
		(hatch none 0.5)
		(connect_pads
			(clearance 0)
		)
		(min_thickness 0.25)
		(keepout
			(tracks not_allowed)
			(vias allowed)
			(pads allowed)
			(copperpour not_allowed)
			(footprints allowed)
		)
		(placement
			(enabled no)
			(sheetname "")
		)
		(fill yes
			(thermal_gap 0.5)
			(thermal_bridge_width 0.5)
			(island_removal_mode 0)
		)
		(polygon
			(pts
				(arc
					(start 335.3308 -23.0886)
					(mid 333.5528 -23.0886)
					(end 335.3308 -23.0886)
				)
			)
		)
	)
	(zone
		(layers "In1.Cu" "In3.Cu" "In6.Cu" "In8.Cu")
		(hatch none 0.5)
		(connect_pads
			(clearance 0)
		)
		(min_thickness 0.25)
		(keepout
			(tracks not_allowed)
			(vias allowed)
			(pads allowed)
			(copperpour not_allowed)
			(footprints allowed)
		)
		(placement
			(enabled no)
			(sheetname "")
		)
		(fill yes
			(thermal_gap 0.5)
			(thermal_bridge_width 0.5)
			(island_removal_mode 0)
		)
		(polygon
			(pts
				(arc
					(start 333.0448 -44.8818)
					(mid 331.2668 -44.8818)
					(end 333.0448 -44.8818)
				)
			)
		)
	)
	(zone
		(layers "In1.Cu" "In3.Cu" "In6.Cu" "In8.Cu")
		(hatch none 0.5)
		(connect_pads
			(clearance 0)
		)
		(min_thickness 0.25)
		(keepout
			(tracks not_allowed)
			(vias allowed)
			(pads allowed)
			(copperpour not_allowed)
			(footprints allowed)
		)
		(placement
			(enabled no)
			(sheetname "")
		)
		(fill yes
			(thermal_gap 0.5)
			(thermal_bridge_width 0.5)
			(island_removal_mode 0)
		)
		(polygon
			(pts
				(arc
					(start 115.630452 -28.5496)
					(mid 113.852452 -28.5496)
					(end 115.630452 -28.5496)
				)
			)
		)
	)
	(zone
		(layers "In1.Cu" "In3.Cu" "In6.Cu" "In8.Cu")
		(hatch none 0.5)
		(connect_pads
			(clearance 0)
		)
		(min_thickness 0.25)
		(keepout
			(tracks not_allowed)
			(vias allowed)
			(pads allowed)
			(copperpour not_allowed)
			(footprints allowed)
		)
		(placement
			(enabled no)
			(sheetname "")
		)
		(fill yes
			(thermal_gap 0.5)
			(thermal_bridge_width 0.5)
			(island_removal_mode 0)
		)
		(polygon
			(pts
				(arc
					(start 116.392452 -72.898)
					(mid 114.614452 -72.898)
					(end 116.392452 -72.898)
				)
			)
		)
	)
	(zone
		(layer "In2.Cu")
		(hatch none 0.5)
		(connect_pads
			(clearance 0)
		)
		(min_thickness 0.25)
		(keepout
			(tracks not_allowed)
			(vias allowed)
			(pads allowed)
			(copperpour not_allowed)
			(footprints allowed)
		)
		(placement
			(enabled no)
			(sheetname "")
		)
		(fill
			(thermal_gap 0.5)
			(thermal_bridge_width 0.5)
			(island_removal_mode 0)
		)
		(polygon
			(pts
				(arc
					(start 185.500264 -87.499952)
					(mid 190.000382 -82.999834)
					(end 194.500246 -87.499952)
				)
				(arc
					(start 194.500246 -92.499942)
					(mid 190.000382 -96.999806)
					(end 185.500264 -92.499942)
				)
			)
		)
	)
	(zone
		(layer "In2.Cu")
		(hatch none 0.5)
		(connect_pads
			(clearance 0)
		)
		(min_thickness 0.25)
		(keepout
			(tracks not_allowed)
			(vias allowed)
			(pads allowed)
			(copperpour not_allowed)
			(footprints allowed)
		)
		(placement
			(enabled no)
			(sheetname "")
		)
		(fill
			(thermal_gap 0.5)
			(thermal_bridge_width 0.5)
			(island_removal_mode 0)
		)
		(polygon
			(pts
				(arc
					(start 423.500296 -4.500118)
					(mid 423.906908 -2.630821)
					(end 425.053252 -1.099312)
				)
				(arc
					(start 430.947322 -1.099312)
					(mid 432.093684 -2.630812)
					(end 432.500278 -4.500118)
				)
				(arc
					(start 432.500278 -9.500108)
					(mid 428.000414 -13.999972)
					(end 423.500296 -9.500108)
				)
			)
		)
	)
	(zone
		(layers "In2.Cu" "In4.Cu" "In5.Cu")
		(hatch none 0.5)
		(connect_pads
			(clearance 0)
		)
		(min_thickness 0.25)
		(keepout
			(tracks not_allowed)
			(vias allowed)
			(pads allowed)
			(copperpour not_allowed)
			(footprints allowed)
		)
		(placement
			(enabled no)
			(sheetname "")
		)
		(fill yes
			(thermal_gap 0.5)
			(thermal_bridge_width 0.5)
			(island_removal_mode 0)
		)
		(polygon
			(pts
				(arc
					(start 335.500472 -87.500206)
					(mid 340.00059 -83.000088)
					(end 344.500454 -87.500206)
				)
				(arc
					(start 344.500454 -92.500196)
					(mid 340.00059 -97.00006)
					(end 335.500472 -92.500196)
				)
			)
		)
	)
	(zone
		(layers "In2.Cu" "In4.Cu" "In5.Cu")
		(hatch none 0.5)
		(connect_pads
			(clearance 0)
		)
		(min_thickness 0.25)
		(keepout
			(tracks not_allowed)
			(vias allowed)
			(pads allowed)
			(copperpour not_allowed)
			(footprints allowed)
		)
		(placement
			(enabled no)
			(sheetname "")
		)
		(fill yes
			(thermal_gap 0.5)
			(thermal_bridge_width 0.5)
			(island_removal_mode 0)
		)
		(polygon
			(pts
				(arc
					(start 364.50016 -13.5001)
					(mid 369.000278 -8.999982)
					(end 373.500142 -13.5001)
				)
				(arc
					(start 373.500142 -18.50009)
					(mid 369.000278 -22.999954)
					(end 364.50016 -18.50009)
				)
			)
		)
	)
	(zone
		(layers "In2.Cu" "In4.Cu" "In5.Cu" "In7.Cu")
		(hatch none 0.5)
		(connect_pads
			(clearance 0)
		)
		(min_thickness 0.25)
		(keepout
			(tracks not_allowed)
			(vias allowed)
			(pads allowed)
			(copperpour not_allowed)
			(footprints allowed)
		)
		(placement
			(enabled no)
			(sheetname "")
		)
		(fill yes
			(thermal_gap 0.5)
			(thermal_bridge_width 0.5)
			(island_removal_mode 0)
		)
		(polygon
			(pts
				(arc
					(start 95.500444 -87.500206)
					(mid 100.000562 -83.000088)
					(end 104.500426 -87.500206)
				)
				(arc
					(start 104.500426 -92.500196)
					(mid 100.000562 -97.00006)
					(end 95.500444 -92.500196)
				)
			)
		)
	)
	(zone
		(layers "In2.Cu" "In4.Cu" "In5.Cu" "In7.Cu")
		(hatch none 0.5)
		(connect_pads
			(clearance 0)
		)
		(min_thickness 0.25)
		(keepout
			(tracks not_allowed)
			(vias allowed)
			(pads allowed)
			(copperpour not_allowed)
			(footprints allowed)
		)
		(placement
			(enabled no)
			(sheetname "")
		)
		(fill yes
			(thermal_gap 0.5)
			(thermal_bridge_width 0.5)
			(island_removal_mode 0)
		)
		(polygon
			(pts
				(arc
					(start 75.50023 -142.500096)
					(mid 80.000348 -137.999978)
					(end 84.500212 -142.500096)
				)
				(arc
					(start 84.500212 -147.500086)
					(mid 80.000348 -151.99995)
					(end 75.50023 -147.500086)
				)
			)
		)
	)
	(zone
		(layers "In2.Cu" "In4.Cu" "In5.Cu" "In7.Cu")
		(hatch none 0.5)
		(connect_pads
			(clearance 0)
		)
		(min_thickness 0.25)
		(keepout
			(tracks not_allowed)
			(vias allowed)
			(pads allowed)
			(copperpour not_allowed)
			(footprints allowed)
		)
		(placement
			(enabled no)
			(sheetname "")
		)
		(fill yes
			(thermal_gap 0.5)
			(thermal_bridge_width 0.5)
			(island_removal_mode 0)
		)
		(polygon
			(pts
				(arc
					(start 355.500432 -142.500096)
					(mid 360.00055 -137.999978)
					(end 364.500414 -142.500096)
				)
				(arc
					(start 364.500414 -147.500086)
					(mid 360.00055 -151.99995)
					(end 355.500432 -147.500086)
				)
			)
		)
	)
	(zone
		(layers "In2.Cu" "In4.Cu" "In5.Cu" "In7.Cu")
		(hatch none 0.5)
		(connect_pads
			(clearance 0)
		)
		(min_thickness 0.25)
		(keepout
			(tracks not_allowed)
			(vias allowed)
			(pads allowed)
			(copperpour not_allowed)
			(footprints allowed)
		)
		(placement
			(enabled no)
			(sheetname "")
		)
		(fill yes
			(thermal_gap 0.5)
			(thermal_bridge_width 0.5)
			(island_removal_mode 0)
		)
		(polygon
			(pts
				(arc
					(start 354.865432 -147.500086)
					(mid 360.00055 -152.635204)
					(end 365.135414 -147.500086)
				)
				(arc
					(start 365.135414 -142.500096)
					(mid 360.00055 -137.365232)
					(end 354.865432 -142.500096)
				)
			)
		)
	)
	(zone
		(layers "In2.Cu" "In4.Cu" "In5.Cu" "In7.Cu")
		(hatch none 0.5)
		(connect_pads
			(clearance 0)
		)
		(min_thickness 0.25)
		(keepout
			(tracks not_allowed)
			(vias allowed)
			(pads allowed)
			(copperpour not_allowed)
			(footprints allowed)
		)
		(placement
			(enabled no)
			(sheetname "")
		)
		(fill yes
			(thermal_gap 0.5)
			(thermal_bridge_width 0.5)
			(island_removal_mode 0)
		)
		(polygon
			(pts
				(arc
					(start 94.865444 -92.500196)
					(mid 100.000562 -97.635314)
					(end 105.135426 -92.500196)
				)
				(arc
					(start 105.135426 -87.500206)
					(mid 100.000562 -82.365342)
					(end 94.865444 -87.500206)
				)
			)
		)
	)
	(zone
		(layers "In2.Cu" "In4.Cu" "In5.Cu" "In7.Cu")
		(hatch none 0.5)
		(connect_pads
			(clearance 0)
		)
		(min_thickness 0.25)
		(keepout
			(tracks not_allowed)
			(vias allowed)
			(pads allowed)
			(copperpour not_allowed)
			(footprints allowed)
		)
		(placement
			(enabled no)
			(sheetname "")
		)
		(fill yes
			(thermal_gap 0.5)
			(thermal_bridge_width 0.5)
			(island_removal_mode 0)
		)
		(polygon
			(pts
				(arc
					(start 74.86523 -147.500086)
					(mid 80.000348 -152.635204)
					(end 85.135212 -147.500086)
				)
				(arc
					(start 85.135212 -142.500096)
					(mid 80.000348 -137.365232)
					(end 74.86523 -142.500096)
				)
			)
		)
	)
	(zone
		(layers "In2.Cu" "In7.Cu")
		(hatch none 0.5)
		(connect_pads
			(clearance 0)
		)
		(min_thickness 0.25)
		(keepout
			(tracks not_allowed)
			(vias allowed)
			(pads allowed)
			(copperpour not_allowed)
			(footprints allowed)
		)
		(placement
			(enabled no)
			(sheetname "")
		)
		(fill yes
			(thermal_gap 0.5)
			(thermal_bridge_width 0.5)
			(island_removal_mode 0)
		)
		(polygon
			(pts
				(arc
					(start 245.500144 -87.499952)
					(mid 250.000262 -82.999834)
					(end 254.500126 -87.499952)
				)
				(arc
					(start 254.500126 -92.499942)
					(mid 250.000262 -96.999806)
					(end 245.500144 -92.499942)
				)
			)
		)
	)
	(zone
		(layers "In3.Cu" "In6.Cu" "In8.Cu")
		(hatch none 0.5)
		(connect_pads
			(clearance 0)
		)
		(min_thickness 0.25)
		(keepout
			(tracks not_allowed)
			(vias allowed)
			(pads allowed)
			(copperpour not_allowed)
			(footprints allowed)
		)
		(placement
			(enabled no)
			(sheetname "")
		)
		(fill yes
			(thermal_gap 0.5)
			(thermal_bridge_width 0.5)
			(island_removal_mode 0)
		)
		(polygon
			(pts
				(arc
					(start 51.162204 -159.99841)
					(mid 48.735996 -159.99841)
					(end 51.162204 -159.99841)
				)
			)
		)
	)
	(zone
		(layers "In3.Cu" "In6.Cu" "In8.Cu")
		(hatch none 0.5)
		(connect_pads
			(clearance 0)
		)
		(min_thickness 0.25)
		(keepout
			(tracks not_allowed)
			(vias allowed)
			(pads allowed)
			(copperpour not_allowed)
			(footprints allowed)
		)
		(placement
			(enabled no)
			(sheetname "")
		)
		(fill yes
			(thermal_gap 0.5)
			(thermal_bridge_width 0.5)
			(island_removal_mode 0)
		)
		(polygon
			(pts
				(arc
					(start 400.623024 -167.591994)
					(mid 398.196816 -167.591994)
					(end 400.623024 -167.591994)
				)
			)
		)
	)
	(zone
		(layers "In3.Cu" "In6.Cu" "In8.Cu")
		(hatch none 0.5)
		(connect_pads
			(clearance 0)
		)
		(min_thickness 0.25)
		(keepout
			(tracks not_allowed)
			(vias allowed)
			(pads allowed)
			(copperpour not_allowed)
			(footprints allowed)
		)
		(placement
			(enabled no)
			(sheetname "")
		)
		(fill yes
			(thermal_gap 0.5)
			(thermal_bridge_width 0.5)
			(island_removal_mode 0)
		)
		(polygon
			(pts
				(arc
					(start 37.199062 -159.56661)
					(mid 34.772854 -159.56661)
					(end 37.199062 -159.56661)
				)
			)
		)
	)
	(zone
		(layers "In3.Cu" "In6.Cu" "In8.Cu")
		(hatch none 0.5)
		(connect_pads
			(clearance 0)
		)
		(min_thickness 0.25)
		(keepout
			(tracks not_allowed)
			(vias allowed)
			(pads allowed)
			(copperpour not_allowed)
			(footprints allowed)
		)
		(placement
			(enabled no)
			(sheetname "")
		)
		(fill yes
			(thermal_gap 0.5)
			(thermal_bridge_width 0.5)
			(island_removal_mode 0)
		)
		(polygon
			(pts
				(arc
					(start 77.070204 -159.74441)
					(mid 74.643996 -159.74441)
					(end 77.070204 -159.74441)
				)
			)
		)
	)
	(zone
		(layers "In3.Cu" "In6.Cu" "In8.Cu")
		(hatch none 0.5)
		(connect_pads
			(clearance 0)
		)
		(min_thickness 0.25)
		(keepout
			(tracks not_allowed)
			(vias allowed)
			(pads allowed)
			(copperpour not_allowed)
			(footprints allowed)
		)
		(placement
			(enabled no)
			(sheetname "")
		)
		(fill yes
			(thermal_gap 0.5)
			(thermal_bridge_width 0.5)
			(island_removal_mode 0)
		)
		(polygon
			(pts
				(arc
					(start 71.101204 -157.795214)
					(mid 68.674996 -157.795214)
					(end 71.101204 -157.795214)
				)
			)
		)
	)
	(zone
		(layers "In3.Cu" "In6.Cu" "In8.Cu")
		(hatch none 0.5)
		(connect_pads
			(clearance 0)
		)
		(min_thickness 0.25)
		(keepout
			(tracks not_allowed)
			(vias allowed)
			(pads allowed)
			(copperpour not_allowed)
			(footprints allowed)
		)
		(placement
			(enabled no)
			(sheetname "")
		)
		(fill yes
			(thermal_gap 0.5)
			(thermal_bridge_width 0.5)
			(island_removal_mode 0)
		)
		(polygon
			(pts
				(arc
					(start 365.336582 -159.82061)
					(mid 362.910374 -159.82061)
					(end 365.336582 -159.82061)
				)
			)
		)
	)
	(zone
		(layers "In3.Cu" "In6.Cu" "In8.Cu")
		(hatch none 0.5)
		(connect_pads
			(clearance 0)
		)
		(min_thickness 0.25)
		(keepout
			(tracks not_allowed)
			(vias allowed)
			(pads allowed)
			(copperpour not_allowed)
			(footprints allowed)
		)
		(placement
			(enabled no)
			(sheetname "")
		)
		(fill yes
			(thermal_gap 0.5)
			(thermal_bridge_width 0.5)
			(island_removal_mode 0)
		)
		(polygon
			(pts
				(arc
					(start 471.404188 -74.785982)
					(mid 468.584788 -74.785982)
					(end 471.404188 -74.785982)
				)
			)
		)
	)
	(zone
		(layers "In3.Cu" "In6.Cu" "In8.Cu")
		(hatch none 0.5)
		(connect_pads
			(clearance 0)
		)
		(min_thickness 0.25)
		(keepout
			(tracks not_allowed)
			(vias allowed)
			(pads allowed)
			(copperpour not_allowed)
			(footprints allowed)
		)
		(placement
			(enabled no)
			(sheetname "")
		)
		(fill yes
			(thermal_gap 0.5)
			(thermal_bridge_width 0.5)
			(island_removal_mode 0)
		)
		(polygon
			(pts
				(arc
					(start 385.275582 -157.642814)
					(mid 382.849374 -157.642814)
					(end 385.275582 -157.642814)
				)
			)
		)
	)
	(zone
		(layers "In3.Cu" "In6.Cu" "In8.Cu")
		(hatch none 0.5)
		(connect_pads
			(clearance 0)
		)
		(min_thickness 0.25)
		(keepout
			(tracks not_allowed)
			(vias allowed)
			(pads allowed)
			(copperpour not_allowed)
			(footprints allowed)
		)
		(placement
			(enabled no)
			(sheetname "")
		)
		(fill yes
			(thermal_gap 0.5)
			(thermal_bridge_width 0.5)
			(island_removal_mode 0)
		)
		(polygon
			(pts
				(arc
					(start 51.162204 -157.998414)
					(mid 48.735996 -157.998414)
					(end 51.162204 -157.998414)
				)
			)
		)
	)
	(zone
		(layers "In3.Cu" "In6.Cu" "In8.Cu")
		(hatch none 0.5)
		(connect_pads
			(clearance 0)
		)
		(min_thickness 0.25)
		(keepout
			(tracks not_allowed)
			(vias allowed)
			(pads allowed)
			(copperpour not_allowed)
			(footprints allowed)
		)
		(placement
			(enabled no)
			(sheetname "")
		)
		(fill yes
			(thermal_gap 0.5)
			(thermal_bridge_width 0.5)
			(island_removal_mode 0)
		)
		(polygon
			(pts
				(arc
					(start 400.623024 -157.592014)
					(mid 398.196816 -157.592014)
					(end 400.623024 -157.592014)
				)
			)
		)
	)
	(zone
		(layers "In3.Cu" "In6.Cu" "In8.Cu")
		(hatch none 0.5)
		(connect_pads
			(clearance 0)
		)
		(min_thickness 0.25)
		(keepout
			(tracks not_allowed)
			(vias allowed)
			(pads allowed)
			(copperpour not_allowed)
			(footprints allowed)
		)
		(placement
			(enabled no)
			(sheetname "")
		)
		(fill yes
			(thermal_gap 0.5)
			(thermal_bridge_width 0.5)
			(island_removal_mode 0)
		)
		(polygon
			(pts
				(arc
					(start 471.404188 -72.245982)
					(mid 468.584788 -72.245982)
					(end 471.404188 -72.245982)
				)
			)
		)
	)
	(zone
		(layers "In3.Cu" "In6.Cu" "In8.Cu")
		(hatch none 0.5)
		(connect_pads
			(clearance 0)
		)
		(min_thickness 0.25)
		(keepout
			(tracks not_allowed)
			(vias allowed)
			(pads allowed)
			(copperpour not_allowed)
			(footprints allowed)
		)
		(placement
			(enabled no)
			(sheetname "")
		)
		(fill yes
			(thermal_gap 0.5)
			(thermal_bridge_width 0.5)
			(island_removal_mode 0)
		)
		(polygon
			(pts
				(arc
					(start 377.122182 -159.79521)
					(mid 374.695974 -159.79521)
					(end 377.122182 -159.79521)
				)
			)
		)
	)
	(zone
		(layers "In3.Cu" "In6.Cu" "In8.Cu")
		(hatch none 0.5)
		(connect_pads
			(clearance 0)
		)
		(min_thickness 0.25)
		(keepout
			(tracks not_allowed)
			(vias allowed)
			(pads allowed)
			(copperpour not_allowed)
			(footprints allowed)
		)
		(placement
			(enabled no)
			(sheetname "")
		)
		(fill yes
			(thermal_gap 0.5)
			(thermal_bridge_width 0.5)
			(island_removal_mode 0)
		)
		(polygon
			(pts
				(arc
					(start 371.203982 -159.87141)
					(mid 368.777774 -159.87141)
					(end 371.203982 -159.87141)
				)
			)
		)
	)
	(zone
		(layers "In3.Cu" "In6.Cu" "In8.Cu")
		(hatch none 0.5)
		(connect_pads
			(clearance 0)
		)
		(min_thickness 0.25)
		(keepout
			(tracks not_allowed)
			(vias allowed)
			(pads allowed)
			(copperpour not_allowed)
			(footprints allowed)
		)
		(placement
			(enabled no)
			(sheetname "")
		)
		(fill yes
			(thermal_gap 0.5)
			(thermal_bridge_width 0.5)
			(island_removal_mode 0)
		)
		(polygon
			(pts
				(arc
					(start 77.070204 -157.744414)
					(mid 74.643996 -157.744414)
					(end 77.070204 -157.744414)
				)
			)
		)
	)
	(zone
		(layers "In3.Cu" "In6.Cu" "In8.Cu")
		(hatch none 0.5)
		(connect_pads
			(clearance 0)
		)
		(min_thickness 0.25)
		(keepout
			(tracks not_allowed)
			(vias allowed)
			(pads allowed)
			(copperpour not_allowed)
			(footprints allowed)
		)
		(placement
			(enabled no)
			(sheetname "")
		)
		(fill yes
			(thermal_gap 0.5)
			(thermal_bridge_width 0.5)
			(island_removal_mode 0)
		)
		(polygon
			(pts
				(arc
					(start 400.623024 -155.592018)
					(mid 398.196816 -155.592018)
					(end 400.623024 -155.592018)
				)
			)
		)
	)
	(zone
		(layers "In3.Cu" "In6.Cu" "In8.Cu")
		(hatch none 0.5)
		(connect_pads
			(clearance 0)
		)
		(min_thickness 0.25)
		(keepout
			(tracks not_allowed)
			(vias allowed)
			(pads allowed)
			(copperpour not_allowed)
			(footprints allowed)
		)
		(placement
			(enabled no)
			(sheetname "")
		)
		(fill yes
			(thermal_gap 0.5)
			(thermal_bridge_width 0.5)
			(island_removal_mode 0)
		)
		(polygon
			(pts
				(arc
					(start 37.199062 -157.566614)
					(mid 34.772854 -157.566614)
					(end 37.199062 -157.566614)
				)
			)
		)
	)
	(zone
		(layers "In3.Cu" "In6.Cu" "In8.Cu")
		(hatch none 0.5)
		(connect_pads
			(clearance 0)
		)
		(min_thickness 0.25)
		(keepout
			(tracks not_allowed)
			(vias allowed)
			(pads allowed)
			(copperpour not_allowed)
			(footprints allowed)
		)
		(placement
			(enabled no)
			(sheetname "")
		)
		(fill yes
			(thermal_gap 0.5)
			(thermal_bridge_width 0.5)
			(island_removal_mode 0)
		)
		(polygon
			(pts
				(arc
					(start 71.101204 -159.79521)
					(mid 68.674996 -159.79521)
					(end 71.101204 -159.79521)
				)
			)
		)
	)
	(zone
		(layers "In3.Cu" "In6.Cu" "In8.Cu")
		(hatch none 0.5)
		(connect_pads
			(clearance 0)
		)
		(min_thickness 0.25)
		(keepout
			(tracks not_allowed)
			(vias allowed)
			(pads allowed)
			(copperpour not_allowed)
			(footprints allowed)
		)
		(placement
			(enabled no)
			(sheetname "")
		)
		(fill yes
			(thermal_gap 0.5)
			(thermal_bridge_width 0.5)
			(island_removal_mode 0)
		)
		(polygon
			(pts
				(arc
					(start 37.199062 -167.566594)
					(mid 34.772854 -167.566594)
					(end 37.199062 -167.566594)
				)
			)
		)
	)
	(zone
		(layers "In3.Cu" "In6.Cu" "In8.Cu")
		(hatch none 0.5)
		(connect_pads
			(clearance 0)
		)
		(min_thickness 0.25)
		(keepout
			(tracks not_allowed)
			(vias allowed)
			(pads allowed)
			(copperpour not_allowed)
			(footprints allowed)
		)
		(placement
			(enabled no)
			(sheetname "")
		)
		(fill yes
			(thermal_gap 0.5)
			(thermal_bridge_width 0.5)
			(island_removal_mode 0)
		)
		(polygon
			(pts
				(arc
					(start 391.371582 -157.719014)
					(mid 388.945374 -157.719014)
					(end 391.371582 -157.719014)
				)
			)
		)
	)
	(zone
		(layers "In3.Cu" "In6.Cu" "In8.Cu")
		(hatch none 0.5)
		(connect_pads
			(clearance 0)
		)
		(min_thickness 0.25)
		(keepout
			(tracks not_allowed)
			(vias allowed)
			(pads allowed)
			(copperpour not_allowed)
			(footprints allowed)
		)
		(placement
			(enabled no)
			(sheetname "")
		)
		(fill yes
			(thermal_gap 0.5)
			(thermal_bridge_width 0.5)
			(island_removal_mode 0)
		)
		(polygon
			(pts
				(arc
					(start 37.199062 -155.566618)
					(mid 34.772854 -155.566618)
					(end 37.199062 -155.566618)
				)
			)
		)
	)
	(zone
		(layers "In3.Cu" "In6.Cu" "In8.Cu")
		(hatch none 0.5)
		(connect_pads
			(clearance 0)
		)
		(min_thickness 0.25)
		(keepout
			(tracks not_allowed)
			(vias allowed)
			(pads allowed)
			(copperpour not_allowed)
			(footprints allowed)
		)
		(placement
			(enabled no)
			(sheetname "")
		)
		(fill yes
			(thermal_gap 0.5)
			(thermal_bridge_width 0.5)
			(island_removal_mode 0)
		)
		(polygon
			(pts
				(arc
					(start 391.371582 -159.71901)
					(mid 388.945374 -159.71901)
					(end 391.371582 -159.71901)
				)
			)
		)
	)
	(zone
		(layers "In3.Cu" "In6.Cu" "In8.Cu")
		(hatch none 0.5)
		(connect_pads
			(clearance 0)
		)
		(min_thickness 0.25)
		(keepout
			(tracks not_allowed)
			(vias allowed)
			(pads allowed)
			(copperpour not_allowed)
			(footprints allowed)
		)
		(placement
			(enabled no)
			(sheetname "")
		)
		(fill yes
			(thermal_gap 0.5)
			(thermal_bridge_width 0.5)
			(island_removal_mode 0)
		)
		(polygon
			(pts
				(arc
					(start 65.183004 -159.89681)
					(mid 62.756796 -159.89681)
					(end 65.183004 -159.89681)
				)
			)
		)
	)
	(zone
		(layers "In3.Cu" "In6.Cu" "In8.Cu")
		(hatch none 0.5)
		(connect_pads
			(clearance 0)
		)
		(min_thickness 0.25)
		(keepout
			(tracks not_allowed)
			(vias allowed)
			(pads allowed)
			(copperpour not_allowed)
			(footprints allowed)
		)
		(placement
			(enabled no)
			(sheetname "")
		)
		(fill yes
			(thermal_gap 0.5)
			(thermal_bridge_width 0.5)
			(island_removal_mode 0)
		)
		(polygon
			(pts
				(arc
					(start 56.775604 -159.84601)
					(mid 54.349396 -159.84601)
					(end 56.775604 -159.84601)
				)
			)
		)
	)
	(zone
		(layers "In3.Cu" "In6.Cu" "In8.Cu")
		(hatch none 0.5)
		(connect_pads
			(clearance 0)
		)
		(min_thickness 0.25)
		(keepout
			(tracks not_allowed)
			(vias allowed)
			(pads allowed)
			(copperpour not_allowed)
			(footprints allowed)
		)
		(placement
			(enabled no)
			(sheetname "")
		)
		(fill yes
			(thermal_gap 0.5)
			(thermal_bridge_width 0.5)
			(island_removal_mode 0)
		)
		(polygon
			(pts
				(arc
					(start 400.623024 -159.59201)
					(mid 398.196816 -159.59201)
					(end 400.623024 -159.59201)
				)
			)
		)
	)
	(zone
		(layers "In3.Cu" "In6.Cu" "In8.Cu")
		(hatch none 0.5)
		(connect_pads
			(clearance 0)
		)
		(min_thickness 0.25)
		(keepout
			(tracks not_allowed)
			(vias allowed)
			(pads allowed)
			(copperpour not_allowed)
			(footprints allowed)
		)
		(placement
			(enabled no)
			(sheetname "")
		)
		(fill yes
			(thermal_gap 0.5)
			(thermal_bridge_width 0.5)
			(island_removal_mode 0)
		)
		(polygon
			(pts
				(arc
					(start 385.275582 -159.64281)
					(mid 382.849374 -159.64281)
					(end 385.275582 -159.64281)
				)
			)
		)
	)
	(zone
		(layers "In3.Cu" "In6.Cu" "In8.Cu")
		(hatch none 0.5)
		(connect_pads
			(clearance 0)
		)
		(min_thickness 0.25)
		(keepout
			(tracks not_allowed)
			(vias allowed)
			(pads allowed)
			(copperpour not_allowed)
			(footprints allowed)
		)
		(placement
			(enabled no)
			(sheetname "")
		)
		(fill yes
			(thermal_gap 0.5)
			(thermal_bridge_width 0.5)
			(island_removal_mode 0)
		)
		(polygon
			(pts
				(arc
					(start 37.199062 -163.566602)
					(mid 34.772854 -163.566602)
					(end 37.199062 -163.566602)
				)
			)
		)
	)
	(zone
		(layers "In3.Cu" "In6.Cu" "In8.Cu")
		(hatch none 0.5)
		(connect_pads
			(clearance 0)
		)
		(min_thickness 0.25)
		(keepout
			(tracks not_allowed)
			(vias allowed)
			(pads allowed)
			(copperpour not_allowed)
			(footprints allowed)
		)
		(placement
			(enabled no)
			(sheetname "")
		)
		(fill yes
			(thermal_gap 0.5)
			(thermal_bridge_width 0.5)
			(island_removal_mode 0)
		)
		(polygon
			(pts
				(arc
					(start 400.623024 -153.592022)
					(mid 398.196816 -153.592022)
					(end 400.623024 -153.592022)
				)
			)
		)
	)
	(zone
		(layers "In3.Cu" "In6.Cu" "In8.Cu")
		(hatch none 0.5)
		(connect_pads
			(clearance 0)
		)
		(min_thickness 0.25)
		(keepout
			(tracks not_allowed)
			(vias allowed)
			(pads allowed)
			(copperpour not_allowed)
			(footprints allowed)
		)
		(placement
			(enabled no)
			(sheetname "")
		)
		(fill yes
			(thermal_gap 0.5)
			(thermal_bridge_width 0.5)
			(island_removal_mode 0)
		)
		(polygon
			(pts
				(arc
					(start 400.623024 -165.591998)
					(mid 398.196816 -165.591998)
					(end 400.623024 -165.591998)
				)
			)
		)
	)
	(zone
		(layers "In3.Cu" "In6.Cu" "In8.Cu")
		(hatch none 0.5)
		(connect_pads
			(clearance 0)
		)
		(min_thickness 0.25)
		(keepout
			(tracks not_allowed)
			(vias allowed)
			(pads allowed)
			(copperpour not_allowed)
			(footprints allowed)
		)
		(placement
			(enabled no)
			(sheetname "")
		)
		(fill yes
			(thermal_gap 0.5)
			(thermal_bridge_width 0.5)
			(island_removal_mode 0)
		)
		(polygon
			(pts
				(arc
					(start 377.122182 -157.795214)
					(mid 374.695974 -157.795214)
					(end 377.122182 -157.795214)
				)
			)
		)
	)
	(zone
		(layers "In3.Cu" "In6.Cu" "In8.Cu")
		(hatch none 0.5)
		(connect_pads
			(clearance 0)
		)
		(min_thickness 0.25)
		(keepout
			(tracks not_allowed)
			(vias allowed)
			(pads allowed)
			(copperpour not_allowed)
			(footprints allowed)
		)
		(placement
			(enabled no)
			(sheetname "")
		)
		(fill yes
			(thermal_gap 0.5)
			(thermal_bridge_width 0.5)
			(island_removal_mode 0)
		)
		(polygon
			(pts
				(arc
					(start 37.199062 -165.566598)
					(mid 34.772854 -165.566598)
					(end 37.199062 -165.566598)
				)
			)
		)
	)
	(zone
		(layers "In3.Cu" "In6.Cu" "In8.Cu")
		(hatch none 0.5)
		(connect_pads
			(clearance 0)
		)
		(min_thickness 0.25)
		(keepout
			(tracks not_allowed)
			(vias allowed)
			(pads allowed)
			(copperpour not_allowed)
			(footprints allowed)
		)
		(placement
			(enabled no)
			(sheetname "")
		)
		(fill yes
			(thermal_gap 0.5)
			(thermal_bridge_width 0.5)
			(island_removal_mode 0)
		)
		(polygon
			(pts
				(arc
					(start 400.623024 -161.592006)
					(mid 398.196816 -161.592006)
					(end 400.623024 -161.592006)
				)
			)
		)
	)
	(zone
		(layers "In3.Cu" "In6.Cu" "In8.Cu")
		(hatch none 0.5)
		(connect_pads
			(clearance 0)
		)
		(min_thickness 0.25)
		(keepout
			(tracks not_allowed)
			(vias allowed)
			(pads allowed)
			(copperpour not_allowed)
			(footprints allowed)
		)
		(placement
			(enabled no)
			(sheetname "")
		)
		(fill yes
			(thermal_gap 0.5)
			(thermal_bridge_width 0.5)
			(island_removal_mode 0)
		)
		(polygon
			(pts
				(arc
					(start 37.199062 -161.566606)
					(mid 34.772854 -161.566606)
					(end 37.199062 -161.566606)
				)
			)
		)
	)
	(zone
		(layers "In3.Cu" "In6.Cu" "In8.Cu")
		(hatch none 0.5)
		(connect_pads
			(clearance 0)
		)
		(min_thickness 0.25)
		(keepout
			(tracks not_allowed)
			(vias allowed)
			(pads allowed)
			(copperpour not_allowed)
			(footprints allowed)
		)
		(placement
			(enabled no)
			(sheetname "")
		)
		(fill yes
			(thermal_gap 0.5)
			(thermal_bridge_width 0.5)
			(island_removal_mode 0)
		)
		(polygon
			(pts
				(arc
					(start 471.404188 -69.705982)
					(mid 468.584788 -69.705982)
					(end 471.404188 -69.705982)
				)
			)
		)
	)
	(zone
		(layers "In3.Cu" "In6.Cu" "In8.Cu")
		(hatch none 0.5)
		(connect_pads
			(clearance 0)
		)
		(min_thickness 0.25)
		(keepout
			(tracks not_allowed)
			(vias allowed)
			(pads allowed)
			(copperpour not_allowed)
			(footprints allowed)
		)
		(placement
			(enabled no)
			(sheetname "")
		)
		(fill yes
			(thermal_gap 0.5)
			(thermal_bridge_width 0.5)
			(island_removal_mode 0)
		)
		(polygon
			(pts
				(arc
					(start 65.183004 -157.896814)
					(mid 62.756796 -157.896814)
					(end 65.183004 -157.896814)
				)
			)
		)
	)
	(zone
		(layers "In3.Cu" "In6.Cu" "In8.Cu")
		(hatch none 0.5)
		(connect_pads
			(clearance 0)
		)
		(min_thickness 0.25)
		(keepout
			(tracks not_allowed)
			(vias allowed)
			(pads allowed)
			(copperpour not_allowed)
			(footprints allowed)
		)
		(placement
			(enabled no)
			(sheetname "")
		)
		(fill yes
			(thermal_gap 0.5)
			(thermal_bridge_width 0.5)
			(island_removal_mode 0)
		)
		(polygon
			(pts
				(arc
					(start 400.623024 -163.592002)
					(mid 398.196816 -163.592002)
					(end 400.623024 -163.592002)
				)
			)
		)
	)
	(zone
		(layers "In3.Cu" "In6.Cu" "In8.Cu")
		(hatch none 0.5)
		(connect_pads
			(clearance 0)
		)
		(min_thickness 0.25)
		(keepout
			(tracks not_allowed)
			(vias allowed)
			(pads allowed)
			(copperpour not_allowed)
			(footprints allowed)
		)
		(placement
			(enabled no)
			(sheetname "")
		)
		(fill yes
			(thermal_gap 0.5)
			(thermal_bridge_width 0.5)
			(island_removal_mode 0)
		)
		(polygon
			(pts
				(arc
					(start 37.199062 -153.566622)
					(mid 34.772854 -153.566622)
					(end 37.199062 -153.566622)
				)
			)
		)
	)
	(zone
		(layers "In3.Cu" "In6.Cu" "In8.Cu")
		(hatch none 0.5)
		(connect_pads
			(clearance 0)
		)
		(min_thickness 0.25)
		(keepout
			(tracks not_allowed)
			(vias allowed)
			(pads allowed)
			(copperpour not_allowed)
			(footprints allowed)
		)
		(placement
			(enabled no)
			(sheetname "")
		)
		(fill yes
			(thermal_gap 0.5)
			(thermal_bridge_width 0.5)
			(island_removal_mode 0)
		)
		(polygon
			(pts
				(arc
					(start 56.775604 -157.846014)
					(mid 54.349396 -157.846014)
					(end 56.775604 -157.846014)
				)
			)
		)
	)
	(zone
		(layers "In3.Cu" "In6.Cu" "In8.Cu")
		(hatch none 0.5)
		(connect_pads
			(clearance 0)
		)
		(min_thickness 0.25)
		(keepout
			(tracks not_allowed)
			(vias allowed)
			(pads allowed)
			(copperpour not_allowed)
			(footprints allowed)
		)
		(placement
			(enabled no)
			(sheetname "")
		)
		(fill yes
			(thermal_gap 0.5)
			(thermal_bridge_width 0.5)
			(island_removal_mode 0)
		)
		(polygon
			(pts
				(arc
					(start 365.336582 -157.820614)
					(mid 362.910374 -157.820614)
					(end 365.336582 -157.820614)
				)
			)
		)
	)
	(zone
		(layers "In3.Cu" "In6.Cu" "In8.Cu")
		(hatch none 0.5)
		(connect_pads
			(clearance 0)
		)
		(min_thickness 0.25)
		(keepout
			(tracks not_allowed)
			(vias allowed)
			(pads allowed)
			(copperpour not_allowed)
			(footprints allowed)
		)
		(placement
			(enabled no)
			(sheetname "")
		)
		(fill yes
			(thermal_gap 0.5)
			(thermal_bridge_width 0.5)
			(island_removal_mode 0)
		)
		(polygon
			(pts
				(arc
					(start 371.203982 -157.871414)
					(mid 368.777774 -157.871414)
					(end 371.203982 -157.871414)
				)
			)
		)
	)
	(zone
		(layer "In4.Cu")
		(hatch none 0.5)
		(connect_pads
			(clearance 0)
		)
		(min_thickness 0.25)
		(keepout
			(tracks not_allowed)
			(vias allowed)
			(pads allowed)
			(copperpour not_allowed)
			(footprints allowed)
		)
		(placement
			(enabled no)
			(sheetname "")
		)
		(fill
			(thermal_gap 0.5)
			(thermal_bridge_width 0.5)
			(island_removal_mode 0)
		)
		(polygon
			(pts
				(arc
					(start 169.05605 -81.28)
					(mid 167.27805 -81.28)
					(end 169.05605 -81.28)
				)
			)
		)
	)
	(zone
		(layer "In4.Cu")
		(hatch none 0.5)
		(connect_pads
			(clearance 0)
		)
		(min_thickness 0.25)
		(keepout
			(tracks not_allowed)
			(vias allowed)
			(pads allowed)
			(copperpour not_allowed)
			(footprints allowed)
		)
		(placement
			(enabled no)
			(sheetname "")
		)
		(fill
			(thermal_gap 0.5)
			(thermal_bridge_width 0.5)
			(island_removal_mode 0)
		)
		(polygon
			(pts
				(arc
					(start 71.063104 -167.718994)
					(mid 68.636896 -167.718994)
					(end 71.063104 -167.718994)
				)
			)
		)
	)
	(zone
		(layer "In4.Cu")
		(hatch none 0.5)
		(connect_pads
			(clearance 0)
		)
		(min_thickness 0.25)
		(keepout
			(tracks not_allowed)
			(vias allowed)
			(pads allowed)
			(copperpour not_allowed)
			(footprints allowed)
		)
		(placement
			(enabled no)
			(sheetname "")
		)
		(fill
			(thermal_gap 0.5)
			(thermal_bridge_width 0.5)
			(island_removal_mode 0)
		)
		(polygon
			(pts
				(arc
					(start 271.2974 -82.296)
					(mid 269.5194 -82.296)
					(end 271.2974 -82.296)
				)
			)
		)
	)
	(zone
		(layer "In4.Cu")
		(hatch none 0.5)
		(connect_pads
			(clearance 0)
		)
		(min_thickness 0.25)
		(keepout
			(tracks not_allowed)
			(vias allowed)
			(pads allowed)
			(copperpour not_allowed)
			(footprints allowed)
		)
		(placement
			(enabled no)
			(sheetname "")
		)
		(fill
			(thermal_gap 0.5)
			(thermal_bridge_width 0.5)
			(island_removal_mode 0)
		)
		(polygon
			(pts
				(arc
					(start 319.90665 -85.598)
					(mid 318.12865 -85.598)
					(end 319.90665 -85.598)
				)
			)
		)
	)
	(zone
		(layer "In4.Cu")
		(hatch none 0.5)
		(connect_pads
			(clearance 0)
		)
		(min_thickness 0.25)
		(keepout
			(tracks not_allowed)
			(vias allowed)
			(pads allowed)
			(copperpour not_allowed)
			(footprints allowed)
		)
		(placement
			(enabled no)
			(sheetname "")
		)
		(fill
			(thermal_gap 0.5)
			(thermal_bridge_width 0.5)
			(island_removal_mode 0)
		)
		(polygon
			(pts
				(arc
					(start 57.093104 -165.591998)
					(mid 54.666896 -165.591998)
					(end 57.093104 -165.591998)
				)
			)
		)
	)
	(zone
		(layer "In4.Cu")
		(hatch none 0.5)
		(connect_pads
			(clearance 0)
		)
		(min_thickness 0.25)
		(keepout
			(tracks not_allowed)
			(vias allowed)
			(pads allowed)
			(copperpour not_allowed)
			(footprints allowed)
		)
		(placement
			(enabled no)
			(sheetname "")
		)
		(fill
			(thermal_gap 0.5)
			(thermal_bridge_width 0.5)
			(island_removal_mode 0)
		)
		(polygon
			(pts
				(arc
					(start 405.354282 -159.97301)
					(mid 402.928074 -159.97301)
					(end 405.354282 -159.97301)
				)
			)
		)
	)
	(zone
		(layer "In4.Cu")
		(hatch none 0.5)
		(connect_pads
			(clearance 0)
		)
		(min_thickness 0.25)
		(keepout
			(tracks not_allowed)
			(vias allowed)
			(pads allowed)
			(copperpour not_allowed)
			(footprints allowed)
		)
		(placement
			(enabled no)
			(sheetname "")
		)
		(fill
			(thermal_gap 0.5)
			(thermal_bridge_width 0.5)
			(island_removal_mode 0)
		)
		(polygon
			(pts
				(arc
					(start 157.526736 -78.22565)
					(mid 155.748736 -78.22565)
					(end 157.526736 -78.22565)
				)
			)
		)
	)
	(zone
		(layer "In4.Cu")
		(hatch none 0.5)
		(connect_pads
			(clearance 0)
		)
		(min_thickness 0.25)
		(keepout
			(tracks not_allowed)
			(vias allowed)
			(pads allowed)
			(copperpour not_allowed)
			(footprints allowed)
		)
		(placement
			(enabled no)
			(sheetname "")
		)
		(fill
			(thermal_gap 0.5)
			(thermal_bridge_width 0.5)
			(island_removal_mode 0)
		)
		(polygon
			(pts
				(arc
					(start 275.3614 -82.296)
					(mid 273.5834 -82.296)
					(end 275.3614 -82.296)
				)
			)
		)
	)
	(zone
		(layer "In4.Cu")
		(hatch none 0.5)
		(connect_pads
			(clearance 0)
		)
		(min_thickness 0.25)
		(keepout
			(tracks not_allowed)
			(vias allowed)
			(pads allowed)
			(copperpour not_allowed)
			(footprints allowed)
		)
		(placement
			(enabled no)
			(sheetname "")
		)
		(fill
			(thermal_gap 0.5)
			(thermal_bridge_width 0.5)
			(island_removal_mode 0)
		)
		(polygon
			(pts
				(arc
					(start 168.275 -72.136)
					(mid 166.497 -72.136)
					(end 168.275 -72.136)
				)
			)
		)
	)
	(zone
		(layer "In4.Cu")
		(hatch none 0.5)
		(connect_pads
			(clearance 0)
		)
		(min_thickness 0.25)
		(keepout
			(tracks not_allowed)
			(vias allowed)
			(pads allowed)
			(copperpour not_allowed)
			(footprints allowed)
		)
		(placement
			(enabled no)
			(sheetname "")
		)
		(fill
			(thermal_gap 0.5)
			(thermal_bridge_width 0.5)
			(island_removal_mode 0)
		)
		(polygon
			(pts
				(arc
					(start 290.8554 -79.461106)
					(mid 289.0774 -79.461106)
					(end 290.8554 -79.461106)
				)
			)
		)
	)
	(zone
		(layer "In4.Cu")
		(hatch none 0.5)
		(connect_pads
			(clearance 0)
		)
		(min_thickness 0.25)
		(keepout
			(tracks not_allowed)
			(vias allowed)
			(pads allowed)
			(copperpour not_allowed)
			(footprints allowed)
		)
		(placement
			(enabled no)
			(sheetname "")
		)
		(fill
			(thermal_gap 0.5)
			(thermal_bridge_width 0.5)
			(island_removal_mode 0)
		)
		(polygon
			(pts
				(arc
					(start 68.212208 -169.97299)
					(mid 65.786 -169.97299)
					(end 68.212208 -169.97299)
				)
			)
		)
	)
	(zone
		(layer "In4.Cu")
		(hatch none 0.5)
		(connect_pads
			(clearance 0)
		)
		(min_thickness 0.25)
		(keepout
			(tracks not_allowed)
			(vias allowed)
			(pads allowed)
			(copperpour not_allowed)
			(footprints allowed)
		)
		(placement
			(enabled no)
			(sheetname "")
		)
		(fill
			(thermal_gap 0.5)
			(thermal_bridge_width 0.5)
			(island_removal_mode 0)
		)
		(polygon
			(pts
				(arc
					(start 143.892778 -30.093158)
					(mid 142.114778 -30.093158)
					(end 143.892778 -30.093158)
				)
			)
		)
	)
	(zone
		(layer "In4.Cu")
		(hatch none 0.5)
		(connect_pads
			(clearance 0)
		)
		(min_thickness 0.25)
		(keepout
			(tracks not_allowed)
			(vias allowed)
			(pads allowed)
			(copperpour not_allowed)
			(footprints allowed)
		)
		(placement
			(enabled no)
			(sheetname "")
		)
		(fill
			(thermal_gap 0.5)
			(thermal_bridge_width 0.5)
			(island_removal_mode 0)
		)
		(polygon
			(pts
				(arc
					(start 405.354282 -157.973014)
					(mid 402.928074 -157.973014)
					(end 405.354282 -157.973014)
				)
			)
		)
	)
	(zone
		(layer "In4.Cu")
		(hatch none 0.5)
		(connect_pads
			(clearance 0)
		)
		(min_thickness 0.25)
		(keepout
			(tracks not_allowed)
			(vias allowed)
			(pads allowed)
			(copperpour not_allowed)
			(footprints allowed)
		)
		(placement
			(enabled no)
			(sheetname "")
		)
		(fill
			(thermal_gap 0.5)
			(thermal_bridge_width 0.5)
			(island_removal_mode 0)
		)
		(polygon
			(pts
				(arc
					(start 51.124104 -167.591994)
					(mid 48.697896 -167.591994)
					(end 51.124104 -167.591994)
				)
			)
		)
	)
	(zone
		(layer "In4.Cu")
		(hatch none 0.5)
		(connect_pads
			(clearance 0)
		)
		(min_thickness 0.25)
		(keepout
			(tracks not_allowed)
			(vias allowed)
			(pads allowed)
			(copperpour not_allowed)
			(footprints allowed)
		)
		(placement
			(enabled no)
			(sheetname "")
		)
		(fill
			(thermal_gap 0.5)
			(thermal_bridge_width 0.5)
			(island_removal_mode 0)
		)
		(polygon
			(pts
				(arc
					(start 77.229208 -169.71899)
					(mid 74.803 -169.71899)
					(end 77.229208 -169.71899)
				)
			)
		)
	)
	(zone
		(layer "In4.Cu")
		(hatch none 0.5)
		(connect_pads
			(clearance 0)
		)
		(min_thickness 0.25)
		(keepout
			(tracks not_allowed)
			(vias allowed)
			(pads allowed)
			(copperpour not_allowed)
			(footprints allowed)
		)
		(placement
			(enabled no)
			(sheetname "")
		)
		(fill
			(thermal_gap 0.5)
			(thermal_bridge_width 0.5)
			(island_removal_mode 0)
		)
		(polygon
			(pts
				(arc
					(start 169.418 -79.121)
					(mid 167.64 -79.121)
					(end 169.418 -79.121)
				)
			)
		)
	)
	(zone
		(layer "In4.Cu")
		(hatch none 0.5)
		(connect_pads
			(clearance 0)
		)
		(min_thickness 0.25)
		(keepout
			(tracks not_allowed)
			(vias allowed)
			(pads allowed)
			(copperpour not_allowed)
			(footprints allowed)
		)
		(placement
			(enabled no)
			(sheetname "")
		)
		(fill
			(thermal_gap 0.5)
			(thermal_bridge_width 0.5)
			(island_removal_mode 0)
		)
		(polygon
			(pts
				(arc
					(start 41.822116 -161.973006)
					(mid 39.395908 -161.973006)
					(end 41.822116 -161.973006)
				)
			)
		)
	)
	(zone
		(layer "In4.Cu")
		(hatch none 0.5)
		(connect_pads
			(clearance 0)
		)
		(min_thickness 0.25)
		(keepout
			(tracks not_allowed)
			(vias allowed)
			(pads allowed)
			(copperpour not_allowed)
			(footprints allowed)
		)
		(placement
			(enabled no)
			(sheetname "")
		)
		(fill
			(thermal_gap 0.5)
			(thermal_bridge_width 0.5)
			(island_removal_mode 0)
		)
		(polygon
			(pts
				(arc
					(start 428.745904 -39.751)
					(mid 426.967904 -39.751)
					(end 428.745904 -39.751)
				)
			)
		)
	)
	(zone
		(layer "In4.Cu")
		(hatch none 0.5)
		(connect_pads
			(clearance 0)
		)
		(min_thickness 0.25)
		(keepout
			(tracks not_allowed)
			(vias allowed)
			(pads allowed)
			(copperpour not_allowed)
			(footprints allowed)
		)
		(placement
			(enabled no)
			(sheetname "")
		)
		(fill
			(thermal_gap 0.5)
			(thermal_bridge_width 0.5)
			(island_removal_mode 0)
		)
		(polygon
			(pts
				(arc
					(start 187.452 -78.08595)
					(mid 185.674 -78.08595)
					(end 187.452 -78.08595)
				)
			)
		)
	)
	(zone
		(layer "In4.Cu")
		(hatch none 0.5)
		(connect_pads
			(clearance 0)
		)
		(min_thickness 0.25)
		(keepout
			(tracks not_allowed)
			(vias allowed)
			(pads allowed)
			(copperpour not_allowed)
			(footprints allowed)
		)
		(placement
			(enabled no)
			(sheetname "")
		)
		(fill
			(thermal_gap 0.5)
			(thermal_bridge_width 0.5)
			(island_removal_mode 0)
		)
		(polygon
			(pts
				(arc
					(start 41.822116 -165.972998)
					(mid 39.395908 -165.972998)
					(end 41.822116 -165.972998)
				)
			)
		)
	)
	(zone
		(layer "In4.Cu")
		(hatch none 0.5)
		(connect_pads
			(clearance 0)
		)
		(min_thickness 0.25)
		(keepout
			(tracks not_allowed)
			(vias allowed)
			(pads allowed)
			(copperpour not_allowed)
			(footprints allowed)
		)
		(placement
			(enabled no)
			(sheetname "")
		)
		(fill
			(thermal_gap 0.5)
			(thermal_bridge_width 0.5)
			(island_removal_mode 0)
		)
		(polygon
			(pts
				(arc
					(start 169.06875 -78.359)
					(mid 167.29075 -78.359)
					(end 169.06875 -78.359)
				)
			)
		)
	)
	(zone
		(layer "In4.Cu")
		(hatch none 0.5)
		(connect_pads
			(clearance 0)
		)
		(min_thickness 0.25)
		(keepout
			(tracks not_allowed)
			(vias allowed)
			(pads allowed)
			(copperpour not_allowed)
			(footprints allowed)
		)
		(placement
			(enabled no)
			(sheetname "")
		)
		(fill
			(thermal_gap 0.5)
			(thermal_bridge_width 0.5)
			(island_removal_mode 0)
		)
		(polygon
			(pts
				(arc
					(start 263.9695 -74.739246)
					(mid 262.1915 -74.739246)
					(end 263.9695 -74.739246)
				)
			)
		)
	)
	(zone
		(layer "In4.Cu")
		(hatch none 0.5)
		(connect_pads
			(clearance 0)
		)
		(min_thickness 0.25)
		(keepout
			(tracks not_allowed)
			(vias allowed)
			(pads allowed)
			(copperpour not_allowed)
			(footprints allowed)
		)
		(placement
			(enabled no)
			(sheetname "")
		)
		(fill
			(thermal_gap 0.5)
			(thermal_bridge_width 0.5)
			(island_removal_mode 0)
		)
		(polygon
			(pts
				(arc
					(start 172.3644 -77.343)
					(mid 170.5864 -77.343)
					(end 172.3644 -77.343)
				)
			)
		)
	)
	(zone
		(layer "In4.Cu")
		(hatch none 0.5)
		(connect_pads
			(clearance 0)
		)
		(min_thickness 0.25)
		(keepout
			(tracks not_allowed)
			(vias allowed)
			(pads allowed)
			(copperpour not_allowed)
			(footprints allowed)
		)
		(placement
			(enabled no)
			(sheetname "")
		)
		(fill
			(thermal_gap 0.5)
			(thermal_bridge_width 0.5)
			(island_removal_mode 0)
		)
		(polygon
			(pts
				(arc
					(start 270.7894 -77.47)
					(mid 269.0114 -77.47)
					(end 270.7894 -77.47)
				)
			)
		)
	)
	(zone
		(layer "In4.Cu")
		(hatch none 0.5)
		(connect_pads
			(clearance 0)
		)
		(min_thickness 0.25)
		(keepout
			(tracks not_allowed)
			(vias allowed)
			(pads allowed)
			(copperpour not_allowed)
			(footprints allowed)
		)
		(placement
			(enabled no)
			(sheetname "")
		)
		(fill
			(thermal_gap 0.5)
			(thermal_bridge_width 0.5)
			(island_removal_mode 0)
		)
		(polygon
			(pts
				(arc
					(start 140.95222 -67.4624)
					(mid 139.17422 -67.4624)
					(end 140.95222 -67.4624)
				)
			)
		)
	)
	(zone
		(layer "In4.Cu")
		(hatch none 0.5)
		(connect_pads
			(clearance 0)
		)
		(min_thickness 0.25)
		(keepout
			(tracks not_allowed)
			(vias allowed)
			(pads allowed)
			(copperpour not_allowed)
			(footprints allowed)
		)
		(placement
			(enabled no)
			(sheetname "")
		)
		(fill
			(thermal_gap 0.5)
			(thermal_bridge_width 0.5)
			(island_removal_mode 0)
		)
		(polygon
			(pts
				(arc
					(start 169.0624 -77.343)
					(mid 167.2844 -77.343)
					(end 169.0624 -77.343)
				)
			)
		)
	)
	(zone
		(layer "In4.Cu")
		(hatch none 0.5)
		(connect_pads
			(clearance 0)
		)
		(min_thickness 0.25)
		(keepout
			(tracks not_allowed)
			(vias allowed)
			(pads allowed)
			(copperpour not_allowed)
			(footprints allowed)
		)
		(placement
			(enabled no)
			(sheetname "")
		)
		(fill
			(thermal_gap 0.5)
			(thermal_bridge_width 0.5)
			(island_removal_mode 0)
		)
		(polygon
			(pts
				(arc
					(start 143.892778 -28.987242)
					(mid 142.114778 -28.987242)
					(end 143.892778 -28.987242)
				)
			)
		)
	)
	(zone
		(layer "In4.Cu")
		(hatch none 0.5)
		(connect_pads
			(clearance 0)
		)
		(min_thickness 0.25)
		(keepout
			(tracks not_allowed)
			(vias allowed)
			(pads allowed)
			(copperpour not_allowed)
			(footprints allowed)
		)
		(placement
			(enabled no)
			(sheetname "")
		)
		(fill
			(thermal_gap 0.5)
			(thermal_bridge_width 0.5)
			(island_removal_mode 0)
		)
		(polygon
			(pts
				(arc
					(start 222.004382 -7.856728)
					(mid 220.226382 -7.856728)
					(end 222.004382 -7.856728)
				)
			)
		)
	)
	(zone
		(layer "In4.Cu")
		(hatch none 0.5)
		(connect_pads
			(clearance 0)
		)
		(min_thickness 0.25)
		(keepout
			(tracks not_allowed)
			(vias allowed)
			(pads allowed)
			(copperpour not_allowed)
			(footprints allowed)
		)
		(placement
			(enabled no)
			(sheetname "")
		)
		(fill
			(thermal_gap 0.5)
			(thermal_bridge_width 0.5)
			(island_removal_mode 0)
		)
		(polygon
			(pts
				(arc
					(start 143.892778 -63.925958)
					(mid 142.114778 -63.925958)
					(end 143.892778 -63.925958)
				)
			)
		)
	)
	(zone
		(layer "In4.Cu")
		(hatch none 0.5)
		(connect_pads
			(clearance 0)
		)
		(min_thickness 0.25)
		(keepout
			(tracks not_allowed)
			(vias allowed)
			(pads allowed)
			(copperpour not_allowed)
			(footprints allowed)
		)
		(placement
			(enabled no)
			(sheetname "")
		)
		(fill
			(thermal_gap 0.5)
			(thermal_bridge_width 0.5)
			(island_removal_mode 0)
		)
		(polygon
			(pts
				(arc
					(start 385.390136 -165.845998)
					(mid 382.963928 -165.845998)
					(end 385.390136 -165.845998)
				)
			)
		)
	)
	(zone
		(layer "In4.Cu")
		(hatch none 0.5)
		(connect_pads
			(clearance 0)
		)
		(min_thickness 0.25)
		(keepout
			(tracks not_allowed)
			(vias allowed)
			(pads allowed)
			(copperpour not_allowed)
			(footprints allowed)
		)
		(placement
			(enabled no)
			(sheetname "")
		)
		(fill
			(thermal_gap 0.5)
			(thermal_bridge_width 0.5)
			(island_removal_mode 0)
		)
		(polygon
			(pts
				(arc
					(start 291.2364 -81.28)
					(mid 289.4584 -81.28)
					(end 291.2364 -81.28)
				)
			)
		)
	)
	(zone
		(layer "In4.Cu")
		(hatch none 0.5)
		(connect_pads
			(clearance 0)
		)
		(min_thickness 0.25)
		(keepout
			(tracks not_allowed)
			(vias allowed)
			(pads allowed)
			(copperpour not_allowed)
			(footprints allowed)
		)
		(placement
			(enabled no)
			(sheetname "")
		)
		(fill
			(thermal_gap 0.5)
			(thermal_bridge_width 0.5)
			(island_removal_mode 0)
		)
		(polygon
			(pts
				(arc
					(start 143.42237 -40.077136)
					(mid 141.64437 -40.077136)
					(end 143.42237 -40.077136)
				)
			)
		)
	)
	(zone
		(layer "In4.Cu")
		(hatch none 0.5)
		(connect_pads
			(clearance 0)
		)
		(min_thickness 0.25)
		(keepout
			(tracks not_allowed)
			(vias allowed)
			(pads allowed)
			(copperpour not_allowed)
			(footprints allowed)
		)
		(placement
			(enabled no)
			(sheetname "")
		)
		(fill
			(thermal_gap 0.5)
			(thermal_bridge_width 0.5)
			(island_removal_mode 0)
		)
		(polygon
			(pts
				(arc
					(start 405.195278 -169.97299)
					(mid 402.76907 -169.97299)
					(end 405.195278 -169.97299)
				)
			)
		)
	)
	(zone
		(layer "In4.Cu")
		(hatch none 0.5)
		(connect_pads
			(clearance 0)
		)
		(min_thickness 0.25)
		(keepout
			(tracks not_allowed)
			(vias allowed)
			(pads allowed)
			(copperpour not_allowed)
			(footprints allowed)
		)
		(placement
			(enabled no)
			(sheetname "")
		)
		(fill
			(thermal_gap 0.5)
			(thermal_bridge_width 0.5)
			(island_removal_mode 0)
		)
		(polygon
			(pts
				(arc
					(start 71.063104 -165.718998)
					(mid 68.636896 -165.718998)
					(end 71.063104 -165.718998)
				)
			)
		)
	)
	(zone
		(layer "In4.Cu")
		(hatch none 0.5)
		(connect_pads
			(clearance 0)
		)
		(min_thickness 0.25)
		(keepout
			(tracks not_allowed)
			(vias allowed)
			(pads allowed)
			(copperpour not_allowed)
			(footprints allowed)
		)
		(placement
			(enabled no)
			(sheetname "")
		)
		(fill
			(thermal_gap 0.5)
			(thermal_bridge_width 0.5)
			(island_removal_mode 0)
		)
		(polygon
			(pts
				(arc
					(start 391.486136 -167.718994)
					(mid 389.059928 -167.718994)
					(end 391.486136 -167.718994)
				)
			)
		)
	)
	(zone
		(layer "In4.Cu")
		(hatch none 0.5)
		(connect_pads
			(clearance 0)
		)
		(min_thickness 0.25)
		(keepout
			(tracks not_allowed)
			(vias allowed)
			(pads allowed)
			(copperpour not_allowed)
			(footprints allowed)
		)
		(placement
			(enabled no)
			(sheetname "")
		)
		(fill
			(thermal_gap 0.5)
			(thermal_bridge_width 0.5)
			(island_removal_mode 0)
		)
		(polygon
			(pts
				(arc
					(start 73.386188 -3.559048)
					(mid 70.95998 -3.559048)
					(end 73.386188 -3.559048)
				)
			)
		)
	)
	(zone
		(layer "In4.Cu")
		(hatch none 0.5)
		(connect_pads
			(clearance 0)
		)
		(min_thickness 0.25)
		(keepout
			(tracks not_allowed)
			(vias allowed)
			(pads allowed)
			(copperpour not_allowed)
			(footprints allowed)
		)
		(placement
			(enabled no)
			(sheetname "")
		)
		(fill
			(thermal_gap 0.5)
			(thermal_bridge_width 0.5)
			(island_removal_mode 0)
		)
		(polygon
			(pts
				(arc
					(start 187.452 -78.88605)
					(mid 185.674 -78.88605)
					(end 187.452 -78.88605)
				)
			)
		)
	)
	(zone
		(layer "In4.Cu")
		(hatch none 0.5)
		(connect_pads
			(clearance 0)
		)
		(min_thickness 0.25)
		(keepout
			(tracks not_allowed)
			(vias allowed)
			(pads allowed)
			(copperpour not_allowed)
			(footprints allowed)
		)
		(placement
			(enabled no)
			(sheetname "")
		)
		(fill
			(thermal_gap 0.5)
			(thermal_bridge_width 0.5)
			(island_removal_mode 0)
		)
		(polygon
			(pts
				(arc
					(start 376.167142 -3.305048)
					(mid 373.740934 -3.305048)
					(end 376.167142 -3.305048)
				)
			)
		)
	)
	(zone
		(layer "In4.Cu")
		(hatch none 0.5)
		(connect_pads
			(clearance 0)
		)
		(min_thickness 0.25)
		(keepout
			(tracks not_allowed)
			(vias allowed)
			(pads allowed)
			(copperpour not_allowed)
			(footprints allowed)
		)
		(placement
			(enabled no)
			(sheetname "")
		)
		(fill
			(thermal_gap 0.5)
			(thermal_bridge_width 0.5)
			(island_removal_mode 0)
		)
		(polygon
			(pts
				(arc
					(start 167.894 -83.03895)
					(mid 166.116 -83.03895)
					(end 167.894 -83.03895)
				)
			)
		)
	)
	(zone
		(layer "In4.Cu")
		(hatch none 0.5)
		(connect_pads
			(clearance 0)
		)
		(min_thickness 0.25)
		(keepout
			(tracks not_allowed)
			(vias allowed)
			(pads allowed)
			(copperpour not_allowed)
			(footprints allowed)
		)
		(placement
			(enabled no)
			(sheetname "")
		)
		(fill
			(thermal_gap 0.5)
			(thermal_bridge_width 0.5)
			(island_removal_mode 0)
		)
		(polygon
			(pts
				(arc
					(start 158.923736 -78.232)
					(mid 157.145736 -78.232)
					(end 158.923736 -78.232)
				)
			)
		)
	)
	(zone
		(layer "In4.Cu")
		(hatch none 0.5)
		(connect_pads
			(clearance 0)
		)
		(min_thickness 0.25)
		(keepout
			(tracks not_allowed)
			(vias allowed)
			(pads allowed)
			(copperpour not_allowed)
			(footprints allowed)
		)
		(placement
			(enabled no)
			(sheetname "")
		)
		(fill
			(thermal_gap 0.5)
			(thermal_bridge_width 0.5)
			(island_removal_mode 0)
		)
		(polygon
			(pts
				(arc
					(start 280.9494 -75.184)
					(mid 279.1714 -75.184)
					(end 280.9494 -75.184)
				)
			)
		)
	)
	(zone
		(layer "In4.Cu")
		(hatch none 0.5)
		(connect_pads
			(clearance 0)
		)
		(min_thickness 0.25)
		(keepout
			(tracks not_allowed)
			(vias allowed)
			(pads allowed)
			(copperpour not_allowed)
			(footprints allowed)
		)
		(placement
			(enabled no)
			(sheetname "")
		)
		(fill
			(thermal_gap 0.5)
			(thermal_bridge_width 0.5)
			(island_removal_mode 0)
		)
		(polygon
			(pts
				(arc
					(start 41.822116 -163.973002)
					(mid 39.395908 -163.973002)
					(end 41.822116 -163.973002)
				)
			)
		)
	)
	(zone
		(layer "In4.Cu")
		(hatch none 0.5)
		(connect_pads
			(clearance 0)
		)
		(min_thickness 0.25)
		(keepout
			(tracks not_allowed)
			(vias allowed)
			(pads allowed)
			(copperpour not_allowed)
			(footprints allowed)
		)
		(placement
			(enabled no)
			(sheetname "")
		)
		(fill
			(thermal_gap 0.5)
			(thermal_bridge_width 0.5)
			(island_removal_mode 0)
		)
		(polygon
			(pts
				(arc
					(start 51.124104 -165.591998)
					(mid 48.697896 -165.591998)
					(end 51.124104 -165.591998)
				)
			)
		)
	)
	(zone
		(layer "In4.Cu")
		(hatch none 0.5)
		(connect_pads
			(clearance 0)
		)
		(min_thickness 0.25)
		(keepout
			(tracks not_allowed)
			(vias allowed)
			(pads allowed)
			(copperpour not_allowed)
			(footprints allowed)
		)
		(placement
			(enabled no)
			(sheetname "")
		)
		(fill
			(thermal_gap 0.5)
			(thermal_bridge_width 0.5)
			(island_removal_mode 0)
		)
		(polygon
			(pts
				(arc
					(start 405.354282 -167.972994)
					(mid 402.928074 -167.972994)
					(end 405.354282 -167.972994)
				)
			)
		)
	)
	(zone
		(layer "In4.Cu")
		(hatch none 0.5)
		(connect_pads
			(clearance 0)
		)
		(min_thickness 0.25)
		(keepout
			(tracks not_allowed)
			(vias allowed)
			(pads allowed)
			(copperpour not_allowed)
			(footprints allowed)
		)
		(placement
			(enabled no)
			(sheetname "")
		)
		(fill
			(thermal_gap 0.5)
			(thermal_bridge_width 0.5)
			(island_removal_mode 0)
		)
		(polygon
			(pts
				(arc
					(start 41.822116 -167.972994)
					(mid 39.395908 -167.972994)
					(end 41.822116 -167.972994)
				)
			)
		)
	)
	(zone
		(layer "In4.Cu")
		(hatch none 0.5)
		(connect_pads
			(clearance 0)
		)
		(min_thickness 0.25)
		(keepout
			(tracks not_allowed)
			(vias allowed)
			(pads allowed)
			(copperpour not_allowed)
			(footprints allowed)
		)
		(placement
			(enabled no)
			(sheetname "")
		)
		(fill
			(thermal_gap 0.5)
			(thermal_bridge_width 0.5)
			(island_removal_mode 0)
		)
		(polygon
			(pts
				(arc
					(start 41.822116 -159.97301)
					(mid 39.395908 -159.97301)
					(end 41.822116 -159.97301)
				)
			)
		)
	)
	(zone
		(layer "In4.Cu")
		(hatch none 0.5)
		(connect_pads
			(clearance 0)
		)
		(min_thickness 0.25)
		(keepout
			(tracks not_allowed)
			(vias allowed)
			(pads allowed)
			(copperpour not_allowed)
			(footprints allowed)
		)
		(placement
			(enabled no)
			(sheetname "")
		)
		(fill
			(thermal_gap 0.5)
			(thermal_bridge_width 0.5)
			(island_removal_mode 0)
		)
		(polygon
			(pts
				(arc
					(start 292.227 -86.995)
					(mid 290.449 -86.995)
					(end 292.227 -86.995)
				)
			)
		)
	)
	(zone
		(layer "In4.Cu")
		(hatch none 0.5)
		(connect_pads
			(clearance 0)
		)
		(min_thickness 0.25)
		(keepout
			(tracks not_allowed)
			(vias allowed)
			(pads allowed)
			(copperpour not_allowed)
			(footprints allowed)
		)
		(placement
			(enabled no)
			(sheetname "")
		)
		(fill
			(thermal_gap 0.5)
			(thermal_bridge_width 0.5)
			(island_removal_mode 0)
		)
		(polygon
			(pts
				(arc
					(start 57.093104 -167.591994)
					(mid 54.666896 -167.591994)
					(end 57.093104 -167.591994)
				)
			)
		)
	)
	(zone
		(layer "In4.Cu")
		(hatch none 0.5)
		(connect_pads
			(clearance 0)
		)
		(min_thickness 0.25)
		(keepout
			(tracks not_allowed)
			(vias allowed)
			(pads allowed)
			(copperpour not_allowed)
			(footprints allowed)
		)
		(placement
			(enabled no)
			(sheetname "")
		)
		(fill
			(thermal_gap 0.5)
			(thermal_bridge_width 0.5)
			(island_removal_mode 0)
		)
		(polygon
			(pts
				(arc
					(start 308.356 -33.6296)
					(mid 306.578 -33.6296)
					(end 308.356 -33.6296)
				)
			)
		)
	)
	(zone
		(layer "In4.Cu")
		(hatch none 0.5)
		(connect_pads
			(clearance 0)
		)
		(min_thickness 0.25)
		(keepout
			(tracks not_allowed)
			(vias allowed)
			(pads allowed)
			(copperpour not_allowed)
			(footprints allowed)
		)
		(placement
			(enabled no)
			(sheetname "")
		)
		(fill
			(thermal_gap 0.5)
			(thermal_bridge_width 0.5)
			(island_removal_mode 0)
		)
		(polygon
			(pts
				(arc
					(start 405.354282 -165.972998)
					(mid 402.928074 -165.972998)
					(end 405.354282 -165.972998)
				)
			)
		)
	)
	(zone
		(layer "In4.Cu")
		(hatch none 0.5)
		(connect_pads
			(clearance 0)
		)
		(min_thickness 0.25)
		(keepout
			(tracks not_allowed)
			(vias allowed)
			(pads allowed)
			(copperpour not_allowed)
			(footprints allowed)
		)
		(placement
			(enabled no)
			(sheetname "")
		)
		(fill
			(thermal_gap 0.5)
			(thermal_bridge_width 0.5)
			(island_removal_mode 0)
		)
		(polygon
			(pts
				(arc
					(start 69.609208 -170.09999)
					(mid 67.183 -170.09999)
					(end 69.609208 -170.09999)
				)
			)
		)
	)
	(zone
		(layer "In4.Cu")
		(hatch none 0.5)
		(connect_pads
			(clearance 0)
		)
		(min_thickness 0.25)
		(keepout
			(tracks not_allowed)
			(vias allowed)
			(pads allowed)
			(copperpour not_allowed)
			(footprints allowed)
		)
		(placement
			(enabled no)
			(sheetname "")
		)
		(fill
			(thermal_gap 0.5)
			(thermal_bridge_width 0.5)
			(island_removal_mode 0)
		)
		(polygon
			(pts
				(arc
					(start 170.561 -79.121)
					(mid 168.783 -79.121)
					(end 170.561 -79.121)
				)
			)
		)
	)
	(zone
		(layer "In4.Cu")
		(hatch none 0.5)
		(connect_pads
			(clearance 0)
		)
		(min_thickness 0.25)
		(keepout
			(tracks not_allowed)
			(vias allowed)
			(pads allowed)
			(copperpour not_allowed)
			(footprints allowed)
		)
		(placement
			(enabled no)
			(sheetname "")
		)
		(fill
			(thermal_gap 0.5)
			(thermal_bridge_width 0.5)
			(island_removal_mode 0)
		)
		(polygon
			(pts
				(arc
					(start 305.505358 -30.093158)
					(mid 303.727358 -30.093158)
					(end 305.505358 -30.093158)
				)
			)
		)
	)
	(zone
		(layer "In4.Cu")
		(hatch none 0.5)
		(connect_pads
			(clearance 0)
		)
		(min_thickness 0.25)
		(keepout
			(tracks not_allowed)
			(vias allowed)
			(pads allowed)
			(copperpour not_allowed)
			(footprints allowed)
		)
		(placement
			(enabled no)
			(sheetname "")
		)
		(fill
			(thermal_gap 0.5)
			(thermal_bridge_width 0.5)
			(island_removal_mode 0)
		)
		(polygon
			(pts
				(arc
					(start 183.642 -80.137)
					(mid 181.864 -80.137)
					(end 183.642 -80.137)
				)
			)
		)
	)
	(zone
		(layer "In4.Cu")
		(hatch none 0.5)
		(connect_pads
			(clearance 0)
		)
		(min_thickness 0.25)
		(keepout
			(tracks not_allowed)
			(vias allowed)
			(pads allowed)
			(copperpour not_allowed)
			(footprints allowed)
		)
		(placement
			(enabled no)
			(sheetname "")
		)
		(fill
			(thermal_gap 0.5)
			(thermal_bridge_width 0.5)
			(island_removal_mode 0)
		)
		(polygon
			(pts
				(arc
					(start 287.9344 -77.514196)
					(mid 286.1564 -77.514196)
					(end 287.9344 -77.514196)
				)
			)
		)
	)
	(zone
		(layer "In4.Cu")
		(hatch none 0.5)
		(connect_pads
			(clearance 0)
		)
		(min_thickness 0.25)
		(keepout
			(tracks not_allowed)
			(vias allowed)
			(pads allowed)
			(copperpour not_allowed)
			(footprints allowed)
		)
		(placement
			(enabled no)
			(sheetname "")
		)
		(fill
			(thermal_gap 0.5)
			(thermal_bridge_width 0.5)
			(island_removal_mode 0)
		)
		(polygon
			(pts
				(arc
					(start 147.311618 -67.4624)
					(mid 145.533618 -67.4624)
					(end 147.311618 -67.4624)
				)
			)
		)
	)
	(zone
		(layer "In4.Cu")
		(hatch none 0.5)
		(connect_pads
			(clearance 0)
		)
		(min_thickness 0.25)
		(keepout
			(tracks not_allowed)
			(vias allowed)
			(pads allowed)
			(copperpour not_allowed)
			(footprints allowed)
		)
		(placement
			(enabled no)
			(sheetname "")
		)
		(fill
			(thermal_gap 0.5)
			(thermal_bridge_width 0.5)
			(island_removal_mode 0)
		)
		(polygon
			(pts
				(arc
					(start 391.486136 -165.718998)
					(mid 389.059928 -165.718998)
					(end 391.486136 -165.718998)
				)
			)
		)
	)
	(zone
		(layer "In4.Cu")
		(hatch none 0.5)
		(connect_pads
			(clearance 0)
		)
		(min_thickness 0.25)
		(keepout
			(tracks not_allowed)
			(vias allowed)
			(pads allowed)
			(copperpour not_allowed)
			(footprints allowed)
		)
		(placement
			(enabled no)
			(sheetname "")
		)
		(fill
			(thermal_gap 0.5)
			(thermal_bridge_width 0.5)
			(island_removal_mode 0)
		)
		(polygon
			(pts
				(arc
					(start 77.032104 -165.845998)
					(mid 74.605896 -165.845998)
					(end 77.032104 -165.845998)
				)
			)
		)
	)
	(zone
		(layer "In4.Cu")
		(hatch none 0.5)
		(connect_pads
			(clearance 0)
		)
		(min_thickness 0.25)
		(keepout
			(tracks not_allowed)
			(vias allowed)
			(pads allowed)
			(copperpour not_allowed)
			(footprints allowed)
		)
		(placement
			(enabled no)
			(sheetname "")
		)
		(fill
			(thermal_gap 0.5)
			(thermal_bridge_width 0.5)
			(island_removal_mode 0)
		)
		(polygon
			(pts
				(arc
					(start 74.816208 -1.44399)
					(mid 72.39 -1.44399)
					(end 74.816208 -1.44399)
				)
			)
		)
	)
	(zone
		(layer "In4.Cu")
		(hatch none 0.5)
		(connect_pads
			(clearance 0)
		)
		(min_thickness 0.25)
		(keepout
			(tracks not_allowed)
			(vias allowed)
			(pads allowed)
			(copperpour not_allowed)
			(footprints allowed)
		)
		(placement
			(enabled no)
			(sheetname "")
		)
		(fill
			(thermal_gap 0.5)
			(thermal_bridge_width 0.5)
			(island_removal_mode 0)
		)
		(polygon
			(pts
				(arc
					(start 294.9702 -79.2607)
					(mid 293.1922 -79.2607)
					(end 294.9702 -79.2607)
				)
			)
		)
	)
	(zone
		(layer "In4.Cu")
		(hatch none 0.5)
		(connect_pads
			(clearance 0)
		)
		(min_thickness 0.25)
		(keepout
			(tracks not_allowed)
			(vias allowed)
			(pads allowed)
			(copperpour not_allowed)
			(footprints allowed)
		)
		(placement
			(enabled no)
			(sheetname "")
		)
		(fill
			(thermal_gap 0.5)
			(thermal_bridge_width 0.5)
			(island_removal_mode 0)
		)
		(polygon
			(pts
				(arc
					(start 319.90665 -83.82)
					(mid 318.12865 -83.82)
					(end 319.90665 -83.82)
				)
			)
		)
	)
	(zone
		(layer "In4.Cu")
		(hatch none 0.5)
		(connect_pads
			(clearance 0)
		)
		(min_thickness 0.25)
		(keepout
			(tracks not_allowed)
			(vias allowed)
			(pads allowed)
			(copperpour not_allowed)
			(footprints allowed)
		)
		(placement
			(enabled no)
			(sheetname "")
		)
		(fill
			(thermal_gap 0.5)
			(thermal_bridge_width 0.5)
			(island_removal_mode 0)
		)
		(polygon
			(pts
				(arc
					(start 377.262136 -165.591998)
					(mid 374.835928 -165.591998)
					(end 377.262136 -165.591998)
				)
			)
		)
	)
	(zone
		(layer "In4.Cu")
		(hatch none 0.5)
		(connect_pads
			(clearance 0)
		)
		(min_thickness 0.25)
		(keepout
			(tracks not_allowed)
			(vias allowed)
			(pads allowed)
			(copperpour not_allowed)
			(footprints allowed)
		)
		(placement
			(enabled no)
			(sheetname "")
		)
		(fill
			(thermal_gap 0.5)
			(thermal_bridge_width 0.5)
			(island_removal_mode 0)
		)
		(polygon
			(pts
				(arc
					(start 272.71345 -77.21092)
					(mid 270.93545 -77.21092)
					(end 272.71345 -77.21092)
				)
			)
		)
	)
	(zone
		(layer "In4.Cu")
		(hatch none 0.5)
		(connect_pads
			(clearance 0)
		)
		(min_thickness 0.25)
		(keepout
			(tracks not_allowed)
			(vias allowed)
			(pads allowed)
			(copperpour not_allowed)
			(footprints allowed)
		)
		(placement
			(enabled no)
			(sheetname "")
		)
		(fill
			(thermal_gap 0.5)
			(thermal_bridge_width 0.5)
			(island_removal_mode 0)
		)
		(polygon
			(pts
				(arc
					(start 143.84782 -33.8582)
					(mid 142.06982 -33.8582)
					(end 143.84782 -33.8582)
				)
			)
		)
	)
	(zone
		(layer "In4.Cu")
		(hatch none 0.5)
		(connect_pads
			(clearance 0)
		)
		(min_thickness 0.25)
		(keepout
			(tracks not_allowed)
			(vias allowed)
			(pads allowed)
			(copperpour not_allowed)
			(footprints allowed)
		)
		(placement
			(enabled no)
			(sheetname "")
		)
		(fill
			(thermal_gap 0.5)
			(thermal_bridge_width 0.5)
			(island_removal_mode 0)
		)
		(polygon
			(pts
				(arc
					(start 176.595786 -78.486)
					(mid 174.817786 -78.486)
					(end 176.595786 -78.486)
				)
			)
		)
	)
	(zone
		(layer "In4.Cu")
		(hatch none 0.5)
		(connect_pads
			(clearance 0)
		)
		(min_thickness 0.25)
		(keepout
			(tracks not_allowed)
			(vias allowed)
			(pads allowed)
			(copperpour not_allowed)
			(footprints allowed)
		)
		(placement
			(enabled no)
			(sheetname "")
		)
		(fill
			(thermal_gap 0.5)
			(thermal_bridge_width 0.5)
			(island_removal_mode 0)
		)
		(polygon
			(pts
				(arc
					(start 165.749986 -79.756)
					(mid 163.971986 -79.756)
					(end 165.749986 -79.756)
				)
			)
		)
	)
	(zone
		(layer "In4.Cu")
		(hatch none 0.5)
		(connect_pads
			(clearance 0)
		)
		(min_thickness 0.25)
		(keepout
			(tracks not_allowed)
			(vias allowed)
			(pads allowed)
			(copperpour not_allowed)
			(footprints allowed)
		)
		(placement
			(enabled no)
			(sheetname "")
		)
		(fill
			(thermal_gap 0.5)
			(thermal_bridge_width 0.5)
			(island_removal_mode 0)
		)
		(polygon
			(pts
				(arc
					(start 286.1564 -81.153)
					(mid 284.3784 -81.153)
					(end 286.1564 -81.153)
				)
			)
		)
	)
	(zone
		(layer "In4.Cu")
		(hatch none 0.5)
		(connect_pads
			(clearance 0)
		)
		(min_thickness 0.25)
		(keepout
			(tracks not_allowed)
			(vias allowed)
			(pads allowed)
			(copperpour not_allowed)
			(footprints allowed)
		)
		(placement
			(enabled no)
			(sheetname "")
		)
		(fill
			(thermal_gap 0.5)
			(thermal_bridge_width 0.5)
			(island_removal_mode 0)
		)
		(polygon
			(pts
				(arc
					(start 143.892778 -62.820042)
					(mid 142.114778 -62.820042)
					(end 143.892778 -62.820042)
				)
			)
		)
	)
	(zone
		(layer "In4.Cu")
		(hatch none 0.5)
		(connect_pads
			(clearance 0)
		)
		(min_thickness 0.25)
		(keepout
			(tracks not_allowed)
			(vias allowed)
			(pads allowed)
			(copperpour not_allowed)
			(footprints allowed)
		)
		(placement
			(enabled no)
			(sheetname "")
		)
		(fill
			(thermal_gap 0.5)
			(thermal_bridge_width 0.5)
			(island_removal_mode 0)
		)
		(polygon
			(pts
				(arc
					(start 296.94505 -86.487)
					(mid 295.16705 -86.487)
					(end 296.94505 -86.487)
				)
			)
		)
	)
	(zone
		(layer "In4.Cu")
		(hatch none 0.5)
		(connect_pads
			(clearance 0)
		)
		(min_thickness 0.25)
		(keepout
			(tracks not_allowed)
			(vias allowed)
			(pads allowed)
			(copperpour not_allowed)
			(footprints allowed)
		)
		(placement
			(enabled no)
			(sheetname "")
		)
		(fill
			(thermal_gap 0.5)
			(thermal_bridge_width 0.5)
			(island_removal_mode 0)
		)
		(polygon
			(pts
				(arc
					(start 305.505358 -63.925958)
					(mid 303.727358 -63.925958)
					(end 305.505358 -63.925958)
				)
			)
		)
	)
	(zone
		(layer "In4.Cu")
		(hatch none 0.5)
		(connect_pads
			(clearance 0)
		)
		(min_thickness 0.25)
		(keepout
			(tracks not_allowed)
			(vias allowed)
			(pads allowed)
			(copperpour not_allowed)
			(footprints allowed)
		)
		(placement
			(enabled no)
			(sheetname "")
		)
		(fill
			(thermal_gap 0.5)
			(thermal_bridge_width 0.5)
			(island_removal_mode 0)
		)
		(polygon
			(pts
				(arc
					(start 371.166136 -167.591994)
					(mid 368.739928 -167.591994)
					(end 371.166136 -167.591994)
				)
			)
		)
	)
	(zone
		(layer "In4.Cu")
		(hatch none 0.5)
		(connect_pads
			(clearance 0)
		)
		(min_thickness 0.25)
		(keepout
			(tracks not_allowed)
			(vias allowed)
			(pads allowed)
			(copperpour not_allowed)
			(footprints allowed)
		)
		(placement
			(enabled no)
			(sheetname "")
		)
		(fill
			(thermal_gap 0.5)
			(thermal_bridge_width 0.5)
			(island_removal_mode 0)
		)
		(polygon
			(pts
				(arc
					(start 273.3294 -82.296)
					(mid 271.5514 -82.296)
					(end 273.3294 -82.296)
				)
			)
		)
	)
	(zone
		(layer "In4.Cu")
		(hatch none 0.5)
		(connect_pads
			(clearance 0)
		)
		(min_thickness 0.25)
		(keepout
			(tracks not_allowed)
			(vias allowed)
			(pads allowed)
			(copperpour not_allowed)
			(footprints allowed)
		)
		(placement
			(enabled no)
			(sheetname "")
		)
		(fill
			(thermal_gap 0.5)
			(thermal_bridge_width 0.5)
			(island_removal_mode 0)
		)
		(polygon
			(pts
				(arc
					(start 305.83505 -40.077136)
					(mid 304.05705 -40.077136)
					(end 305.83505 -40.077136)
				)
			)
		)
	)
	(zone
		(layer "In4.Cu")
		(hatch none 0.5)
		(connect_pads
			(clearance 0)
		)
		(min_thickness 0.25)
		(keepout
			(tracks not_allowed)
			(vias allowed)
			(pads allowed)
			(copperpour not_allowed)
			(footprints allowed)
		)
		(placement
			(enabled no)
			(sheetname "")
		)
		(fill
			(thermal_gap 0.5)
			(thermal_bridge_width 0.5)
			(island_removal_mode 0)
		)
		(polygon
			(pts
				(arc
					(start 41.822116 -155.973018)
					(mid 39.395908 -155.973018)
					(end 41.822116 -155.973018)
				)
			)
		)
	)
	(zone
		(layer "In4.Cu")
		(hatch none 0.5)
		(connect_pads
			(clearance 0)
		)
		(min_thickness 0.25)
		(keepout
			(tracks not_allowed)
			(vias allowed)
			(pads allowed)
			(copperpour not_allowed)
			(footprints allowed)
		)
		(placement
			(enabled no)
			(sheetname "")
		)
		(fill
			(thermal_gap 0.5)
			(thermal_bridge_width 0.5)
			(island_removal_mode 0)
		)
		(polygon
			(pts
				(arc
					(start 168.702736 -66.675)
					(mid 166.924736 -66.675)
					(end 168.702736 -66.675)
				)
			)
		)
	)
	(zone
		(layer "In4.Cu")
		(hatch none 0.5)
		(connect_pads
			(clearance 0)
		)
		(min_thickness 0.25)
		(keepout
			(tracks not_allowed)
			(vias allowed)
			(pads allowed)
			(copperpour not_allowed)
			(footprints allowed)
		)
		(placement
			(enabled no)
			(sheetname "")
		)
		(fill
			(thermal_gap 0.5)
			(thermal_bridge_width 0.5)
			(island_removal_mode 0)
		)
		(polygon
			(pts
				(arc
					(start 317.086996 -83.82)
					(mid 315.308996 -83.82)
					(end 317.086996 -83.82)
				)
			)
		)
	)
	(zone
		(layer "In4.Cu")
		(hatch none 0.5)
		(connect_pads
			(clearance 0)
		)
		(min_thickness 0.25)
		(keepout
			(tracks not_allowed)
			(vias allowed)
			(pads allowed)
			(copperpour not_allowed)
			(footprints allowed)
		)
		(placement
			(enabled no)
			(sheetname "")
		)
		(fill
			(thermal_gap 0.5)
			(thermal_bridge_width 0.5)
			(island_removal_mode 0)
		)
		(polygon
			(pts
				(arc
					(start 302.5648 -33.6296)
					(mid 300.7868 -33.6296)
					(end 302.5648 -33.6296)
				)
			)
		)
	)
	(zone
		(layer "In4.Cu")
		(hatch none 0.5)
		(connect_pads
			(clearance 0)
		)
		(min_thickness 0.25)
		(keepout
			(tracks not_allowed)
			(vias allowed)
			(pads allowed)
			(copperpour not_allowed)
			(footprints allowed)
		)
		(placement
			(enabled no)
			(sheetname "")
		)
		(fill
			(thermal_gap 0.5)
			(thermal_bridge_width 0.5)
			(island_removal_mode 0)
		)
		(polygon
			(pts
				(arc
					(start 413.512 -44.45)
					(mid 411.734 -44.45)
					(end 413.512 -44.45)
				)
			)
		)
	)
	(zone
		(layer "In4.Cu")
		(hatch none 0.5)
		(connect_pads
			(clearance 0)
		)
		(min_thickness 0.25)
		(keepout
			(tracks not_allowed)
			(vias allowed)
			(pads allowed)
			(copperpour not_allowed)
			(footprints allowed)
		)
		(placement
			(enabled no)
			(sheetname "")
		)
		(fill
			(thermal_gap 0.5)
			(thermal_bridge_width 0.5)
			(island_removal_mode 0)
		)
		(polygon
			(pts
				(arc
					(start 65.221104 -165.718998)
					(mid 62.794896 -165.718998)
					(end 65.221104 -165.718998)
				)
			)
		)
	)
	(zone
		(layer "In4.Cu")
		(hatch none 0.5)
		(connect_pads
			(clearance 0)
		)
		(min_thickness 0.25)
		(keepout
			(tracks not_allowed)
			(vias allowed)
			(pads allowed)
			(copperpour not_allowed)
			(footprints allowed)
		)
		(placement
			(enabled no)
			(sheetname "")
		)
		(fill
			(thermal_gap 0.5)
			(thermal_bridge_width 0.5)
			(island_removal_mode 0)
		)
		(polygon
			(pts
				(arc
					(start 285.6484 -76.327)
					(mid 283.8704 -76.327)
					(end 285.6484 -76.327)
				)
			)
		)
	)
	(zone
		(layer "In4.Cu")
		(hatch none 0.5)
		(connect_pads
			(clearance 0)
		)
		(min_thickness 0.25)
		(keepout
			(tracks not_allowed)
			(vias allowed)
			(pads allowed)
			(copperpour not_allowed)
			(footprints allowed)
		)
		(placement
			(enabled no)
			(sheetname "")
		)
		(fill
			(thermal_gap 0.5)
			(thermal_bridge_width 0.5)
			(island_removal_mode 0)
		)
		(polygon
			(pts
				(arc
					(start 285.6484 -75.184)
					(mid 283.8704 -75.184)
					(end 285.6484 -75.184)
				)
			)
		)
	)
	(zone
		(layer "In4.Cu")
		(hatch none 0.5)
		(connect_pads
			(clearance 0)
		)
		(min_thickness 0.25)
		(keepout
			(tracks not_allowed)
			(vias allowed)
			(pads allowed)
			(copperpour not_allowed)
			(footprints allowed)
		)
		(placement
			(enabled no)
			(sheetname "")
		)
		(fill
			(thermal_gap 0.5)
			(thermal_bridge_width 0.5)
			(island_removal_mode 0)
		)
		(polygon
			(pts
				(arc
					(start 283.337 -75.184)
					(mid 281.559 -75.184)
					(end 283.337 -75.184)
				)
			)
		)
	)
	(zone
		(layer "In4.Cu")
		(hatch none 0.5)
		(connect_pads
			(clearance 0)
		)
		(min_thickness 0.25)
		(keepout
			(tracks not_allowed)
			(vias allowed)
			(pads allowed)
			(copperpour not_allowed)
			(footprints allowed)
		)
		(placement
			(enabled no)
			(sheetname "")
		)
		(fill
			(thermal_gap 0.5)
			(thermal_bridge_width 0.5)
			(island_removal_mode 0)
		)
		(polygon
			(pts
				(arc
					(start 377.262136 -167.591994)
					(mid 374.835928 -167.591994)
					(end 377.262136 -167.591994)
				)
			)
		)
	)
	(zone
		(layer "In4.Cu")
		(hatch none 0.5)
		(connect_pads
			(clearance 0)
		)
		(min_thickness 0.25)
		(keepout
			(tracks not_allowed)
			(vias allowed)
			(pads allowed)
			(copperpour not_allowed)
			(footprints allowed)
		)
		(placement
			(enabled no)
			(sheetname "")
		)
		(fill
			(thermal_gap 0.5)
			(thermal_bridge_width 0.5)
			(island_removal_mode 0)
		)
		(polygon
			(pts
				(arc
					(start 375.024142 -4.575048)
					(mid 372.597934 -4.575048)
					(end 375.024142 -4.575048)
				)
			)
		)
	)
	(zone
		(layer "In4.Cu")
		(hatch none 0.5)
		(connect_pads
			(clearance 0)
		)
		(min_thickness 0.25)
		(keepout
			(tracks not_allowed)
			(vias allowed)
			(pads allowed)
			(copperpour not_allowed)
			(footprints allowed)
		)
		(placement
			(enabled no)
			(sheetname "")
		)
		(fill
			(thermal_gap 0.5)
			(thermal_bridge_width 0.5)
			(island_removal_mode 0)
		)
		(polygon
			(pts
				(arc
					(start 167.832786 -66.802)
					(mid 166.054786 -66.802)
					(end 167.832786 -66.802)
				)
			)
		)
	)
	(zone
		(layer "In4.Cu")
		(hatch none 0.5)
		(connect_pads
			(clearance 0)
		)
		(min_thickness 0.25)
		(keepout
			(tracks not_allowed)
			(vias allowed)
			(pads allowed)
			(copperpour not_allowed)
			(footprints allowed)
		)
		(placement
			(enabled no)
			(sheetname "")
		)
		(fill
			(thermal_gap 0.5)
			(thermal_bridge_width 0.5)
			(island_removal_mode 0)
		)
		(polygon
			(pts
				(arc
					(start 41.822116 -157.973014)
					(mid 39.395908 -157.973014)
					(end 41.822116 -157.973014)
				)
			)
		)
	)
	(zone
		(layer "In4.Cu")
		(hatch none 0.5)
		(connect_pads
			(clearance 0)
		)
		(min_thickness 0.25)
		(keepout
			(tracks not_allowed)
			(vias allowed)
			(pads allowed)
			(copperpour not_allowed)
			(footprints allowed)
		)
		(placement
			(enabled no)
			(sheetname "")
		)
		(fill
			(thermal_gap 0.5)
			(thermal_bridge_width 0.5)
			(island_removal_mode 0)
		)
		(polygon
			(pts
				(arc
					(start 406.338278 -169.71899)
					(mid 403.91207 -169.71899)
					(end 406.338278 -169.71899)
				)
			)
		)
	)
	(zone
		(layer "In4.Cu")
		(hatch none 0.5)
		(connect_pads
			(clearance 0)
		)
		(min_thickness 0.25)
		(keepout
			(tracks not_allowed)
			(vias allowed)
			(pads allowed)
			(copperpour not_allowed)
			(footprints allowed)
		)
		(placement
			(enabled no)
			(sheetname "")
		)
		(fill
			(thermal_gap 0.5)
			(thermal_bridge_width 0.5)
			(island_removal_mode 0)
		)
		(polygon
			(pts
				(arc
					(start 171.323 -80.20304)
					(mid 169.545 -80.20304)
					(end 171.323 -80.20304)
				)
			)
		)
	)
	(zone
		(layer "In4.Cu")
		(hatch none 0.5)
		(connect_pads
			(clearance 0)
		)
		(min_thickness 0.25)
		(keepout
			(tracks not_allowed)
			(vias allowed)
			(pads allowed)
			(copperpour not_allowed)
			(footprints allowed)
		)
		(placement
			(enabled no)
			(sheetname "")
		)
		(fill
			(thermal_gap 0.5)
			(thermal_bridge_width 0.5)
			(island_removal_mode 0)
		)
		(polygon
			(pts
				(arc
					(start 293.878 -86.995)
					(mid 292.1 -86.995)
					(end 293.878 -86.995)
				)
			)
		)
	)
	(zone
		(layer "In4.Cu")
		(hatch none 0.5)
		(connect_pads
			(clearance 0)
		)
		(min_thickness 0.25)
		(keepout
			(tracks not_allowed)
			(vias allowed)
			(pads allowed)
			(copperpour not_allowed)
			(footprints allowed)
		)
		(placement
			(enabled no)
			(sheetname "")
		)
		(fill
			(thermal_gap 0.5)
			(thermal_bridge_width 0.5)
			(island_removal_mode 0)
		)
		(polygon
			(pts
				(arc
					(start 140.95222 -33.6296)
					(mid 139.17422 -33.6296)
					(end 140.95222 -33.6296)
				)
			)
		)
	)
	(zone
		(layer "In4.Cu")
		(hatch none 0.5)
		(connect_pads
			(clearance 0)
		)
		(min_thickness 0.25)
		(keepout
			(tracks not_allowed)
			(vias allowed)
			(pads allowed)
			(copperpour not_allowed)
			(footprints allowed)
		)
		(placement
			(enabled no)
			(sheetname "")
		)
		(fill
			(thermal_gap 0.5)
			(thermal_bridge_width 0.5)
			(island_removal_mode 0)
		)
		(polygon
			(pts
				(arc
					(start 405.354282 -155.973018)
					(mid 402.928074 -155.973018)
					(end 405.354282 -155.973018)
				)
			)
		)
	)
	(zone
		(layer "In4.Cu")
		(hatch none 0.5)
		(connect_pads
			(clearance 0)
		)
		(min_thickness 0.25)
		(keepout
			(tracks not_allowed)
			(vias allowed)
			(pads allowed)
			(copperpour not_allowed)
			(footprints allowed)
		)
		(placement
			(enabled no)
			(sheetname "")
		)
		(fill
			(thermal_gap 0.5)
			(thermal_bridge_width 0.5)
			(island_removal_mode 0)
		)
		(polygon
			(pts
				(arc
					(start 302.5648 -67.4624)
					(mid 300.7868 -67.4624)
					(end 302.5648 -67.4624)
				)
			)
		)
	)
	(zone
		(layer "In4.Cu")
		(hatch none 0.5)
		(connect_pads
			(clearance 0)
		)
		(min_thickness 0.25)
		(keepout
			(tracks not_allowed)
			(vias allowed)
			(pads allowed)
			(copperpour not_allowed)
			(footprints allowed)
		)
		(placement
			(enabled no)
			(sheetname "")
		)
		(fill
			(thermal_gap 0.5)
			(thermal_bridge_width 0.5)
			(island_removal_mode 0)
		)
		(polygon
			(pts
				(arc
					(start 405.354282 -161.973006)
					(mid 402.928074 -161.973006)
					(end 405.354282 -161.973006)
				)
			)
		)
	)
	(zone
		(layer "In4.Cu")
		(hatch none 0.5)
		(connect_pads
			(clearance 0)
		)
		(min_thickness 0.25)
		(keepout
			(tracks not_allowed)
			(vias allowed)
			(pads allowed)
			(copperpour not_allowed)
			(footprints allowed)
		)
		(placement
			(enabled no)
			(sheetname "")
		)
		(fill
			(thermal_gap 0.5)
			(thermal_bridge_width 0.5)
			(island_removal_mode 0)
		)
		(polygon
			(pts
				(arc
					(start 143.84782 -36.5252)
					(mid 142.06982 -36.5252)
					(end 143.84782 -36.5252)
				)
			)
		)
	)
	(zone
		(layer "In4.Cu")
		(hatch none 0.5)
		(connect_pads
			(clearance 0)
		)
		(min_thickness 0.25)
		(keepout
			(tracks not_allowed)
			(vias allowed)
			(pads allowed)
			(copperpour not_allowed)
			(footprints allowed)
		)
		(placement
			(enabled no)
			(sheetname "")
		)
		(fill
			(thermal_gap 0.5)
			(thermal_bridge_width 0.5)
			(island_removal_mode 0)
		)
		(polygon
			(pts
				(arc
					(start 155.386786 -77.47)
					(mid 153.608786 -77.47)
					(end 155.386786 -77.47)
				)
			)
		)
	)
	(zone
		(layer "In4.Cu")
		(hatch none 0.5)
		(connect_pads
			(clearance 0)
		)
		(min_thickness 0.25)
		(keepout
			(tracks not_allowed)
			(vias allowed)
			(pads allowed)
			(copperpour not_allowed)
			(footprints allowed)
		)
		(placement
			(enabled no)
			(sheetname "")
		)
		(fill
			(thermal_gap 0.5)
			(thermal_bridge_width 0.5)
			(island_removal_mode 0)
		)
		(polygon
			(pts
				(arc
					(start 168.25595 -81.28)
					(mid 166.47795 -81.28)
					(end 168.25595 -81.28)
				)
			)
		)
	)
	(zone
		(layer "In4.Cu")
		(hatch none 0.5)
		(connect_pads
			(clearance 0)
		)
		(min_thickness 0.25)
		(keepout
			(tracks not_allowed)
			(vias allowed)
			(pads allowed)
			(copperpour not_allowed)
			(footprints allowed)
		)
		(placement
			(enabled no)
			(sheetname "")
		)
		(fill
			(thermal_gap 0.5)
			(thermal_bridge_width 0.5)
			(island_removal_mode 0)
		)
		(polygon
			(pts
				(arc
					(start 184.51195 -76.073)
					(mid 182.73395 -76.073)
					(end 184.51195 -76.073)
				)
			)
		)
	)
	(zone
		(layer "In4.Cu")
		(hatch none 0.5)
		(connect_pads
			(clearance 0)
		)
		(min_thickness 0.25)
		(keepout
			(tracks not_allowed)
			(vias allowed)
			(pads allowed)
			(copperpour not_allowed)
			(footprints allowed)
		)
		(placement
			(enabled no)
			(sheetname "")
		)
		(fill
			(thermal_gap 0.5)
			(thermal_bridge_width 0.5)
			(island_removal_mode 0)
		)
		(polygon
			(pts
				(arc
					(start 77.032104 -167.845994)
					(mid 74.605896 -167.845994)
					(end 77.032104 -167.845994)
				)
			)
		)
	)
	(zone
		(layer "In4.Cu")
		(hatch none 0.5)
		(connect_pads
			(clearance 0)
		)
		(min_thickness 0.25)
		(keepout
			(tracks not_allowed)
			(vias allowed)
			(pads allowed)
			(copperpour not_allowed)
			(footprints allowed)
		)
		(placement
			(enabled no)
			(sheetname "")
		)
		(fill
			(thermal_gap 0.5)
			(thermal_bridge_width 0.5)
			(island_removal_mode 0)
		)
		(polygon
			(pts
				(arc
					(start 305.505358 -28.987242)
					(mid 303.727358 -28.987242)
					(end 305.505358 -28.987242)
				)
			)
		)
	)
	(zone
		(layer "In4.Cu")
		(hatch none 0.5)
		(connect_pads
			(clearance 0)
		)
		(min_thickness 0.25)
		(keepout
			(tracks not_allowed)
			(vias allowed)
			(pads allowed)
			(copperpour not_allowed)
			(footprints allowed)
		)
		(placement
			(enabled no)
			(sheetname "")
		)
		(fill
			(thermal_gap 0.5)
			(thermal_bridge_width 0.5)
			(island_removal_mode 0)
		)
		(polygon
			(pts
				(arc
					(start 305.505358 -62.820042)
					(mid 303.727358 -62.820042)
					(end 305.505358 -62.820042)
				)
			)
		)
	)
	(zone
		(layer "In4.Cu")
		(hatch none 0.5)
		(connect_pads
			(clearance 0)
		)
		(min_thickness 0.25)
		(keepout
			(tracks not_allowed)
			(vias allowed)
			(pads allowed)
			(copperpour not_allowed)
			(footprints allowed)
		)
		(placement
			(enabled no)
			(sheetname "")
		)
		(fill
			(thermal_gap 0.5)
			(thermal_bridge_width 0.5)
			(island_removal_mode 0)
		)
		(polygon
			(pts
				(arc
					(start 365.197136 -167.718994)
					(mid 362.770928 -167.718994)
					(end 365.197136 -167.718994)
				)
			)
		)
	)
	(zone
		(layer "In4.Cu")
		(hatch none 0.5)
		(connect_pads
			(clearance 0)
		)
		(min_thickness 0.25)
		(keepout
			(tracks not_allowed)
			(vias allowed)
			(pads allowed)
			(copperpour not_allowed)
			(footprints allowed)
		)
		(placement
			(enabled no)
			(sheetname "")
		)
		(fill
			(thermal_gap 0.5)
			(thermal_bridge_width 0.5)
			(island_removal_mode 0)
		)
		(polygon
			(pts
				(arc
					(start 167.894 -83.83905)
					(mid 166.116 -83.83905)
					(end 167.894 -83.83905)
				)
			)
		)
	)
	(zone
		(layer "In4.Cu")
		(hatch none 0.5)
		(connect_pads
			(clearance 0)
		)
		(min_thickness 0.25)
		(keepout
			(tracks not_allowed)
			(vias allowed)
			(pads allowed)
			(copperpour not_allowed)
			(footprints allowed)
		)
		(placement
			(enabled no)
			(sheetname "")
		)
		(fill
			(thermal_gap 0.5)
			(thermal_bridge_width 0.5)
			(island_removal_mode 0)
		)
		(polygon
			(pts
				(arc
					(start 144.22247 -40.077136)
					(mid 142.44447 -40.077136)
					(end 144.22247 -40.077136)
				)
			)
		)
	)
	(zone
		(layer "In4.Cu")
		(hatch none 0.5)
		(connect_pads
			(clearance 0)
		)
		(min_thickness 0.25)
		(keepout
			(tracks not_allowed)
			(vias allowed)
			(pads allowed)
			(copperpour not_allowed)
			(footprints allowed)
		)
		(placement
			(enabled no)
			(sheetname "")
		)
		(fill
			(thermal_gap 0.5)
			(thermal_bridge_width 0.5)
			(island_removal_mode 0)
		)
		(polygon
			(pts
				(arc
					(start 405.354282 -153.973022)
					(mid 402.928074 -153.973022)
					(end 405.354282 -153.973022)
				)
			)
		)
	)
	(zone
		(layer "In4.Cu")
		(hatch none 0.5)
		(connect_pads
			(clearance 0)
		)
		(min_thickness 0.25)
		(keepout
			(tracks not_allowed)
			(vias allowed)
			(pads allowed)
			(copperpour not_allowed)
			(footprints allowed)
		)
		(placement
			(enabled no)
			(sheetname "")
		)
		(fill
			(thermal_gap 0.5)
			(thermal_bridge_width 0.5)
			(island_removal_mode 0)
		)
		(polygon
			(pts
				(arc
					(start 290.8554 -77.510894)
					(mid 289.0774 -77.510894)
					(end 290.8554 -77.510894)
				)
			)
		)
	)
	(zone
		(layer "In4.Cu")
		(hatch none 0.5)
		(connect_pads
			(clearance 0)
		)
		(min_thickness 0.25)
		(keepout
			(tracks not_allowed)
			(vias allowed)
			(pads allowed)
			(copperpour not_allowed)
			(footprints allowed)
		)
		(placement
			(enabled no)
			(sheetname "")
		)
		(fill
			(thermal_gap 0.5)
			(thermal_bridge_width 0.5)
			(island_removal_mode 0)
		)
		(polygon
			(pts
				(arc
					(start 143.84782 -35.6362)
					(mid 142.06982 -35.6362)
					(end 143.84782 -35.6362)
				)
			)
		)
	)
	(zone
		(layer "In4.Cu")
		(hatch none 0.5)
		(connect_pads
			(clearance 0)
		)
		(min_thickness 0.25)
		(keepout
			(tracks not_allowed)
			(vias allowed)
			(pads allowed)
			(copperpour not_allowed)
			(footprints allowed)
		)
		(placement
			(enabled no)
			(sheetname "")
		)
		(fill
			(thermal_gap 0.5)
			(thermal_bridge_width 0.5)
			(island_removal_mode 0)
		)
		(polygon
			(pts
				(arc
					(start 377.056142 -1.527048)
					(mid 374.629934 -1.527048)
					(end 377.056142 -1.527048)
				)
			)
		)
	)
	(zone
		(layer "In4.Cu")
		(hatch none 0.5)
		(connect_pads
			(clearance 0)
		)
		(min_thickness 0.25)
		(keepout
			(tracks not_allowed)
			(vias allowed)
			(pads allowed)
			(copperpour not_allowed)
			(footprints allowed)
		)
		(placement
			(enabled no)
			(sheetname "")
		)
		(fill
			(thermal_gap 0.5)
			(thermal_bridge_width 0.5)
			(island_removal_mode 0)
		)
		(polygon
			(pts
				(arc
					(start 294.802052 -76.962)
					(mid 293.024052 -76.962)
					(end 294.802052 -76.962)
				)
			)
		)
	)
	(zone
		(layer "In4.Cu")
		(hatch none 0.5)
		(connect_pads
			(clearance 0)
		)
		(min_thickness 0.25)
		(keepout
			(tracks not_allowed)
			(vias allowed)
			(pads allowed)
			(copperpour not_allowed)
			(footprints allowed)
		)
		(placement
			(enabled no)
			(sheetname "")
		)
		(fill
			(thermal_gap 0.5)
			(thermal_bridge_width 0.5)
			(island_removal_mode 0)
		)
		(polygon
			(pts
				(arc
					(start 308.356 -67.4624)
					(mid 306.578 -67.4624)
					(end 308.356 -67.4624)
				)
			)
		)
	)
	(zone
		(layer "In4.Cu")
		(hatch none 0.5)
		(connect_pads
			(clearance 0)
		)
		(min_thickness 0.25)
		(keepout
			(tracks not_allowed)
			(vias allowed)
			(pads allowed)
			(copperpour not_allowed)
			(footprints allowed)
		)
		(placement
			(enabled no)
			(sheetname "")
		)
		(fill
			(thermal_gap 0.5)
			(thermal_bridge_width 0.5)
			(island_removal_mode 0)
		)
		(polygon
			(pts
				(arc
					(start 305.03495 -40.077136)
					(mid 303.25695 -40.077136)
					(end 305.03495 -40.077136)
				)
			)
		)
	)
	(zone
		(layer "In4.Cu")
		(hatch none 0.5)
		(connect_pads
			(clearance 0)
		)
		(min_thickness 0.25)
		(keepout
			(tracks not_allowed)
			(vias allowed)
			(pads allowed)
			(copperpour not_allowed)
			(footprints allowed)
		)
		(placement
			(enabled no)
			(sheetname "")
		)
		(fill
			(thermal_gap 0.5)
			(thermal_bridge_width 0.5)
			(island_removal_mode 0)
		)
		(polygon
			(pts
				(arc
					(start 153.71445 -77.61605)
					(mid 151.93645 -77.61605)
					(end 153.71445 -77.61605)
				)
			)
		)
	)
	(zone
		(layer "In4.Cu")
		(hatch none 0.5)
		(connect_pads
			(clearance 0)
		)
		(min_thickness 0.25)
		(keepout
			(tracks not_allowed)
			(vias allowed)
			(pads allowed)
			(copperpour not_allowed)
			(footprints allowed)
		)
		(placement
			(enabled no)
			(sheetname "")
		)
		(fill
			(thermal_gap 0.5)
			(thermal_bridge_width 0.5)
			(island_removal_mode 0)
		)
		(polygon
			(pts
				(arc
					(start 65.221104 -167.718994)
					(mid 62.794896 -167.718994)
					(end 65.221104 -167.718994)
				)
			)
		)
	)
	(zone
		(layer "In4.Cu")
		(hatch none 0.5)
		(connect_pads
			(clearance 0)
		)
		(min_thickness 0.25)
		(keepout
			(tracks not_allowed)
			(vias allowed)
			(pads allowed)
			(copperpour not_allowed)
			(footprints allowed)
		)
		(placement
			(enabled no)
			(sheetname "")
		)
		(fill
			(thermal_gap 0.5)
			(thermal_bridge_width 0.5)
			(island_removal_mode 0)
		)
		(polygon
			(pts
				(arc
					(start 66.942208 -169.97299)
					(mid 64.516 -169.97299)
					(end 66.942208 -169.97299)
				)
			)
		)
	)
	(zone
		(layer "In4.Cu")
		(hatch none 0.5)
		(connect_pads
			(clearance 0)
		)
		(min_thickness 0.25)
		(keepout
			(tracks not_allowed)
			(vias allowed)
			(pads allowed)
			(copperpour not_allowed)
			(footprints allowed)
		)
		(placement
			(enabled no)
			(sheetname "")
		)
		(fill
			(thermal_gap 0.5)
			(thermal_bridge_width 0.5)
			(island_removal_mode 0)
		)
		(polygon
			(pts
				(arc
					(start 272.80235 -61.722)
					(mid 271.02435 -61.722)
					(end 272.80235 -61.722)
				)
			)
		)
	)
	(zone
		(layer "In4.Cu")
		(hatch none 0.5)
		(connect_pads
			(clearance 0)
		)
		(min_thickness 0.25)
		(keepout
			(tracks not_allowed)
			(vias allowed)
			(pads allowed)
			(copperpour not_allowed)
			(footprints allowed)
		)
		(placement
			(enabled no)
			(sheetname "")
		)
		(fill
			(thermal_gap 0.5)
			(thermal_bridge_width 0.5)
			(island_removal_mode 0)
		)
		(polygon
			(pts
				(arc
					(start 365.197136 -165.718998)
					(mid 362.770928 -165.718998)
					(end 365.197136 -165.718998)
				)
			)
		)
	)
	(zone
		(layer "In4.Cu")
		(hatch none 0.5)
		(connect_pads
			(clearance 0)
		)
		(min_thickness 0.25)
		(keepout
			(tracks not_allowed)
			(vias allowed)
			(pads allowed)
			(copperpour not_allowed)
			(footprints allowed)
		)
		(placement
			(enabled no)
			(sheetname "")
		)
		(fill
			(thermal_gap 0.5)
			(thermal_bridge_width 0.5)
			(island_removal_mode 0)
		)
		(polygon
			(pts
				(arc
					(start 275.3614 -74.676)
					(mid 273.5834 -74.676)
					(end 275.3614 -74.676)
				)
			)
		)
	)
	(zone
		(layer "In4.Cu")
		(hatch none 0.5)
		(connect_pads
			(clearance 0)
		)
		(min_thickness 0.25)
		(keepout
			(tracks not_allowed)
			(vias allowed)
			(pads allowed)
			(copperpour not_allowed)
			(footprints allowed)
		)
		(placement
			(enabled no)
			(sheetname "")
		)
		(fill
			(thermal_gap 0.5)
			(thermal_bridge_width 0.5)
			(island_removal_mode 0)
		)
		(polygon
			(pts
				(arc
					(start 143.84782 -34.7472)
					(mid 142.06982 -34.7472)
					(end 143.84782 -34.7472)
				)
			)
		)
	)
	(zone
		(layer "In4.Cu")
		(hatch none 0.5)
		(connect_pads
			(clearance 0)
		)
		(min_thickness 0.25)
		(keepout
			(tracks not_allowed)
			(vias allowed)
			(pads allowed)
			(copperpour not_allowed)
			(footprints allowed)
		)
		(placement
			(enabled no)
			(sheetname "")
		)
		(fill
			(thermal_gap 0.5)
			(thermal_bridge_width 0.5)
			(island_removal_mode 0)
		)
		(polygon
			(pts
				(arc
					(start 41.822116 -153.973022)
					(mid 39.395908 -153.973022)
					(end 41.822116 -153.973022)
				)
			)
		)
	)
	(zone
		(layer "In4.Cu")
		(hatch none 0.5)
		(connect_pads
			(clearance 0)
		)
		(min_thickness 0.25)
		(keepout
			(tracks not_allowed)
			(vias allowed)
			(pads allowed)
			(copperpour not_allowed)
			(footprints allowed)
		)
		(placement
			(enabled no)
			(sheetname "")
		)
		(fill
			(thermal_gap 0.5)
			(thermal_bridge_width 0.5)
			(island_removal_mode 0)
		)
		(polygon
			(pts
				(arc
					(start 291.2364 -81.915)
					(mid 289.4584 -81.915)
					(end 291.2364 -81.915)
				)
			)
		)
	)
	(zone
		(layer "In4.Cu")
		(hatch none 0.5)
		(connect_pads
			(clearance 0)
		)
		(min_thickness 0.25)
		(keepout
			(tracks not_allowed)
			(vias allowed)
			(pads allowed)
			(copperpour not_allowed)
			(footprints allowed)
		)
		(placement
			(enabled no)
			(sheetname "")
		)
		(fill
			(thermal_gap 0.5)
			(thermal_bridge_width 0.5)
			(island_removal_mode 0)
		)
		(polygon
			(pts
				(arc
					(start 378.453142 -1.654048)
					(mid 376.026934 -1.654048)
					(end 378.453142 -1.654048)
				)
			)
		)
	)
	(zone
		(layer "In4.Cu")
		(hatch none 0.5)
		(connect_pads
			(clearance 0)
		)
		(min_thickness 0.25)
		(keepout
			(tracks not_allowed)
			(vias allowed)
			(pads allowed)
			(copperpour not_allowed)
			(footprints allowed)
		)
		(placement
			(enabled no)
			(sheetname "")
		)
		(fill
			(thermal_gap 0.5)
			(thermal_bridge_width 0.5)
			(island_removal_mode 0)
		)
		(polygon
			(pts
				(arc
					(start 371.166136 -165.591998)
					(mid 368.739928 -165.591998)
					(end 371.166136 -165.591998)
				)
			)
		)
	)
	(zone
		(layer "In4.Cu")
		(hatch none 0.5)
		(connect_pads
			(clearance 0)
		)
		(min_thickness 0.25)
		(keepout
			(tracks not_allowed)
			(vias allowed)
			(pads allowed)
			(copperpour not_allowed)
			(footprints allowed)
		)
		(placement
			(enabled no)
			(sheetname "")
		)
		(fill
			(thermal_gap 0.5)
			(thermal_bridge_width 0.5)
			(island_removal_mode 0)
		)
		(polygon
			(pts
				(arc
					(start 146.74342 -33.6296)
					(mid 144.96542 -33.6296)
					(end 146.74342 -33.6296)
				)
			)
		)
	)
	(zone
		(layer "In4.Cu")
		(hatch none 0.5)
		(connect_pads
			(clearance 0)
		)
		(min_thickness 0.25)
		(keepout
			(tracks not_allowed)
			(vias allowed)
			(pads allowed)
			(copperpour not_allowed)
			(footprints allowed)
		)
		(placement
			(enabled no)
			(sheetname "")
		)
		(fill
			(thermal_gap 0.5)
			(thermal_bridge_width 0.5)
			(island_removal_mode 0)
		)
		(polygon
			(pts
				(arc
					(start 405.354282 -163.973002)
					(mid 402.928074 -163.973002)
					(end 405.354282 -163.973002)
				)
			)
		)
	)
	(zone
		(layer "In4.Cu")
		(hatch none 0.5)
		(connect_pads
			(clearance 0)
		)
		(min_thickness 0.25)
		(keepout
			(tracks not_allowed)
			(vias allowed)
			(pads allowed)
			(copperpour not_allowed)
			(footprints allowed)
		)
		(placement
			(enabled no)
			(sheetname "")
		)
		(fill
			(thermal_gap 0.5)
			(thermal_bridge_width 0.5)
			(island_removal_mode 0)
		)
		(polygon
			(pts
				(arc
					(start 72.022208 -1.57099)
					(mid 69.596 -1.57099)
					(end 72.022208 -1.57099)
				)
			)
		)
	)
	(zone
		(layer "In4.Cu")
		(hatch none 0.5)
		(connect_pads
			(clearance 0)
		)
		(min_thickness 0.25)
		(keepout
			(tracks not_allowed)
			(vias allowed)
			(pads allowed)
			(copperpour not_allowed)
			(footprints allowed)
		)
		(placement
			(enabled no)
			(sheetname "")
		)
		(fill
			(thermal_gap 0.5)
			(thermal_bridge_width 0.5)
			(island_removal_mode 0)
		)
		(polygon
			(pts
				(arc
					(start 283.1084 -76.327)
					(mid 281.3304 -76.327)
					(end 283.1084 -76.327)
				)
			)
		)
	)
	(zone
		(layer "In4.Cu")
		(hatch none 0.5)
		(connect_pads
			(clearance 0)
		)
		(min_thickness 0.25)
		(keepout
			(tracks not_allowed)
			(vias allowed)
			(pads allowed)
			(copperpour not_allowed)
			(footprints allowed)
		)
		(placement
			(enabled no)
			(sheetname "")
		)
		(fill
			(thermal_gap 0.5)
			(thermal_bridge_width 0.5)
			(island_removal_mode 0)
		)
		(polygon
			(pts
				(arc
					(start 181.4576 -82.3214)
					(mid 179.6796 -82.3214)
					(end 181.4576 -82.3214)
				)
			)
		)
	)
	(zone
		(layer "In4.Cu")
		(hatch none 0.5)
		(connect_pads
			(clearance 0)
		)
		(min_thickness 0.25)
		(keepout
			(tracks not_allowed)
			(vias allowed)
			(pads allowed)
			(copperpour not_allowed)
			(footprints allowed)
		)
		(placement
			(enabled no)
			(sheetname "")
		)
		(fill
			(thermal_gap 0.5)
			(thermal_bridge_width 0.5)
			(island_removal_mode 0)
		)
		(polygon
			(pts
				(arc
					(start 288.03854 -78.16088)
					(mid 286.26054 -78.16088)
					(end 288.03854 -78.16088)
				)
			)
		)
	)
	(zone
		(layer "In4.Cu")
		(hatch none 0.5)
		(connect_pads
			(clearance 0)
		)
		(min_thickness 0.25)
		(keepout
			(tracks not_allowed)
			(vias allowed)
			(pads allowed)
			(copperpour not_allowed)
			(footprints allowed)
		)
		(placement
			(enabled no)
			(sheetname "")
		)
		(fill
			(thermal_gap 0.5)
			(thermal_bridge_width 0.5)
			(island_removal_mode 0)
		)
		(polygon
			(pts
				(arc
					(start 296.14495 -86.487)
					(mid 294.36695 -86.487)
					(end 296.14495 -86.487)
				)
			)
		)
	)
	(zone
		(layer "In4.Cu")
		(hatch none 0.5)
		(connect_pads
			(clearance 0)
		)
		(min_thickness 0.25)
		(keepout
			(tracks not_allowed)
			(vias allowed)
			(pads allowed)
			(copperpour not_allowed)
			(footprints allowed)
		)
		(placement
			(enabled no)
			(sheetname "")
		)
		(fill
			(thermal_gap 0.5)
			(thermal_bridge_width 0.5)
			(island_removal_mode 0)
		)
		(polygon
			(pts
				(arc
					(start 271.91335 -77.21092)
					(mid 270.13535 -77.21092)
					(end 271.91335 -77.21092)
				)
			)
		)
	)
	(zone
		(layer "In4.Cu")
		(hatch none 0.5)
		(connect_pads
			(clearance 0)
		)
		(min_thickness 0.25)
		(keepout
			(tracks not_allowed)
			(vias allowed)
			(pads allowed)
			(copperpour not_allowed)
			(footprints allowed)
		)
		(placement
			(enabled no)
			(sheetname "")
		)
		(fill
			(thermal_gap 0.5)
			(thermal_bridge_width 0.5)
			(island_removal_mode 0)
		)
		(polygon
			(pts
				(arc
					(start 286.1564 -81.915)
					(mid 284.3784 -81.915)
					(end 286.1564 -81.915)
				)
			)
		)
	)
	(zone
		(layer "In4.Cu")
		(hatch none 0.5)
		(connect_pads
			(clearance 0)
		)
		(min_thickness 0.25)
		(keepout
			(tracks not_allowed)
			(vias allowed)
			(pads allowed)
			(copperpour not_allowed)
			(footprints allowed)
		)
		(placement
			(enabled no)
			(sheetname "")
		)
		(fill
			(thermal_gap 0.5)
			(thermal_bridge_width 0.5)
			(island_removal_mode 0)
		)
		(polygon
			(pts
				(arc
					(start 167.0304 -66.802)
					(mid 165.2524 -66.802)
					(end 167.0304 -66.802)
				)
			)
		)
	)
	(zone
		(layer "In4.Cu")
		(hatch none 0.5)
		(connect_pads
			(clearance 0)
		)
		(min_thickness 0.25)
		(keepout
			(tracks not_allowed)
			(vias allowed)
			(pads allowed)
			(copperpour not_allowed)
			(footprints allowed)
		)
		(placement
			(enabled no)
			(sheetname "")
		)
		(fill
			(thermal_gap 0.5)
			(thermal_bridge_width 0.5)
			(island_removal_mode 0)
		)
		(polygon
			(pts
				(arc
					(start 72.370188 -4.575048)
					(mid 69.94398 -4.575048)
					(end 72.370188 -4.575048)
				)
			)
		)
	)
	(zone
		(layer "In4.Cu")
		(hatch none 0.5)
		(connect_pads
			(clearance 0)
		)
		(min_thickness 0.25)
		(keepout
			(tracks not_allowed)
			(vias allowed)
			(pads allowed)
			(copperpour not_allowed)
			(footprints allowed)
		)
		(placement
			(enabled no)
			(sheetname "")
		)
		(fill
			(thermal_gap 0.5)
			(thermal_bridge_width 0.5)
			(island_removal_mode 0)
		)
		(polygon
			(pts
				(arc
					(start 294.1574 -81.5467)
					(mid 292.3794 -81.5467)
					(end 294.1574 -81.5467)
				)
			)
		)
	)
	(zone
		(layer "In4.Cu")
		(hatch none 0.5)
		(connect_pads
			(clearance 0)
		)
		(min_thickness 0.25)
		(keepout
			(tracks not_allowed)
			(vias allowed)
			(pads allowed)
			(copperpour not_allowed)
			(footprints allowed)
		)
		(placement
			(enabled no)
			(sheetname "")
		)
		(fill
			(thermal_gap 0.5)
			(thermal_bridge_width 0.5)
			(island_removal_mode 0)
		)
		(polygon
			(pts
				(arc
					(start 185.31205 -76.09205)
					(mid 183.53405 -76.09205)
					(end 185.31205 -76.09205)
				)
			)
		)
	)
	(zone
		(layer "In4.Cu")
		(hatch none 0.5)
		(connect_pads
			(clearance 0)
		)
		(min_thickness 0.25)
		(keepout
			(tracks not_allowed)
			(vias allowed)
			(pads allowed)
			(copperpour not_allowed)
			(footprints allowed)
		)
		(placement
			(enabled no)
			(sheetname "")
		)
		(fill
			(thermal_gap 0.5)
			(thermal_bridge_width 0.5)
			(island_removal_mode 0)
		)
		(polygon
			(pts
				(arc
					(start 385.390136 -167.845994)
					(mid 382.963928 -167.845994)
					(end 385.390136 -167.845994)
				)
			)
		)
	)
	(zone
		(layers "In4.Cu" "In5.Cu")
		(hatch none 0.5)
		(connect_pads
			(clearance 0)
		)
		(min_thickness 0.25)
		(keepout
			(tracks not_allowed)
			(vias allowed)
			(pads allowed)
			(copperpour not_allowed)
			(footprints allowed)
		)
		(placement
			(enabled no)
			(sheetname "")
		)
		(fill yes
			(thermal_gap 0.5)
			(thermal_bridge_width 0.5)
			(island_removal_mode 0)
		)
		(polygon
			(pts
				(arc
					(start 384.412998 -166.829994)
					(mid 381.98679 -166.829994)
					(end 384.412998 -166.829994)
				)
			)
		)
	)
	(zone
		(layers "In4.Cu" "In5.Cu")
		(hatch none 0.5)
		(connect_pads
			(clearance 0)
		)
		(min_thickness 0.25)
		(keepout
			(tracks not_allowed)
			(vias allowed)
			(pads allowed)
			(copperpour not_allowed)
			(footprints allowed)
		)
		(placement
			(enabled no)
			(sheetname "")
		)
		(fill yes
			(thermal_gap 0.5)
			(thermal_bridge_width 0.5)
			(island_removal_mode 0)
		)
		(polygon
			(pts
				(arc
					(start 438.293002 -39.868348)
					(mid 436.515002 -39.868348)
					(end 438.293002 -39.868348)
				)
			)
		)
	)
	(zone
		(layers "In4.Cu" "In5.Cu")
		(hatch none 0.5)
		(connect_pads
			(clearance 0)
		)
		(min_thickness 0.25)
		(keepout
			(tracks not_allowed)
			(vias allowed)
			(pads allowed)
			(copperpour not_allowed)
			(footprints allowed)
		)
		(placement
			(enabled no)
			(sheetname "")
		)
		(fill yes
			(thermal_gap 0.5)
			(thermal_bridge_width 0.5)
			(island_removal_mode 0)
		)
		(polygon
			(pts
				(arc
					(start 417.077398 -26.450036)
					(mid 415.299398 -26.450036)
					(end 417.077398 -26.450036)
				)
			)
		)
	)
	(zone
		(layers "In4.Cu" "In5.Cu")
		(hatch none 0.5)
		(connect_pads
			(clearance 0)
		)
		(min_thickness 0.25)
		(keepout
			(tracks not_allowed)
			(vias allowed)
			(pads allowed)
			(copperpour not_allowed)
			(footprints allowed)
		)
		(placement
			(enabled no)
			(sheetname "")
		)
		(fill yes
			(thermal_gap 0.5)
			(thermal_bridge_width 0.5)
			(island_removal_mode 0)
		)
		(polygon
			(pts
				(arc
					(start 377.550172 -27.374342)
					(mid 375.772172 -27.374342)
					(end 377.550172 -27.374342)
				)
			)
		)
	)
	(zone
		(layers "In4.Cu" "In5.Cu")
		(hatch none 0.5)
		(connect_pads
			(clearance 0)
		)
		(min_thickness 0.25)
		(keepout
			(tracks not_allowed)
			(vias allowed)
			(pads allowed)
			(copperpour not_allowed)
			(footprints allowed)
		)
		(placement
			(enabled no)
			(sheetname "")
		)
		(fill yes
			(thermal_gap 0.5)
			(thermal_bridge_width 0.5)
			(island_removal_mode 0)
		)
		(polygon
			(pts
				(arc
					(start 81.407 -18.91665)
					(mid 79.629 -18.91665)
					(end 81.407 -18.91665)
				)
			)
		)
	)
	(zone
		(layers "In4.Cu" "In5.Cu")
		(hatch none 0.5)
		(connect_pads
			(clearance 0)
		)
		(min_thickness 0.25)
		(keepout
			(tracks not_allowed)
			(vias allowed)
			(pads allowed)
			(copperpour not_allowed)
			(footprints allowed)
		)
		(placement
			(enabled no)
			(sheetname "")
		)
		(fill yes
			(thermal_gap 0.5)
			(thermal_bridge_width 0.5)
			(island_removal_mode 0)
		)
		(polygon
			(pts
				(arc
					(start 42.838116 -158.83001)
					(mid 40.411908 -158.83001)
					(end 42.838116 -158.83001)
				)
			)
		)
	)
	(zone
		(layers "In4.Cu" "In5.Cu")
		(hatch none 0.5)
		(connect_pads
			(clearance 0)
		)
		(min_thickness 0.25)
		(keepout
			(tracks not_allowed)
			(vias allowed)
			(pads allowed)
			(copperpour not_allowed)
			(footprints allowed)
		)
		(placement
			(enabled no)
			(sheetname "")
		)
		(fill yes
			(thermal_gap 0.5)
			(thermal_bridge_width 0.5)
			(island_removal_mode 0)
		)
		(polygon
			(pts
				(arc
					(start 345.13774 -9.878822)
					(mid 343.35974 -9.878822)
					(end 345.13774 -9.878822)
				)
			)
		)
	)
	(zone
		(layers "In4.Cu" "In5.Cu")
		(hatch none 0.5)
		(connect_pads
			(clearance 0)
		)
		(min_thickness 0.25)
		(keepout
			(tracks not_allowed)
			(vias allowed)
			(pads allowed)
			(copperpour not_allowed)
			(footprints allowed)
		)
		(placement
			(enabled no)
			(sheetname "")
		)
		(fill yes
			(thermal_gap 0.5)
			(thermal_bridge_width 0.5)
			(island_removal_mode 0)
		)
		(polygon
			(pts
				(arc
					(start 413.893 -41.529)
					(mid 412.115 -41.529)
					(end 413.893 -41.529)
				)
			)
		)
	)
	(zone
		(layers "In4.Cu" "In5.Cu")
		(hatch none 0.5)
		(connect_pads
			(clearance 0)
		)
		(min_thickness 0.25)
		(keepout
			(tracks not_allowed)
			(vias allowed)
			(pads allowed)
			(copperpour not_allowed)
			(footprints allowed)
		)
		(placement
			(enabled no)
			(sheetname "")
		)
		(fill yes
			(thermal_gap 0.5)
			(thermal_bridge_width 0.5)
			(island_removal_mode 0)
		)
		(polygon
			(pts
				(arc
					(start 379.349 -20.447)
					(mid 377.571 -20.447)
					(end 379.349 -20.447)
				)
			)
		)
	)
	(zone
		(layers "In4.Cu" "In5.Cu")
		(hatch none 0.5)
		(connect_pads
			(clearance 0)
		)
		(min_thickness 0.25)
		(keepout
			(tracks not_allowed)
			(vias allowed)
			(pads allowed)
			(copperpour not_allowed)
			(footprints allowed)
		)
		(placement
			(enabled no)
			(sheetname "")
		)
		(fill yes
			(thermal_gap 0.5)
			(thermal_bridge_width 0.5)
			(island_removal_mode 0)
		)
		(polygon
			(pts
				(arc
					(start 435.48935 -47.498)
					(mid 433.71135 -47.498)
					(end 435.48935 -47.498)
				)
			)
		)
	)
	(zone
		(layers "In4.Cu" "In5.Cu")
		(hatch none 0.5)
		(connect_pads
			(clearance 0)
		)
		(min_thickness 0.25)
		(keepout
			(tracks not_allowed)
			(vias allowed)
			(pads allowed)
			(copperpour not_allowed)
			(footprints allowed)
		)
		(placement
			(enabled no)
			(sheetname "")
		)
		(fill yes
			(thermal_gap 0.5)
			(thermal_bridge_width 0.5)
			(island_removal_mode 0)
		)
		(polygon
			(pts
				(arc
					(start 410.8704 -29.21)
					(mid 409.0924 -29.21)
					(end 410.8704 -29.21)
				)
			)
		)
	)
	(zone
		(layers "In4.Cu" "In5.Cu")
		(hatch none 0.5)
		(connect_pads
			(clearance 0)
		)
		(min_thickness 0.25)
		(keepout
			(tracks not_allowed)
			(vias allowed)
			(pads allowed)
			(copperpour not_allowed)
			(footprints allowed)
		)
		(placement
			(enabled no)
			(sheetname "")
		)
		(fill yes
			(thermal_gap 0.5)
			(thermal_bridge_width 0.5)
			(island_removal_mode 0)
		)
		(polygon
			(pts
				(arc
					(start 42.838116 -168.82999)
					(mid 40.411908 -168.82999)
					(end 42.838116 -168.82999)
				)
			)
		)
	)
	(zone
		(layers "In4.Cu" "In5.Cu")
		(hatch none 0.5)
		(connect_pads
			(clearance 0)
		)
		(min_thickness 0.25)
		(keepout
			(tracks not_allowed)
			(vias allowed)
			(pads allowed)
			(copperpour not_allowed)
			(footprints allowed)
		)
		(placement
			(enabled no)
			(sheetname "")
		)
		(fill yes
			(thermal_gap 0.5)
			(thermal_bridge_width 0.5)
			(island_removal_mode 0)
		)
		(polygon
			(pts
				(arc
					(start 434.2384 -23.368)
					(mid 432.4604 -23.368)
					(end 434.2384 -23.368)
				)
			)
		)
	)
	(zone
		(layers "In4.Cu" "In5.Cu")
		(hatch none 0.5)
		(connect_pads
			(clearance 0)
		)
		(min_thickness 0.25)
		(keepout
			(tracks not_allowed)
			(vias allowed)
			(pads allowed)
			(copperpour not_allowed)
			(footprints allowed)
		)
		(placement
			(enabled no)
			(sheetname "")
		)
		(fill yes
			(thermal_gap 0.5)
			(thermal_bridge_width 0.5)
			(island_removal_mode 0)
		)
		(polygon
			(pts
				(arc
					(start 379.836172 -27.374342)
					(mid 378.058172 -27.374342)
					(end 379.836172 -27.374342)
				)
			)
		)
	)
	(zone
		(layers "In4.Cu" "In5.Cu")
		(hatch none 0.5)
		(connect_pads
			(clearance 0)
		)
		(min_thickness 0.25)
		(keepout
			(tracks not_allowed)
			(vias allowed)
			(pads allowed)
			(copperpour not_allowed)
			(footprints allowed)
		)
		(placement
			(enabled no)
			(sheetname "")
		)
		(fill yes
			(thermal_gap 0.5)
			(thermal_bridge_width 0.5)
			(island_removal_mode 0)
		)
		(polygon
			(pts
				(arc
					(start 449.961 -47.56404)
					(mid 448.183 -47.56404)
					(end 449.961 -47.56404)
				)
			)
		)
	)
	(zone
		(layers "In4.Cu" "In5.Cu")
		(hatch none 0.5)
		(connect_pads
			(clearance 0)
		)
		(min_thickness 0.25)
		(keepout
			(tracks not_allowed)
			(vias allowed)
			(pads allowed)
			(copperpour not_allowed)
			(footprints allowed)
		)
		(placement
			(enabled no)
			(sheetname "")
		)
		(fill yes
			(thermal_gap 0.5)
			(thermal_bridge_width 0.5)
			(island_removal_mode 0)
		)
		(polygon
			(pts
				(arc
					(start 437.7944 -45.593)
					(mid 436.0164 -45.593)
					(end 437.7944 -45.593)
				)
			)
		)
	)
	(zone
		(layers "In4.Cu" "In5.Cu")
		(hatch none 0.5)
		(connect_pads
			(clearance 0)
		)
		(min_thickness 0.25)
		(keepout
			(tracks not_allowed)
			(vias allowed)
			(pads allowed)
			(copperpour not_allowed)
			(footprints allowed)
		)
		(placement
			(enabled no)
			(sheetname "")
		)
		(fill yes
			(thermal_gap 0.5)
			(thermal_bridge_width 0.5)
			(island_removal_mode 0)
		)
		(polygon
			(pts
				(arc
					(start 80.839564 -9.959594)
					(mid 79.061564 -9.959594)
					(end 80.839564 -9.959594)
				)
			)
		)
	)
	(zone
		(layers "In4.Cu" "In5.Cu")
		(hatch none 0.5)
		(connect_pads
			(clearance 0)
		)
		(min_thickness 0.25)
		(keepout
			(tracks not_allowed)
			(vias allowed)
			(pads allowed)
			(copperpour not_allowed)
			(footprints allowed)
		)
		(placement
			(enabled no)
			(sheetname "")
		)
		(fill yes
			(thermal_gap 0.5)
			(thermal_bridge_width 0.5)
			(island_removal_mode 0)
		)
		(polygon
			(pts
				(arc
					(start 449.68795 -46.101)
					(mid 447.90995 -46.101)
					(end 449.68795 -46.101)
				)
			)
		)
	)
	(zone
		(layers "In4.Cu" "In5.Cu")
		(hatch none 0.5)
		(connect_pads
			(clearance 0)
		)
		(min_thickness 0.25)
		(keepout
			(tracks not_allowed)
			(vias allowed)
			(pads allowed)
			(copperpour not_allowed)
			(footprints allowed)
		)
		(placement
			(enabled no)
			(sheetname "")
		)
		(fill yes
			(thermal_gap 0.5)
			(thermal_bridge_width 0.5)
			(island_removal_mode 0)
		)
		(polygon
			(pts
				(arc
					(start 449.566538 -61.670692)
					(mid 447.788538 -61.670692)
					(end 449.566538 -61.670692)
				)
			)
		)
	)
	(zone
		(layers "In4.Cu" "In5.Cu")
		(hatch none 0.5)
		(connect_pads
			(clearance 0)
		)
		(min_thickness 0.25)
		(keepout
			(tracks not_allowed)
			(vias allowed)
			(pads allowed)
			(copperpour not_allowed)
			(footprints allowed)
		)
		(placement
			(enabled no)
			(sheetname "")
		)
		(fill yes
			(thermal_gap 0.5)
			(thermal_bridge_width 0.5)
			(island_removal_mode 0)
		)
		(polygon
			(pts
				(arc
					(start 417.458398 -25.764236)
					(mid 415.680398 -25.764236)
					(end 417.458398 -25.764236)
				)
			)
		)
	)
	(zone
		(layers "In4.Cu" "In5.Cu")
		(hatch none 0.5)
		(connect_pads
			(clearance 0)
		)
		(min_thickness 0.25)
		(keepout
			(tracks not_allowed)
			(vias allowed)
			(pads allowed)
			(copperpour not_allowed)
			(footprints allowed)
		)
		(placement
			(enabled no)
			(sheetname "")
		)
		(fill yes
			(thermal_gap 0.5)
			(thermal_bridge_width 0.5)
			(island_removal_mode 0)
		)
		(polygon
			(pts
				(arc
					(start 406.338278 -158.83001)
					(mid 403.91207 -158.83001)
					(end 406.338278 -158.83001)
				)
			)
		)
	)
	(zone
		(layers "In4.Cu" "In5.Cu")
		(hatch none 0.5)
		(connect_pads
			(clearance 0)
		)
		(min_thickness 0.25)
		(keepout
			(tracks not_allowed)
			(vias allowed)
			(pads allowed)
			(copperpour not_allowed)
			(footprints allowed)
		)
		(placement
			(enabled no)
			(sheetname "")
		)
		(fill yes
			(thermal_gap 0.5)
			(thermal_bridge_width 0.5)
			(island_removal_mode 0)
		)
		(polygon
			(pts
				(arc
					(start 454.011538 -60.908692)
					(mid 452.233538 -60.908692)
					(end 454.011538 -60.908692)
				)
			)
		)
	)
	(zone
		(layers "In4.Cu" "In5.Cu")
		(hatch none 0.5)
		(connect_pads
			(clearance 0)
		)
		(min_thickness 0.25)
		(keepout
			(tracks not_allowed)
			(vias allowed)
			(pads allowed)
			(copperpour not_allowed)
			(footprints allowed)
		)
		(placement
			(enabled no)
			(sheetname "")
		)
		(fill yes
			(thermal_gap 0.5)
			(thermal_bridge_width 0.5)
			(island_removal_mode 0)
		)
		(polygon
			(pts
				(arc
					(start 377.183142 -3.305048)
					(mid 374.756934 -3.305048)
					(end 377.183142 -3.305048)
				)
			)
		)
	)
	(zone
		(layers "In4.Cu" "In5.Cu")
		(hatch none 0.5)
		(connect_pads
			(clearance 0)
		)
		(min_thickness 0.25)
		(keepout
			(tracks not_allowed)
			(vias allowed)
			(pads allowed)
			(copperpour not_allowed)
			(footprints allowed)
		)
		(placement
			(enabled no)
			(sheetname "")
		)
		(fill yes
			(thermal_gap 0.5)
			(thermal_bridge_width 0.5)
			(island_removal_mode 0)
		)
		(polygon
			(pts
				(arc
					(start 433.9844 -35.687)
					(mid 432.2064 -35.687)
					(end 433.9844 -35.687)
				)
			)
		)
	)
	(zone
		(layers "In4.Cu" "In5.Cu")
		(hatch none 0.5)
		(connect_pads
			(clearance 0)
		)
		(min_thickness 0.25)
		(keepout
			(tracks not_allowed)
			(vias allowed)
			(pads allowed)
			(copperpour not_allowed)
			(footprints allowed)
		)
		(placement
			(enabled no)
			(sheetname "")
		)
		(fill yes
			(thermal_gap 0.5)
			(thermal_bridge_width 0.5)
			(island_removal_mode 0)
		)
		(polygon
			(pts
				(arc
					(start 43.88739 -132.199888)
					(mid 40.83939 -132.199888)
					(end 43.88739 -132.199888)
				)
			)
		)
	)
	(zone
		(layers "In4.Cu" "In5.Cu")
		(hatch none 0.5)
		(connect_pads
			(clearance 0)
		)
		(min_thickness 0.25)
		(keepout
			(tracks not_allowed)
			(vias allowed)
			(pads allowed)
			(copperpour not_allowed)
			(footprints allowed)
		)
		(placement
			(enabled no)
			(sheetname "")
		)
		(fill yes
			(thermal_gap 0.5)
			(thermal_bridge_width 0.5)
			(island_removal_mode 0)
		)
		(polygon
			(pts
				(arc
					(start 421.005 -48.895)
					(mid 419.227 -48.895)
					(end 421.005 -48.895)
				)
			)
		)
	)
	(zone
		(layers "In4.Cu" "In5.Cu")
		(hatch none 0.5)
		(connect_pads
			(clearance 0)
		)
		(min_thickness 0.25)
		(keepout
			(tracks not_allowed)
			(vias allowed)
			(pads allowed)
			(copperpour not_allowed)
			(footprints allowed)
		)
		(placement
			(enabled no)
			(sheetname "")
		)
		(fill yes
			(thermal_gap 0.5)
			(thermal_bridge_width 0.5)
			(island_removal_mode 0)
		)
		(polygon
			(pts
				(arc
					(start 390.412986 -166.829994)
					(mid 387.986778 -166.829994)
					(end 390.412986 -166.829994)
				)
			)
		)
	)
	(zone
		(layers "In4.Cu" "In5.Cu")
		(hatch none 0.5)
		(connect_pads
			(clearance 0)
		)
		(min_thickness 0.25)
		(keepout
			(tracks not_allowed)
			(vias allowed)
			(pads allowed)
			(copperpour not_allowed)
			(footprints allowed)
		)
		(placement
			(enabled no)
			(sheetname "")
		)
		(fill yes
			(thermal_gap 0.5)
			(thermal_bridge_width 0.5)
			(island_removal_mode 0)
		)
		(polygon
			(pts
				(arc
					(start 374.643142 -5.845048)
					(mid 372.216934 -5.845048)
					(end 374.643142 -5.845048)
				)
			)
		)
	)
	(zone
		(layers "In4.Cu" "In5.Cu")
		(hatch none 0.5)
		(connect_pads
			(clearance 0)
		)
		(min_thickness 0.25)
		(keepout
			(tracks not_allowed)
			(vias allowed)
			(pads allowed)
			(copperpour not_allowed)
			(footprints allowed)
		)
		(placement
			(enabled no)
			(sheetname "")
		)
		(fill yes
			(thermal_gap 0.5)
			(thermal_bridge_width 0.5)
			(island_removal_mode 0)
		)
		(polygon
			(pts
				(arc
					(start 56.013096 -164.829998)
					(mid 53.586888 -164.829998)
					(end 56.013096 -164.829998)
				)
			)
		)
	)
	(zone
		(layers "In4.Cu" "In5.Cu")
		(hatch none 0.5)
		(connect_pads
			(clearance 0)
		)
		(min_thickness 0.25)
		(keepout
			(tracks not_allowed)
			(vias allowed)
			(pads allowed)
			(copperpour not_allowed)
			(footprints allowed)
		)
		(placement
			(enabled no)
			(sheetname "")
		)
		(fill yes
			(thermal_gap 0.5)
			(thermal_bridge_width 0.5)
			(island_removal_mode 0)
		)
		(polygon
			(pts
				(arc
					(start 399.161 -71.239888)
					(mid 396.113 -71.239888)
					(end 399.161 -71.239888)
				)
			)
		)
	)
	(zone
		(layers "In4.Cu" "In5.Cu")
		(hatch none 0.5)
		(connect_pads
			(clearance 0)
		)
		(min_thickness 0.25)
		(keepout
			(tracks not_allowed)
			(vias allowed)
			(pads allowed)
			(copperpour not_allowed)
			(footprints allowed)
		)
		(placement
			(enabled no)
			(sheetname "")
		)
		(fill yes
			(thermal_gap 0.5)
			(thermal_bridge_width 0.5)
			(island_removal_mode 0)
		)
		(polygon
			(pts
				(arc
					(start 451.104 -44.196)
					(mid 449.326 -44.196)
					(end 451.104 -44.196)
				)
			)
		)
	)
	(zone
		(layers "In4.Cu" "In5.Cu")
		(hatch none 0.5)
		(connect_pads
			(clearance 0)
		)
		(min_thickness 0.25)
		(keepout
			(tracks not_allowed)
			(vias allowed)
			(pads allowed)
			(copperpour not_allowed)
			(footprints allowed)
		)
		(placement
			(enabled no)
			(sheetname "")
		)
		(fill yes
			(thermal_gap 0.5)
			(thermal_bridge_width 0.5)
			(island_removal_mode 0)
		)
		(polygon
			(pts
				(arc
					(start 429.126904 -43.18)
					(mid 427.348904 -43.18)
					(end 429.126904 -43.18)
				)
			)
		)
	)
	(zone
		(layers "In4.Cu" "In5.Cu")
		(hatch none 0.5)
		(connect_pads
			(clearance 0)
		)
		(min_thickness 0.25)
		(keepout
			(tracks not_allowed)
			(vias allowed)
			(pads allowed)
			(copperpour not_allowed)
			(footprints allowed)
		)
		(placement
			(enabled no)
			(sheetname "")
		)
		(fill yes
			(thermal_gap 0.5)
			(thermal_bridge_width 0.5)
			(island_removal_mode 0)
		)
		(polygon
			(pts
				(arc
					(start 374.643142 -3.305048)
					(mid 372.216934 -3.305048)
					(end 374.643142 -3.305048)
				)
			)
		)
	)
	(zone
		(layers "In4.Cu" "In5.Cu")
		(hatch none 0.5)
		(connect_pads
			(clearance 0)
		)
		(min_thickness 0.25)
		(keepout
			(tracks not_allowed)
			(vias allowed)
			(pads allowed)
			(copperpour not_allowed)
			(footprints allowed)
		)
		(placement
			(enabled no)
			(sheetname "")
		)
		(fill yes
			(thermal_gap 0.5)
			(thermal_bridge_width 0.5)
			(island_removal_mode 0)
		)
		(polygon
			(pts
				(arc
					(start 448.945 -40.13835)
					(mid 447.167 -40.13835)
					(end 448.945 -40.13835)
				)
			)
		)
	)
	(zone
		(layers "In4.Cu" "In5.Cu")
		(hatch none 0.5)
		(connect_pads
			(clearance 0)
		)
		(min_thickness 0.25)
		(keepout
			(tracks not_allowed)
			(vias allowed)
			(pads allowed)
			(copperpour not_allowed)
			(footprints allowed)
		)
		(placement
			(enabled no)
			(sheetname "")
		)
		(fill yes
			(thermal_gap 0.5)
			(thermal_bridge_width 0.5)
			(island_removal_mode 0)
		)
		(polygon
			(pts
				(arc
					(start 451.848728 -63.590678)
					(mid 450.070728 -63.590678)
					(end 451.848728 -63.590678)
				)
			)
		)
	)
	(zone
		(layers "In4.Cu" "In5.Cu")
		(hatch none 0.5)
		(connect_pads
			(clearance 0)
		)
		(min_thickness 0.25)
		(keepout
			(tracks not_allowed)
			(vias allowed)
			(pads allowed)
			(copperpour not_allowed)
			(footprints allowed)
		)
		(placement
			(enabled no)
			(sheetname "")
		)
		(fill yes
			(thermal_gap 0.5)
			(thermal_bridge_width 0.5)
			(island_removal_mode 0)
		)
		(polygon
			(pts
				(arc
					(start 440.159394 -40.426894)
					(mid 438.381394 -40.426894)
					(end 440.159394 -40.426894)
				)
			)
		)
	)
	(zone
		(layers "In4.Cu" "In5.Cu")
		(hatch none 0.5)
		(connect_pads
			(clearance 0)
		)
		(min_thickness 0.25)
		(keepout
			(tracks not_allowed)
			(vias allowed)
			(pads allowed)
			(copperpour not_allowed)
			(footprints allowed)
		)
		(placement
			(enabled no)
			(sheetname "")
		)
		(fill yes
			(thermal_gap 0.5)
			(thermal_bridge_width 0.5)
			(island_removal_mode 0)
		)
		(polygon
			(pts
				(arc
					(start 417.939728 -31.234126)
					(mid 416.161728 -31.234126)
					(end 417.939728 -31.234126)
				)
			)
		)
	)
	(zone
		(layers "In4.Cu" "In5.Cu")
		(hatch none 0.5)
		(connect_pads
			(clearance 0)
		)
		(min_thickness 0.25)
		(keepout
			(tracks not_allowed)
			(vias allowed)
			(pads allowed)
			(copperpour not_allowed)
			(footprints allowed)
		)
		(placement
			(enabled no)
			(sheetname "")
		)
		(fill yes
			(thermal_gap 0.5)
			(thermal_bridge_width 0.5)
			(island_removal_mode 0)
		)
		(polygon
			(pts
				(arc
					(start 384.412998 -168.82999)
					(mid 381.98679 -168.82999)
					(end 384.412998 -168.82999)
				)
			)
		)
	)
	(zone
		(layers "In4.Cu" "In5.Cu")
		(hatch none 0.5)
		(connect_pads
			(clearance 0)
		)
		(min_thickness 0.25)
		(keepout
			(tracks not_allowed)
			(vias allowed)
			(pads allowed)
			(copperpour not_allowed)
			(footprints allowed)
		)
		(placement
			(enabled no)
			(sheetname "")
		)
		(fill yes
			(thermal_gap 0.5)
			(thermal_bridge_width 0.5)
			(island_removal_mode 0)
		)
		(polygon
			(pts
				(arc
					(start 379.074172 -26.612342)
					(mid 377.296172 -26.612342)
					(end 379.074172 -26.612342)
				)
			)
		)
	)
	(zone
		(layers "In4.Cu" "In5.Cu")
		(hatch none 0.5)
		(connect_pads
			(clearance 0)
		)
		(min_thickness 0.25)
		(keepout
			(tracks not_allowed)
			(vias allowed)
			(pads allowed)
			(copperpour not_allowed)
			(footprints allowed)
		)
		(placement
			(enabled no)
			(sheetname "")
		)
		(fill yes
			(thermal_gap 0.5)
			(thermal_bridge_width 0.5)
			(island_removal_mode 0)
		)
		(polygon
			(pts
				(arc
					(start 419.439598 -30.940248)
					(mid 417.661598 -30.940248)
					(end 419.439598 -30.940248)
				)
			)
		)
	)
	(zone
		(layers "In4.Cu" "In5.Cu")
		(hatch none 0.5)
		(connect_pads
			(clearance 0)
		)
		(min_thickness 0.25)
		(keepout
			(tracks not_allowed)
			(vias allowed)
			(pads allowed)
			(copperpour not_allowed)
			(footprints allowed)
		)
		(placement
			(enabled no)
			(sheetname "")
		)
		(fill yes
			(thermal_gap 0.5)
			(thermal_bridge_width 0.5)
			(island_removal_mode 0)
		)
		(polygon
			(pts
				(arc
					(start 419.236398 -25.764236)
					(mid 417.458398 -25.764236)
					(end 419.236398 -25.764236)
				)
			)
		)
	)
	(zone
		(layers "In4.Cu" "In5.Cu")
		(hatch none 0.5)
		(connect_pads
			(clearance 0)
		)
		(min_thickness 0.25)
		(keepout
			(tracks not_allowed)
			(vias allowed)
			(pads allowed)
			(copperpour not_allowed)
			(footprints allowed)
		)
		(placement
			(enabled no)
			(sheetname "")
		)
		(fill yes
			(thermal_gap 0.5)
			(thermal_bridge_width 0.5)
			(island_removal_mode 0)
		)
		(polygon
			(pts
				(arc
					(start 438.1754 -50.419)
					(mid 436.3974 -50.419)
					(end 438.1754 -50.419)
				)
			)
		)
	)
	(zone
		(layers "In4.Cu" "In5.Cu")
		(hatch none 0.5)
		(connect_pads
			(clearance 0)
		)
		(min_thickness 0.25)
		(keepout
			(tracks not_allowed)
			(vias allowed)
			(pads allowed)
			(copperpour not_allowed)
			(footprints allowed)
		)
		(placement
			(enabled no)
			(sheetname "")
		)
		(fill yes
			(thermal_gap 0.5)
			(thermal_bridge_width 0.5)
			(island_removal_mode 0)
		)
		(polygon
			(pts
				(arc
					(start 82.55 -16.891)
					(mid 80.772 -16.891)
					(end 82.55 -16.891)
				)
			)
		)
	)
	(zone
		(layers "In4.Cu" "In5.Cu")
		(hatch none 0.5)
		(connect_pads
			(clearance 0)
		)
		(min_thickness 0.25)
		(keepout
			(tracks not_allowed)
			(vias allowed)
			(pads allowed)
			(copperpour not_allowed)
			(footprints allowed)
		)
		(placement
			(enabled no)
			(sheetname "")
		)
		(fill yes
			(thermal_gap 0.5)
			(thermal_bridge_width 0.5)
			(island_removal_mode 0)
		)
		(polygon
			(pts
				(arc
					(start 407.8224 -21.717)
					(mid 406.0444 -21.717)
					(end 407.8224 -21.717)
				)
			)
		)
	)
	(zone
		(layers "In4.Cu" "In5.Cu")
		(hatch none 0.5)
		(connect_pads
			(clearance 0)
		)
		(min_thickness 0.25)
		(keepout
			(tracks not_allowed)
			(vias allowed)
			(pads allowed)
			(copperpour not_allowed)
			(footprints allowed)
		)
		(placement
			(enabled no)
			(sheetname "")
		)
		(fill yes
			(thermal_gap 0.5)
			(thermal_bridge_width 0.5)
			(island_removal_mode 0)
		)
		(polygon
			(pts
				(arc
					(start 443.0014 -60.452)
					(mid 441.2234 -60.452)
					(end 443.0014 -60.452)
				)
			)
		)
	)
	(zone
		(layers "In4.Cu" "In5.Cu")
		(hatch none 0.5)
		(connect_pads
			(clearance 0)
		)
		(min_thickness 0.25)
		(keepout
			(tracks not_allowed)
			(vias allowed)
			(pads allowed)
			(copperpour not_allowed)
			(footprints allowed)
		)
		(placement
			(enabled no)
			(sheetname "")
		)
		(fill yes
			(thermal_gap 0.5)
			(thermal_bridge_width 0.5)
			(island_removal_mode 0)
		)
		(polygon
			(pts
				(arc
					(start 379.095254 -99.06)
					(mid 377.062746 -99.06)
					(end 379.095254 -99.06)
				)
			)
		)
	)
	(zone
		(layers "In4.Cu" "In5.Cu")
		(hatch none 0.5)
		(connect_pads
			(clearance 0)
		)
		(min_thickness 0.25)
		(keepout
			(tracks not_allowed)
			(vias allowed)
			(pads allowed)
			(copperpour not_allowed)
			(footprints allowed)
		)
		(placement
			(enabled no)
			(sheetname "")
		)
		(fill yes
			(thermal_gap 0.5)
			(thermal_bridge_width 0.5)
			(island_removal_mode 0)
		)
		(polygon
			(pts
				(arc
					(start 404.338282 -158.83001)
					(mid 401.912074 -158.83001)
					(end 404.338282 -158.83001)
				)
			)
		)
	)
	(zone
		(layers "In4.Cu" "In5.Cu")
		(hatch none 0.5)
		(connect_pads
			(clearance 0)
		)
		(min_thickness 0.25)
		(keepout
			(tracks not_allowed)
			(vias allowed)
			(pads allowed)
			(copperpour not_allowed)
			(footprints allowed)
		)
		(placement
			(enabled no)
			(sheetname "")
		)
		(fill yes
			(thermal_gap 0.5)
			(thermal_bridge_width 0.5)
			(island_removal_mode 0)
		)
		(polygon
			(pts
				(arc
					(start 42.838116 -156.830014)
					(mid 40.411908 -156.830014)
					(end 42.838116 -156.830014)
				)
			)
		)
	)
	(zone
		(layers "In4.Cu" "In5.Cu")
		(hatch none 0.5)
		(connect_pads
			(clearance 0)
		)
		(min_thickness 0.25)
		(keepout
			(tracks not_allowed)
			(vias allowed)
			(pads allowed)
			(copperpour not_allowed)
			(footprints allowed)
		)
		(placement
			(enabled no)
			(sheetname "")
		)
		(fill yes
			(thermal_gap 0.5)
			(thermal_bridge_width 0.5)
			(island_removal_mode 0)
		)
		(polygon
			(pts
				(arc
					(start 449.72605 -39.492936)
					(mid 447.94805 -39.492936)
					(end 449.72605 -39.492936)
				)
			)
		)
	)
	(zone
		(layers "In4.Cu" "In5.Cu")
		(hatch none 0.5)
		(connect_pads
			(clearance 0)
		)
		(min_thickness 0.25)
		(keepout
			(tracks not_allowed)
			(vias allowed)
			(pads allowed)
			(copperpour not_allowed)
			(footprints allowed)
		)
		(placement
			(enabled no)
			(sheetname "")
		)
		(fill yes
			(thermal_gap 0.5)
			(thermal_bridge_width 0.5)
			(island_removal_mode 0)
		)
		(polygon
			(pts
				(arc
					(start 58.013092 -168.82999)
					(mid 55.586884 -168.82999)
					(end 58.013092 -168.82999)
				)
			)
		)
	)
	(zone
		(layers "In4.Cu" "In5.Cu")
		(hatch none 0.5)
		(connect_pads
			(clearance 0)
		)
		(min_thickness 0.25)
		(keepout
			(tracks not_allowed)
			(vias allowed)
			(pads allowed)
			(copperpour not_allowed)
			(footprints allowed)
		)
		(placement
			(enabled no)
			(sheetname "")
		)
		(fill yes
			(thermal_gap 0.5)
			(thermal_bridge_width 0.5)
			(island_removal_mode 0)
		)
		(polygon
			(pts
				(arc
					(start 417.966398 -26.450036)
					(mid 416.188398 -26.450036)
					(end 417.966398 -26.450036)
				)
			)
		)
	)
	(zone
		(layers "In4.Cu" "In5.Cu")
		(hatch none 0.5)
		(connect_pads
			(clearance 0)
		)
		(min_thickness 0.25)
		(keepout
			(tracks not_allowed)
			(vias allowed)
			(pads allowed)
			(copperpour not_allowed)
			(footprints allowed)
		)
		(placement
			(enabled no)
			(sheetname "")
		)
		(fill yes
			(thermal_gap 0.5)
			(thermal_bridge_width 0.5)
			(island_removal_mode 0)
		)
		(polygon
			(pts
				(arc
					(start 412.9024 -39.606474)
					(mid 411.1244 -39.606474)
					(end 412.9024 -39.606474)
				)
			)
		)
	)
	(zone
		(layers "In4.Cu" "In5.Cu")
		(hatch none 0.5)
		(connect_pads
			(clearance 0)
		)
		(min_thickness 0.25)
		(keepout
			(tracks not_allowed)
			(vias allowed)
			(pads allowed)
			(copperpour not_allowed)
			(footprints allowed)
		)
		(placement
			(enabled no)
			(sheetname "")
		)
		(fill yes
			(thermal_gap 0.5)
			(thermal_bridge_width 0.5)
			(island_removal_mode 0)
		)
		(polygon
			(pts
				(arc
					(start 433.21605 -52.197)
					(mid 431.43805 -52.197)
					(end 433.21605 -52.197)
				)
			)
		)
	)
	(zone
		(layers "In4.Cu" "In5.Cu")
		(hatch none 0.5)
		(connect_pads
			(clearance 0)
		)
		(min_thickness 0.25)
		(keepout
			(tracks not_allowed)
			(vias allowed)
			(pads allowed)
			(copperpour not_allowed)
			(footprints allowed)
		)
		(placement
			(enabled no)
			(sheetname "")
		)
		(fill yes
			(thermal_gap 0.5)
			(thermal_bridge_width 0.5)
			(island_removal_mode 0)
		)
		(polygon
			(pts
				(arc
					(start 379.095254 -78.74)
					(mid 377.062746 -78.74)
					(end 379.095254 -78.74)
				)
			)
		)
	)
	(zone
		(layers "In4.Cu" "In5.Cu")
		(hatch none 0.5)
		(connect_pads
			(clearance 0)
		)
		(min_thickness 0.25)
		(keepout
			(tracks not_allowed)
			(vias allowed)
			(pads allowed)
			(copperpour not_allowed)
			(footprints allowed)
		)
		(placement
			(enabled no)
			(sheetname "")
		)
		(fill yes
			(thermal_gap 0.5)
			(thermal_bridge_width 0.5)
			(island_removal_mode 0)
		)
		(polygon
			(pts
				(arc
					(start 378.213112 -166.829994)
					(mid 375.786904 -166.829994)
					(end 378.213112 -166.829994)
				)
			)
		)
	)
	(zone
		(layers "In4.Cu" "In5.Cu")
		(hatch none 0.5)
		(connect_pads
			(clearance 0)
		)
		(min_thickness 0.25)
		(keepout
			(tracks not_allowed)
			(vias allowed)
			(pads allowed)
			(copperpour not_allowed)
			(footprints allowed)
		)
		(placement
			(enabled no)
			(sheetname "")
		)
		(fill yes
			(thermal_gap 0.5)
			(thermal_bridge_width 0.5)
			(island_removal_mode 0)
		)
		(polygon
			(pts
				(arc
					(start 390.412986 -168.82999)
					(mid 387.986778 -168.82999)
					(end 390.412986 -168.82999)
				)
			)
		)
	)
	(zone
		(layers "In4.Cu" "In5.Cu")
		(hatch none 0.5)
		(connect_pads
			(clearance 0)
		)
		(min_thickness 0.25)
		(keepout
			(tracks not_allowed)
			(vias allowed)
			(pads allowed)
			(copperpour not_allowed)
			(footprints allowed)
		)
		(placement
			(enabled no)
			(sheetname "")
		)
		(fill yes
			(thermal_gap 0.5)
			(thermal_bridge_width 0.5)
			(island_removal_mode 0)
		)
		(polygon
			(pts
				(arc
					(start 221.1324 -8.001)
					(mid 219.3544 -8.001)
					(end 221.1324 -8.001)
				)
			)
		)
	)
	(zone
		(layers "In4.Cu" "In5.Cu")
		(hatch none 0.5)
		(connect_pads
			(clearance 0)
		)
		(min_thickness 0.25)
		(keepout
			(tracks not_allowed)
			(vias allowed)
			(pads allowed)
			(copperpour not_allowed)
			(footprints allowed)
		)
		(placement
			(enabled no)
			(sheetname "")
		)
		(fill yes
			(thermal_gap 0.5)
			(thermal_bridge_width 0.5)
			(island_removal_mode 0)
		)
		(polygon
			(pts
				(arc
					(start 443.0014 -65.532)
					(mid 441.2234 -65.532)
					(end 443.0014 -65.532)
				)
			)
		)
	)
	(zone
		(layers "In4.Cu" "In5.Cu")
		(hatch none 0.5)
		(connect_pads
			(clearance 0)
		)
		(min_thickness 0.25)
		(keepout
			(tracks not_allowed)
			(vias allowed)
			(pads allowed)
			(copperpour not_allowed)
			(footprints allowed)
		)
		(placement
			(enabled no)
			(sheetname "")
		)
		(fill yes
			(thermal_gap 0.5)
			(thermal_bridge_width 0.5)
			(island_removal_mode 0)
		)
		(polygon
			(pts
				(arc
					(start 450.48805 -46.101)
					(mid 448.71005 -46.101)
					(end 450.48805 -46.101)
				)
			)
		)
	)
	(zone
		(layers "In4.Cu" "In5.Cu")
		(hatch none 0.5)
		(connect_pads
			(clearance 0)
		)
		(min_thickness 0.25)
		(keepout
			(tracks not_allowed)
			(vias allowed)
			(pads allowed)
			(copperpour not_allowed)
			(footprints allowed)
		)
		(placement
			(enabled no)
			(sheetname "")
		)
		(fill yes
			(thermal_gap 0.5)
			(thermal_bridge_width 0.5)
			(island_removal_mode 0)
		)
		(polygon
			(pts
				(arc
					(start 84.836 -18.916904)
					(mid 83.058 -18.916904)
					(end 84.836 -18.916904)
				)
			)
		)
	)
	(zone
		(layers "In4.Cu" "In5.Cu")
		(hatch none 0.5)
		(connect_pads
			(clearance 0)
		)
		(min_thickness 0.25)
		(keepout
			(tracks not_allowed)
			(vias allowed)
			(pads allowed)
			(copperpour not_allowed)
			(footprints allowed)
		)
		(placement
			(enabled no)
			(sheetname "")
		)
		(fill yes
			(thermal_gap 0.5)
			(thermal_bridge_width 0.5)
			(island_removal_mode 0)
		)
		(polygon
			(pts
				(arc
					(start 432.174904 -38.989)
					(mid 430.396904 -38.989)
					(end 432.174904 -38.989)
				)
			)
		)
	)
	(zone
		(layers "In4.Cu" "In5.Cu")
		(hatch none 0.5)
		(connect_pads
			(clearance 0)
		)
		(min_thickness 0.25)
		(keepout
			(tracks not_allowed)
			(vias allowed)
			(pads allowed)
			(copperpour not_allowed)
			(footprints allowed)
		)
		(placement
			(enabled no)
			(sheetname "")
		)
		(fill yes
			(thermal_gap 0.5)
			(thermal_bridge_width 0.5)
			(island_removal_mode 0)
		)
		(polygon
			(pts
				(arc
					(start 411.8864 -37.82695)
					(mid 410.1084 -37.82695)
					(end 411.8864 -37.82695)
				)
			)
		)
	)
	(zone
		(layers "In4.Cu" "In5.Cu")
		(hatch none 0.5)
		(connect_pads
			(clearance 0)
		)
		(min_thickness 0.25)
		(keepout
			(tracks not_allowed)
			(vias allowed)
			(pads allowed)
			(copperpour not_allowed)
			(footprints allowed)
		)
		(placement
			(enabled no)
			(sheetname "")
		)
		(fill yes
			(thermal_gap 0.5)
			(thermal_bridge_width 0.5)
			(island_removal_mode 0)
		)
		(polygon
			(pts
				(arc
					(start 447.90995 -45.4406)
					(mid 446.13195 -45.4406)
					(end 447.90995 -45.4406)
				)
			)
		)
	)
	(zone
		(layers "In4.Cu" "In5.Cu")
		(hatch none 0.5)
		(connect_pads
			(clearance 0)
		)
		(min_thickness 0.25)
		(keepout
			(tracks not_allowed)
			(vias allowed)
			(pads allowed)
			(copperpour not_allowed)
			(footprints allowed)
		)
		(placement
			(enabled no)
			(sheetname "")
		)
		(fill yes
			(thermal_gap 0.5)
			(thermal_bridge_width 0.5)
			(island_removal_mode 0)
		)
		(polygon
			(pts
				(arc
					(start 63.44539 -50.919888)
					(mid 60.39739 -50.919888)
					(end 63.44539 -50.919888)
				)
			)
		)
	)
	(zone
		(layers "In4.Cu" "In5.Cu")
		(hatch none 0.5)
		(connect_pads
			(clearance 0)
		)
		(min_thickness 0.25)
		(keepout
			(tracks not_allowed)
			(vias allowed)
			(pads allowed)
			(copperpour not_allowed)
			(footprints allowed)
		)
		(placement
			(enabled no)
			(sheetname "")
		)
		(fill yes
			(thermal_gap 0.5)
			(thermal_bridge_width 0.5)
			(island_removal_mode 0)
		)
		(polygon
			(pts
				(arc
					(start 40.83812 -162.830002)
					(mid 38.411912 -162.830002)
					(end 40.83812 -162.830002)
				)
			)
		)
	)
	(zone
		(layers "In4.Cu" "In5.Cu")
		(hatch none 0.5)
		(connect_pads
			(clearance 0)
		)
		(min_thickness 0.25)
		(keepout
			(tracks not_allowed)
			(vias allowed)
			(pads allowed)
			(copperpour not_allowed)
			(footprints allowed)
		)
		(placement
			(enabled no)
			(sheetname "")
		)
		(fill yes
			(thermal_gap 0.5)
			(thermal_bridge_width 0.5)
			(island_removal_mode 0)
		)
		(polygon
			(pts
				(arc
					(start 454.007728 -62.828678)
					(mid 452.229728 -62.828678)
					(end 454.007728 -62.828678)
				)
			)
		)
	)
	(zone
		(layers "In4.Cu" "In5.Cu")
		(hatch none 0.5)
		(connect_pads
			(clearance 0)
		)
		(min_thickness 0.25)
		(keepout
			(tracks not_allowed)
			(vias allowed)
			(pads allowed)
			(copperpour not_allowed)
			(footprints allowed)
		)
		(placement
			(enabled no)
			(sheetname "")
		)
		(fill yes
			(thermal_gap 0.5)
			(thermal_bridge_width 0.5)
			(island_removal_mode 0)
		)
		(polygon
			(pts
				(arc
					(start 429.126904 -37.592)
					(mid 427.348904 -37.592)
					(end 429.126904 -37.592)
				)
			)
		)
	)
	(zone
		(layers "In4.Cu" "In5.Cu")
		(hatch none 0.5)
		(connect_pads
			(clearance 0)
		)
		(min_thickness 0.25)
		(keepout
			(tracks not_allowed)
			(vias allowed)
			(pads allowed)
			(copperpour not_allowed)
			(footprints allowed)
		)
		(placement
			(enabled no)
			(sheetname "")
		)
		(fill yes
			(thermal_gap 0.5)
			(thermal_bridge_width 0.5)
			(island_removal_mode 0)
		)
		(polygon
			(pts
				(arc
					(start 70.21322 -166.829994)
					(mid 67.787012 -166.829994)
					(end 70.21322 -166.829994)
				)
			)
		)
	)
	(zone
		(layers "In4.Cu" "In5.Cu")
		(hatch none 0.5)
		(connect_pads
			(clearance 0)
		)
		(min_thickness 0.25)
		(keepout
			(tracks not_allowed)
			(vias allowed)
			(pads allowed)
			(copperpour not_allowed)
			(footprints allowed)
		)
		(placement
			(enabled no)
			(sheetname "")
		)
		(fill yes
			(thermal_gap 0.5)
			(thermal_bridge_width 0.5)
			(island_removal_mode 0)
		)
		(polygon
			(pts
				(arc
					(start 76.213208 -164.829998)
					(mid 73.787 -164.829998)
					(end 76.213208 -164.829998)
				)
			)
		)
	)
	(zone
		(layers "In4.Cu" "In5.Cu")
		(hatch none 0.5)
		(connect_pads
			(clearance 0)
		)
		(min_thickness 0.25)
		(keepout
			(tracks not_allowed)
			(vias allowed)
			(pads allowed)
			(copperpour not_allowed)
			(footprints allowed)
		)
		(placement
			(enabled no)
			(sheetname "")
		)
		(fill yes
			(thermal_gap 0.5)
			(thermal_bridge_width 0.5)
			(island_removal_mode 0)
		)
		(polygon
			(pts
				(arc
					(start 42.838116 -154.830018)
					(mid 40.411908 -154.830018)
					(end 42.838116 -154.830018)
				)
			)
		)
	)
	(zone
		(layers "In4.Cu" "In5.Cu")
		(hatch none 0.5)
		(connect_pads
			(clearance 0)
		)
		(min_thickness 0.25)
		(keepout
			(tracks not_allowed)
			(vias allowed)
			(pads allowed)
			(copperpour not_allowed)
			(footprints allowed)
		)
		(placement
			(enabled no)
			(sheetname "")
		)
		(fill yes
			(thermal_gap 0.5)
			(thermal_bridge_width 0.5)
			(island_removal_mode 0)
		)
		(polygon
			(pts
				(arc
					(start 63.44539 -132.199888)
					(mid 60.39739 -132.199888)
					(end 63.44539 -132.199888)
				)
			)
		)
	)
	(zone
		(layers "In4.Cu" "In5.Cu")
		(hatch none 0.5)
		(connect_pads
			(clearance 0)
		)
		(min_thickness 0.25)
		(keepout
			(tracks not_allowed)
			(vias allowed)
			(pads allowed)
			(copperpour not_allowed)
			(footprints allowed)
		)
		(placement
			(enabled no)
			(sheetname "")
		)
		(fill yes
			(thermal_gap 0.5)
			(thermal_bridge_width 0.5)
			(island_removal_mode 0)
		)
		(polygon
			(pts
				(arc
					(start 448.3354 -31.629096)
					(mid 446.5574 -31.629096)
					(end 448.3354 -31.629096)
				)
			)
		)
	)
	(zone
		(layers "In4.Cu" "In5.Cu")
		(hatch none 0.5)
		(connect_pads
			(clearance 0)
		)
		(min_thickness 0.25)
		(keepout
			(tracks not_allowed)
			(vias allowed)
			(pads allowed)
			(copperpour not_allowed)
			(footprints allowed)
		)
		(placement
			(enabled no)
			(sheetname "")
		)
		(fill yes
			(thermal_gap 0.5)
			(thermal_bridge_width 0.5)
			(island_removal_mode 0)
		)
		(polygon
			(pts
				(arc
					(start 343.61374 -9.878822)
					(mid 341.83574 -9.878822)
					(end 343.61374 -9.878822)
				)
			)
		)
	)
	(zone
		(layers "In4.Cu" "In5.Cu")
		(hatch none 0.5)
		(connect_pads
			(clearance 0)
		)
		(min_thickness 0.25)
		(keepout
			(tracks not_allowed)
			(vias allowed)
			(pads allowed)
			(copperpour not_allowed)
			(footprints allowed)
		)
		(placement
			(enabled no)
			(sheetname "")
		)
		(fill yes
			(thermal_gap 0.5)
			(thermal_bridge_width 0.5)
			(island_removal_mode 0)
		)
		(polygon
			(pts
				(arc
					(start 435.1274 -40.132)
					(mid 433.3494 -40.132)
					(end 435.1274 -40.132)
				)
			)
		)
	)
	(zone
		(layers "In4.Cu" "In5.Cu")
		(hatch none 0.5)
		(connect_pads
			(clearance 0)
		)
		(min_thickness 0.25)
		(keepout
			(tracks not_allowed)
			(vias allowed)
			(pads allowed)
			(copperpour not_allowed)
			(footprints allowed)
		)
		(placement
			(enabled no)
			(sheetname "")
		)
		(fill yes
			(thermal_gap 0.5)
			(thermal_bridge_width 0.5)
			(island_removal_mode 0)
		)
		(polygon
			(pts
				(arc
					(start 50.013108 -164.829998)
					(mid 47.5869 -164.829998)
					(end 50.013108 -164.829998)
				)
			)
		)
	)
	(zone
		(layers "In4.Cu" "In5.Cu")
		(hatch none 0.5)
		(connect_pads
			(clearance 0)
		)
		(min_thickness 0.25)
		(keepout
			(tracks not_allowed)
			(vias allowed)
			(pads allowed)
			(copperpour not_allowed)
			(footprints allowed)
		)
		(placement
			(enabled no)
			(sheetname "")
		)
		(fill yes
			(thermal_gap 0.5)
			(thermal_bridge_width 0.5)
			(island_removal_mode 0)
		)
		(polygon
			(pts
				(arc
					(start 380.549912 -21.209)
					(mid 378.771912 -21.209)
					(end 380.549912 -21.209)
				)
			)
		)
	)
	(zone
		(layers "In4.Cu" "In5.Cu")
		(hatch none 0.5)
		(connect_pads
			(clearance 0)
		)
		(min_thickness 0.25)
		(keepout
			(tracks not_allowed)
			(vias allowed)
			(pads allowed)
			(copperpour not_allowed)
			(footprints allowed)
		)
		(placement
			(enabled no)
			(sheetname "")
		)
		(fill yes
			(thermal_gap 0.5)
			(thermal_bridge_width 0.5)
			(island_removal_mode 0)
		)
		(polygon
			(pts
				(arc
					(start 426.5422 -30.5816)
					(mid 424.7642 -30.5816)
					(end 426.5422 -30.5816)
				)
			)
		)
	)
	(zone
		(layers "In4.Cu" "In5.Cu")
		(hatch none 0.5)
		(connect_pads
			(clearance 0)
		)
		(min_thickness 0.25)
		(keepout
			(tracks not_allowed)
			(vias allowed)
			(pads allowed)
			(copperpour not_allowed)
			(footprints allowed)
		)
		(placement
			(enabled no)
			(sheetname "")
		)
		(fill yes
			(thermal_gap 0.5)
			(thermal_bridge_width 0.5)
			(island_removal_mode 0)
		)
		(polygon
			(pts
				(arc
					(start 421.679878 -32.35071)
					(mid 419.901878 -32.35071)
					(end 421.679878 -32.35071)
				)
			)
		)
	)
	(zone
		(layers "In4.Cu" "In5.Cu")
		(hatch none 0.5)
		(connect_pads
			(clearance 0)
		)
		(min_thickness 0.25)
		(keepout
			(tracks not_allowed)
			(vias allowed)
			(pads allowed)
			(copperpour not_allowed)
			(footprints allowed)
		)
		(placement
			(enabled no)
			(sheetname "")
		)
		(fill yes
			(thermal_gap 0.5)
			(thermal_bridge_width 0.5)
			(island_removal_mode 0)
		)
		(polygon
			(pts
				(arc
					(start 61.202062 -24.32812)
					(mid 59.424062 -24.32812)
					(end 61.202062 -24.32812)
				)
			)
		)
	)
	(zone
		(layers "In4.Cu" "In5.Cu")
		(hatch none 0.5)
		(connect_pads
			(clearance 0)
		)
		(min_thickness 0.25)
		(keepout
			(tracks not_allowed)
			(vias allowed)
			(pads allowed)
			(copperpour not_allowed)
			(footprints allowed)
		)
		(placement
			(enabled no)
			(sheetname "")
		)
		(fill yes
			(thermal_gap 0.5)
			(thermal_bridge_width 0.5)
			(island_removal_mode 0)
		)
		(polygon
			(pts
				(arc
					(start 414.87598 -26.47696)
					(mid 413.09798 -26.47696)
					(end 414.87598 -26.47696)
				)
			)
		)
	)
	(zone
		(layers "In4.Cu" "In5.Cu")
		(hatch none 0.5)
		(connect_pads
			(clearance 0)
		)
		(min_thickness 0.25)
		(keepout
			(tracks not_allowed)
			(vias allowed)
			(pads allowed)
			(copperpour not_allowed)
			(footprints allowed)
		)
		(placement
			(enabled no)
			(sheetname "")
		)
		(fill yes
			(thermal_gap 0.5)
			(thermal_bridge_width 0.5)
			(island_removal_mode 0)
		)
		(polygon
			(pts
				(arc
					(start 412.95193 -29.19476)
					(mid 411.17393 -29.19476)
					(end 412.95193 -29.19476)
				)
			)
		)
	)
	(zone
		(layers "In4.Cu" "In5.Cu")
		(hatch none 0.5)
		(connect_pads
			(clearance 0)
		)
		(min_thickness 0.25)
		(keepout
			(tracks not_allowed)
			(vias allowed)
			(pads allowed)
			(copperpour not_allowed)
			(footprints allowed)
		)
		(placement
			(enabled no)
			(sheetname "")
		)
		(fill yes
			(thermal_gap 0.5)
			(thermal_bridge_width 0.5)
			(island_removal_mode 0)
		)
		(polygon
			(pts
				(arc
					(start 433.8574 -51.181)
					(mid 432.0794 -51.181)
					(end 433.8574 -51.181)
				)
			)
		)
	)
	(zone
		(layers "In4.Cu" "In5.Cu")
		(hatch none 0.5)
		(connect_pads
			(clearance 0)
		)
		(min_thickness 0.25)
		(keepout
			(tracks not_allowed)
			(vias allowed)
			(pads allowed)
			(copperpour not_allowed)
			(footprints allowed)
		)
		(placement
			(enabled no)
			(sheetname "")
		)
		(fill yes
			(thermal_gap 0.5)
			(thermal_bridge_width 0.5)
			(island_removal_mode 0)
		)
		(polygon
			(pts
				(arc
					(start 448.92595 -39.492936)
					(mid 447.14795 -39.492936)
					(end 448.92595 -39.492936)
				)
			)
		)
	)
	(zone
		(layers "In4.Cu" "In5.Cu")
		(hatch none 0.5)
		(connect_pads
			(clearance 0)
		)
		(min_thickness 0.25)
		(keepout
			(tracks not_allowed)
			(vias allowed)
			(pads allowed)
			(copperpour not_allowed)
			(footprints allowed)
		)
		(placement
			(enabled no)
			(sheetname "")
		)
		(fill yes
			(thermal_gap 0.5)
			(thermal_bridge_width 0.5)
			(island_removal_mode 0)
		)
		(polygon
			(pts
				(arc
					(start 408.8384 -16.764)
					(mid 407.0604 -16.764)
					(end 408.8384 -16.764)
				)
			)
		)
	)
	(zone
		(layers "In4.Cu" "In5.Cu")
		(hatch none 0.5)
		(connect_pads
			(clearance 0)
		)
		(min_thickness 0.25)
		(keepout
			(tracks not_allowed)
			(vias allowed)
			(pads allowed)
			(copperpour not_allowed)
			(footprints allowed)
		)
		(placement
			(enabled no)
			(sheetname "")
		)
		(fill yes
			(thermal_gap 0.5)
			(thermal_bridge_width 0.5)
			(island_removal_mode 0)
		)
		(polygon
			(pts
				(arc
					(start 344.37574 -9.878822)
					(mid 342.59774 -9.878822)
					(end 344.37574 -9.878822)
				)
			)
		)
	)
	(zone
		(layers "In4.Cu" "In5.Cu")
		(hatch none 0.5)
		(connect_pads
			(clearance 0)
		)
		(min_thickness 0.25)
		(keepout
			(tracks not_allowed)
			(vias allowed)
			(pads allowed)
			(copperpour not_allowed)
			(footprints allowed)
		)
		(placement
			(enabled no)
			(sheetname "")
		)
		(fill yes
			(thermal_gap 0.5)
			(thermal_bridge_width 0.5)
			(island_removal_mode 0)
		)
		(polygon
			(pts
				(arc
					(start 428.879 -33.782)
					(mid 427.101 -33.782)
					(end 428.879 -33.782)
				)
			)
		)
	)
	(zone
		(layers "In4.Cu" "In5.Cu")
		(hatch none 0.5)
		(connect_pads
			(clearance 0)
		)
		(min_thickness 0.25)
		(keepout
			(tracks not_allowed)
			(vias allowed)
			(pads allowed)
			(copperpour not_allowed)
			(footprints allowed)
		)
		(placement
			(enabled no)
			(sheetname "")
		)
		(fill yes
			(thermal_gap 0.5)
			(thermal_bridge_width 0.5)
			(island_removal_mode 0)
		)
		(polygon
			(pts
				(arc
					(start 415.245042 -29.24556)
					(mid 413.467042 -29.24556)
					(end 415.245042 -29.24556)
				)
			)
		)
	)
	(zone
		(layers "In4.Cu" "In5.Cu")
		(hatch none 0.5)
		(connect_pads
			(clearance 0)
		)
		(min_thickness 0.25)
		(keepout
			(tracks not_allowed)
			(vias allowed)
			(pads allowed)
			(copperpour not_allowed)
			(footprints allowed)
		)
		(placement
			(enabled no)
			(sheetname "")
		)
		(fill yes
			(thermal_gap 0.5)
			(thermal_bridge_width 0.5)
			(island_removal_mode 0)
		)
		(polygon
			(pts
				(arc
					(start 366.213136 -164.829998)
					(mid 363.786928 -164.829998)
					(end 366.213136 -164.829998)
				)
			)
		)
	)
	(zone
		(layers "In4.Cu" "In5.Cu")
		(hatch none 0.5)
		(connect_pads
			(clearance 0)
		)
		(min_thickness 0.25)
		(keepout
			(tracks not_allowed)
			(vias allowed)
			(pads allowed)
			(copperpour not_allowed)
			(footprints allowed)
		)
		(placement
			(enabled no)
			(sheetname "")
		)
		(fill yes
			(thermal_gap 0.5)
			(thermal_bridge_width 0.5)
			(island_removal_mode 0)
		)
		(polygon
			(pts
				(arc
					(start 379.074172 -28.898342)
					(mid 377.296172 -28.898342)
					(end 379.074172 -28.898342)
				)
			)
		)
	)
	(zone
		(layers "In4.Cu" "In5.Cu")
		(hatch none 0.5)
		(connect_pads
			(clearance 0)
		)
		(min_thickness 0.25)
		(keepout
			(tracks not_allowed)
			(vias allowed)
			(pads allowed)
			(copperpour not_allowed)
			(footprints allowed)
		)
		(placement
			(enabled no)
			(sheetname "")
		)
		(fill yes
			(thermal_gap 0.5)
			(thermal_bridge_width 0.5)
			(island_removal_mode 0)
		)
		(polygon
			(pts
				(arc
					(start 61.186314 -23.44547)
					(mid 59.408314 -23.44547)
					(end 61.186314 -23.44547)
				)
			)
		)
	)
	(zone
		(layers "In4.Cu" "In5.Cu")
		(hatch none 0.5)
		(connect_pads
			(clearance 0)
		)
		(min_thickness 0.25)
		(keepout
			(tracks not_allowed)
			(vias allowed)
			(pads allowed)
			(copperpour not_allowed)
			(footprints allowed)
		)
		(placement
			(enabled no)
			(sheetname "")
		)
		(fill yes
			(thermal_gap 0.5)
			(thermal_bridge_width 0.5)
			(island_removal_mode 0)
		)
		(polygon
			(pts
				(arc
					(start 373.373142 -2.035048)
					(mid 370.946934 -2.035048)
					(end 373.373142 -2.035048)
				)
			)
		)
	)
	(zone
		(layers "In4.Cu" "In5.Cu")
		(hatch none 0.5)
		(connect_pads
			(clearance 0)
		)
		(min_thickness 0.25)
		(keepout
			(tracks not_allowed)
			(vias allowed)
			(pads allowed)
			(copperpour not_allowed)
			(footprints allowed)
		)
		(placement
			(enabled no)
			(sheetname "")
		)
		(fill yes
			(thermal_gap 0.5)
			(thermal_bridge_width 0.5)
			(island_removal_mode 0)
		)
		(polygon
			(pts
				(arc
					(start 461.01 -47.244)
					(mid 459.232 -47.244)
					(end 461.01 -47.244)
				)
			)
		)
	)
	(zone
		(layers "In4.Cu" "In5.Cu")
		(hatch none 0.5)
		(connect_pads
			(clearance 0)
		)
		(min_thickness 0.25)
		(keepout
			(tracks not_allowed)
			(vias allowed)
			(pads allowed)
			(copperpour not_allowed)
			(footprints allowed)
		)
		(placement
			(enabled no)
			(sheetname "")
		)
		(fill yes
			(thermal_gap 0.5)
			(thermal_bridge_width 0.5)
			(island_removal_mode 0)
		)
		(polygon
			(pts
				(arc
					(start 404.338282 -154.830018)
					(mid 401.912074 -154.830018)
					(end 404.338282 -154.830018)
				)
			)
		)
	)
	(zone
		(layers "In4.Cu" "In5.Cu")
		(hatch none 0.5)
		(connect_pads
			(clearance 0)
		)
		(min_thickness 0.25)
		(keepout
			(tracks not_allowed)
			(vias allowed)
			(pads allowed)
			(copperpour not_allowed)
			(footprints allowed)
		)
		(placement
			(enabled no)
			(sheetname "")
		)
		(fill yes
			(thermal_gap 0.5)
			(thermal_bridge_width 0.5)
			(island_removal_mode 0)
		)
		(polygon
			(pts
				(arc
					(start 420.24046 -30.996636)
					(mid 418.46246 -30.996636)
					(end 420.24046 -30.996636)
				)
			)
		)
	)
	(zone
		(layers "In4.Cu" "In5.Cu")
		(hatch none 0.5)
		(connect_pads
			(clearance 0)
		)
		(min_thickness 0.25)
		(keepout
			(tracks not_allowed)
			(vias allowed)
			(pads allowed)
			(copperpour not_allowed)
			(footprints allowed)
		)
		(placement
			(enabled no)
			(sheetname "")
		)
		(fill yes
			(thermal_gap 0.5)
			(thermal_bridge_width 0.5)
			(island_removal_mode 0)
		)
		(polygon
			(pts
				(arc
					(start 419.964108 -28.4353)
					(mid 418.236908 -28.4353)
					(end 419.964108 -28.4353)
				)
			)
		)
	)
	(zone
		(layers "In4.Cu" "In5.Cu")
		(hatch none 0.5)
		(connect_pads
			(clearance 0)
		)
		(min_thickness 0.25)
		(keepout
			(tracks not_allowed)
			(vias allowed)
			(pads allowed)
			(copperpour not_allowed)
			(footprints allowed)
		)
		(placement
			(enabled no)
			(sheetname "")
		)
		(fill yes
			(thermal_gap 0.5)
			(thermal_bridge_width 0.5)
			(island_removal_mode 0)
		)
		(polygon
			(pts
				(arc
					(start 81.601564 -9.959594)
					(mid 79.823564 -9.959594)
					(end 81.601564 -9.959594)
				)
			)
		)
	)
	(zone
		(layers "In4.Cu" "In5.Cu")
		(hatch none 0.5)
		(connect_pads
			(clearance 0)
		)
		(min_thickness 0.25)
		(keepout
			(tracks not_allowed)
			(vias allowed)
			(pads allowed)
			(copperpour not_allowed)
			(footprints allowed)
		)
		(placement
			(enabled no)
			(sheetname "")
		)
		(fill yes
			(thermal_gap 0.5)
			(thermal_bridge_width 0.5)
			(island_removal_mode 0)
		)
		(polygon
			(pts
				(arc
					(start 443.0014 -64.897)
					(mid 441.2234 -64.897)
					(end 443.0014 -64.897)
				)
			)
		)
	)
	(zone
		(layers "In4.Cu" "In5.Cu")
		(hatch none 0.5)
		(connect_pads
			(clearance 0)
		)
		(min_thickness 0.25)
		(keepout
			(tracks not_allowed)
			(vias allowed)
			(pads allowed)
			(copperpour not_allowed)
			(footprints allowed)
		)
		(placement
			(enabled no)
			(sheetname "")
		)
		(fill yes
			(thermal_gap 0.5)
			(thermal_bridge_width 0.5)
			(island_removal_mode 0)
		)
		(polygon
			(pts
				(arc
					(start 429.126904 -38.989)
					(mid 427.348904 -38.989)
					(end 429.126904 -38.989)
				)
			)
		)
	)
	(zone
		(layers "In4.Cu" "In5.Cu")
		(hatch none 0.5)
		(connect_pads
			(clearance 0)
		)
		(min_thickness 0.25)
		(keepout
			(tracks not_allowed)
			(vias allowed)
			(pads allowed)
			(copperpour not_allowed)
			(footprints allowed)
		)
		(placement
			(enabled no)
			(sheetname "")
		)
		(fill yes
			(thermal_gap 0.5)
			(thermal_bridge_width 0.5)
			(island_removal_mode 0)
		)
		(polygon
			(pts
				(arc
					(start 40.83812 -166.829994)
					(mid 38.411912 -166.829994)
					(end 40.83812 -166.829994)
				)
			)
		)
	)
	(zone
		(layers "In4.Cu" "In5.Cu")
		(hatch none 0.5)
		(connect_pads
			(clearance 0)
		)
		(min_thickness 0.25)
		(keepout
			(tracks not_allowed)
			(vias allowed)
			(pads allowed)
			(copperpour not_allowed)
			(footprints allowed)
		)
		(placement
			(enabled no)
			(sheetname "")
		)
		(fill yes
			(thermal_gap 0.5)
			(thermal_bridge_width 0.5)
			(island_removal_mode 0)
		)
		(polygon
			(pts
				(arc
					(start 85.344 -16.0782)
					(mid 83.566 -16.0782)
					(end 85.344 -16.0782)
				)
			)
		)
	)
	(zone
		(layers "In4.Cu" "In5.Cu")
		(hatch none 0.5)
		(connect_pads
			(clearance 0)
		)
		(min_thickness 0.25)
		(keepout
			(tracks not_allowed)
			(vias allowed)
			(pads allowed)
			(copperpour not_allowed)
			(footprints allowed)
		)
		(placement
			(enabled no)
			(sheetname "")
		)
		(fill yes
			(thermal_gap 0.5)
			(thermal_bridge_width 0.5)
			(island_removal_mode 0)
		)
		(polygon
			(pts
				(arc
					(start 386.412994 -164.829998)
					(mid 383.986786 -164.829998)
					(end 386.412994 -164.829998)
				)
			)
		)
	)
	(zone
		(layers "In4.Cu" "In5.Cu")
		(hatch none 0.5)
		(connect_pads
			(clearance 0)
		)
		(min_thickness 0.25)
		(keepout
			(tracks not_allowed)
			(vias allowed)
			(pads allowed)
			(copperpour not_allowed)
			(footprints allowed)
		)
		(placement
			(enabled no)
			(sheetname "")
		)
		(fill yes
			(thermal_gap 0.5)
			(thermal_bridge_width 0.5)
			(island_removal_mode 0)
		)
		(polygon
			(pts
				(arc
					(start 430.1744 -32.35325)
					(mid 428.3964 -32.35325)
					(end 430.1744 -32.35325)
				)
			)
		)
	)
	(zone
		(layers "In4.Cu" "In5.Cu")
		(hatch none 0.5)
		(connect_pads
			(clearance 0)
		)
		(min_thickness 0.25)
		(keepout
			(tracks not_allowed)
			(vias allowed)
			(pads allowed)
			(copperpour not_allowed)
			(footprints allowed)
		)
		(placement
			(enabled no)
			(sheetname "")
		)
		(fill yes
			(thermal_gap 0.5)
			(thermal_bridge_width 0.5)
			(island_removal_mode 0)
		)
		(polygon
			(pts
				(arc
					(start 376.213116 -164.829998)
					(mid 373.786908 -164.829998)
					(end 376.213116 -164.829998)
				)
			)
		)
	)
	(zone
		(layers "In4.Cu" "In5.Cu")
		(hatch none 0.5)
		(connect_pads
			(clearance 0)
		)
		(min_thickness 0.25)
		(keepout
			(tracks not_allowed)
			(vias allowed)
			(pads allowed)
			(copperpour not_allowed)
			(footprints allowed)
		)
		(placement
			(enabled no)
			(sheetname "")
		)
		(fill yes
			(thermal_gap 0.5)
			(thermal_bridge_width 0.5)
			(island_removal_mode 0)
		)
		(polygon
			(pts
				(arc
					(start 333.721964 -9.774428)
					(mid 331.943964 -9.774428)
					(end 333.721964 -9.774428)
				)
			)
		)
	)
	(zone
		(layers "In4.Cu" "In5.Cu")
		(hatch none 0.5)
		(connect_pads
			(clearance 0)
		)
		(min_thickness 0.25)
		(keepout
			(tracks not_allowed)
			(vias allowed)
			(pads allowed)
			(copperpour not_allowed)
			(footprints allowed)
		)
		(placement
			(enabled no)
			(sheetname "")
		)
		(fill yes
			(thermal_gap 0.5)
			(thermal_bridge_width 0.5)
			(island_removal_mode 0)
		)
		(polygon
			(pts
				(arc
					(start 52.013104 -164.829998)
					(mid 49.586896 -164.829998)
					(end 52.013104 -164.829998)
				)
			)
		)
	)
	(zone
		(layers "In4.Cu" "In5.Cu")
		(hatch none 0.5)
		(connect_pads
			(clearance 0)
		)
		(min_thickness 0.25)
		(keepout
			(tracks not_allowed)
			(vias allowed)
			(pads allowed)
			(copperpour not_allowed)
			(footprints allowed)
		)
		(placement
			(enabled no)
			(sheetname "")
		)
		(fill yes
			(thermal_gap 0.5)
			(thermal_bridge_width 0.5)
			(island_removal_mode 0)
		)
		(polygon
			(pts
				(arc
					(start 409.6004 -17.653)
					(mid 407.8224 -17.653)
					(end 409.6004 -17.653)
				)
			)
		)
	)
	(zone
		(layers "In4.Cu" "In5.Cu")
		(hatch none 0.5)
		(connect_pads
			(clearance 0)
		)
		(min_thickness 0.25)
		(keepout
			(tracks not_allowed)
			(vias allowed)
			(pads allowed)
			(copperpour not_allowed)
			(footprints allowed)
		)
		(placement
			(enabled no)
			(sheetname "")
		)
		(fill yes
			(thermal_gap 0.5)
			(thermal_bridge_width 0.5)
			(island_removal_mode 0)
		)
		(polygon
			(pts
				(arc
					(start 58.013092 -166.829994)
					(mid 55.586884 -166.829994)
					(end 58.013092 -166.829994)
				)
			)
		)
	)
	(zone
		(layers "In4.Cu" "In5.Cu")
		(hatch none 0.5)
		(connect_pads
			(clearance 0)
		)
		(min_thickness 0.25)
		(keepout
			(tracks not_allowed)
			(vias allowed)
			(pads allowed)
			(copperpour not_allowed)
			(footprints allowed)
		)
		(placement
			(enabled no)
			(sheetname "")
		)
		(fill yes
			(thermal_gap 0.5)
			(thermal_bridge_width 0.5)
			(island_removal_mode 0)
		)
		(polygon
			(pts
				(arc
					(start 437.43245 -23.749)
					(mid 435.65445 -23.749)
					(end 437.43245 -23.749)
				)
			)
		)
	)
	(zone
		(layers "In4.Cu" "In5.Cu")
		(hatch none 0.5)
		(connect_pads
			(clearance 0)
		)
		(min_thickness 0.25)
		(keepout
			(tracks not_allowed)
			(vias allowed)
			(pads allowed)
			(copperpour not_allowed)
			(footprints allowed)
		)
		(placement
			(enabled no)
			(sheetname "")
		)
		(fill yes
			(thermal_gap 0.5)
			(thermal_bridge_width 0.5)
			(island_removal_mode 0)
		)
		(polygon
			(pts
				(arc
					(start 445.7954 -59.817)
					(mid 444.0174 -59.817)
					(end 445.7954 -59.817)
				)
			)
		)
	)
	(zone
		(layers "In4.Cu" "In5.Cu")
		(hatch none 0.5)
		(connect_pads
			(clearance 0)
		)
		(min_thickness 0.25)
		(keepout
			(tracks not_allowed)
			(vias allowed)
			(pads allowed)
			(copperpour not_allowed)
			(footprints allowed)
		)
		(placement
			(enabled no)
			(sheetname "")
		)
		(fill yes
			(thermal_gap 0.5)
			(thermal_bridge_width 0.5)
			(island_removal_mode 0)
		)
		(polygon
			(pts
				(arc
					(start 438.19699 -24.36876)
					(mid 436.41899 -24.36876)
					(end 438.19699 -24.36876)
				)
			)
		)
	)
	(zone
		(layers "In4.Cu" "In5.Cu")
		(hatch none 0.5)
		(connect_pads
			(clearance 0)
		)
		(min_thickness 0.25)
		(keepout
			(tracks not_allowed)
			(vias allowed)
			(pads allowed)
			(copperpour not_allowed)
			(footprints allowed)
		)
		(placement
			(enabled no)
			(sheetname "")
		)
		(fill yes
			(thermal_gap 0.5)
			(thermal_bridge_width 0.5)
			(island_removal_mode 0)
		)
		(polygon
			(pts
				(arc
					(start 451.1294 -45.0342)
					(mid 449.3514 -45.0342)
					(end 451.1294 -45.0342)
				)
			)
		)
	)
	(zone
		(layers "In4.Cu" "In5.Cu")
		(hatch none 0.5)
		(connect_pads
			(clearance 0)
		)
		(min_thickness 0.25)
		(keepout
			(tracks not_allowed)
			(vias allowed)
			(pads allowed)
			(copperpour not_allowed)
			(footprints allowed)
		)
		(placement
			(enabled no)
			(sheetname "")
		)
		(fill yes
			(thermal_gap 0.5)
			(thermal_bridge_width 0.5)
			(island_removal_mode 0)
		)
		(polygon
			(pts
				(arc
					(start 413.512 -36.195)
					(mid 411.734 -36.195)
					(end 413.512 -36.195)
				)
			)
		)
	)
	(zone
		(layers "In4.Cu" "In5.Cu")
		(hatch none 0.5)
		(connect_pads
			(clearance 0)
		)
		(min_thickness 0.25)
		(keepout
			(tracks not_allowed)
			(vias allowed)
			(pads allowed)
			(copperpour not_allowed)
			(footprints allowed)
		)
		(placement
			(enabled no)
			(sheetname "")
		)
		(fill yes
			(thermal_gap 0.5)
			(thermal_bridge_width 0.5)
			(island_removal_mode 0)
		)
		(polygon
			(pts
				(arc
					(start 78.213204 -168.82999)
					(mid 75.786996 -168.82999)
					(end 78.213204 -168.82999)
				)
			)
		)
	)
	(zone
		(layers "In4.Cu" "In5.Cu")
		(hatch none 0.5)
		(connect_pads
			(clearance 0)
		)
		(min_thickness 0.25)
		(keepout
			(tracks not_allowed)
			(vias allowed)
			(pads allowed)
			(copperpour not_allowed)
			(footprints allowed)
		)
		(placement
			(enabled no)
			(sheetname "")
		)
		(fill yes
			(thermal_gap 0.5)
			(thermal_bridge_width 0.5)
			(island_removal_mode 0)
		)
		(polygon
			(pts
				(arc
					(start 74.783188 -5.845048)
					(mid 72.35698 -5.845048)
					(end 74.783188 -5.845048)
				)
			)
		)
	)
	(zone
		(layers "In4.Cu" "In5.Cu")
		(hatch none 0.5)
		(connect_pads
			(clearance 0)
		)
		(min_thickness 0.25)
		(keepout
			(tracks not_allowed)
			(vias allowed)
			(pads allowed)
			(copperpour not_allowed)
			(footprints allowed)
		)
		(placement
			(enabled no)
			(sheetname "")
		)
		(fill yes
			(thermal_gap 0.5)
			(thermal_bridge_width 0.5)
			(island_removal_mode 0)
		)
		(polygon
			(pts
				(arc
					(start 407.8224 -16.764)
					(mid 406.0444 -16.764)
					(end 407.8224 -16.764)
				)
			)
		)
	)
	(zone
		(layers "In4.Cu" "In5.Cu")
		(hatch none 0.5)
		(connect_pads
			(clearance 0)
		)
		(min_thickness 0.25)
		(keepout
			(tracks not_allowed)
			(vias allowed)
			(pads allowed)
			(copperpour not_allowed)
			(footprints allowed)
		)
		(placement
			(enabled no)
			(sheetname "")
		)
		(fill yes
			(thermal_gap 0.5)
			(thermal_bridge_width 0.5)
			(island_removal_mode 0)
		)
		(polygon
			(pts
				(arc
					(start 413.1564 -43.815)
					(mid 411.3784 -43.815)
					(end 413.1564 -43.815)
				)
			)
		)
	)
	(zone
		(layers "In4.Cu" "In5.Cu")
		(hatch none 0.5)
		(connect_pads
			(clearance 0)
		)
		(min_thickness 0.25)
		(keepout
			(tracks not_allowed)
			(vias allowed)
			(pads allowed)
			(copperpour not_allowed)
			(footprints allowed)
		)
		(placement
			(enabled no)
			(sheetname "")
		)
		(fill yes
			(thermal_gap 0.5)
			(thermal_bridge_width 0.5)
			(island_removal_mode 0)
		)
		(polygon
			(pts
				(arc
					(start 404.338282 -160.830006)
					(mid 401.912074 -160.830006)
					(end 404.338282 -160.830006)
				)
			)
		)
	)
	(zone
		(layers "In4.Cu" "In5.Cu")
		(hatch none 0.5)
		(connect_pads
			(clearance 0)
		)
		(min_thickness 0.25)
		(keepout
			(tracks not_allowed)
			(vias allowed)
			(pads allowed)
			(copperpour not_allowed)
			(footprints allowed)
		)
		(placement
			(enabled no)
			(sheetname "")
		)
		(fill yes
			(thermal_gap 0.5)
			(thermal_bridge_width 0.5)
			(island_removal_mode 0)
		)
		(polygon
			(pts
				(arc
					(start 406.338278 -156.830014)
					(mid 403.91207 -156.830014)
					(end 406.338278 -156.830014)
				)
			)
		)
	)
	(zone
		(layers "In4.Cu" "In5.Cu")
		(hatch none 0.5)
		(connect_pads
			(clearance 0)
		)
		(min_thickness 0.25)
		(keepout
			(tracks not_allowed)
			(vias allowed)
			(pads allowed)
			(copperpour not_allowed)
			(footprints allowed)
		)
		(placement
			(enabled no)
			(sheetname "")
		)
		(fill yes
			(thermal_gap 0.5)
			(thermal_bridge_width 0.5)
			(island_removal_mode 0)
		)
		(polygon
			(pts
				(arc
					(start 436.2704 -36.81095)
					(mid 434.4924 -36.81095)
					(end 436.2704 -36.81095)
				)
			)
		)
	)
	(zone
		(layers "In4.Cu" "In5.Cu")
		(hatch none 0.5)
		(connect_pads
			(clearance 0)
		)
		(min_thickness 0.25)
		(keepout
			(tracks not_allowed)
			(vias allowed)
			(pads allowed)
			(copperpour not_allowed)
			(footprints allowed)
		)
		(placement
			(enabled no)
			(sheetname "")
		)
		(fill yes
			(thermal_gap 0.5)
			(thermal_bridge_width 0.5)
			(island_removal_mode 0)
		)
		(polygon
			(pts
				(arc
					(start 455.4474 -61.849)
					(mid 453.6694 -61.849)
					(end 455.4474 -61.849)
				)
			)
		)
	)
	(zone
		(layers "In4.Cu" "In5.Cu")
		(hatch none 0.5)
		(connect_pads
			(clearance 0)
		)
		(min_thickness 0.25)
		(keepout
			(tracks not_allowed)
			(vias allowed)
			(pads allowed)
			(copperpour not_allowed)
			(footprints allowed)
		)
		(placement
			(enabled no)
			(sheetname "")
		)
		(fill yes
			(thermal_gap 0.5)
			(thermal_bridge_width 0.5)
			(island_removal_mode 0)
		)
		(polygon
			(pts
				(arc
					(start 398.653254 -58.42)
					(mid 396.620746 -58.42)
					(end 398.653254 -58.42)
				)
			)
		)
	)
	(zone
		(layers "In4.Cu" "In5.Cu")
		(hatch none 0.5)
		(connect_pads
			(clearance 0)
		)
		(min_thickness 0.25)
		(keepout
			(tracks not_allowed)
			(vias allowed)
			(pads allowed)
			(copperpour not_allowed)
			(footprints allowed)
		)
		(placement
			(enabled no)
			(sheetname "")
		)
		(fill yes
			(thermal_gap 0.5)
			(thermal_bridge_width 0.5)
			(island_removal_mode 0)
		)
		(polygon
			(pts
				(arc
					(start 406.338278 -164.829998)
					(mid 403.91207 -164.829998)
					(end 406.338278 -164.829998)
				)
			)
		)
	)
	(zone
		(layers "In4.Cu" "In5.Cu")
		(hatch none 0.5)
		(connect_pads
			(clearance 0)
		)
		(min_thickness 0.25)
		(keepout
			(tracks not_allowed)
			(vias allowed)
			(pads allowed)
			(copperpour not_allowed)
			(footprints allowed)
		)
		(placement
			(enabled no)
			(sheetname "")
		)
		(fill yes
			(thermal_gap 0.5)
			(thermal_bridge_width 0.5)
			(island_removal_mode 0)
		)
		(polygon
			(pts
				(arc
					(start 42.838116 -164.829998)
					(mid 40.411908 -164.829998)
					(end 42.838116 -164.829998)
				)
			)
		)
	)
	(zone
		(layers "In4.Cu" "In5.Cu")
		(hatch none 0.5)
		(connect_pads
			(clearance 0)
		)
		(min_thickness 0.25)
		(keepout
			(tracks not_allowed)
			(vias allowed)
			(pads allowed)
			(copperpour not_allowed)
			(footprints allowed)
		)
		(placement
			(enabled no)
			(sheetname "")
		)
		(fill yes
			(thermal_gap 0.5)
			(thermal_bridge_width 0.5)
			(island_removal_mode 0)
		)
		(polygon
			(pts
				(arc
					(start 367.333022 -5.290058)
					(mid 364.906814 -5.290058)
					(end 367.333022 -5.290058)
				)
			)
		)
	)
	(zone
		(layers "In4.Cu" "In5.Cu")
		(hatch none 0.5)
		(connect_pads
			(clearance 0)
		)
		(min_thickness 0.25)
		(keepout
			(tracks not_allowed)
			(vias allowed)
			(pads allowed)
			(copperpour not_allowed)
			(footprints allowed)
		)
		(placement
			(enabled no)
			(sheetname "")
		)
		(fill yes
			(thermal_gap 0.5)
			(thermal_bridge_width 0.5)
			(island_removal_mode 0)
		)
		(polygon
			(pts
				(arc
					(start 410.8704 -33.02)
					(mid 409.0924 -33.02)
					(end 410.8704 -33.02)
				)
			)
		)
	)
	(zone
		(layers "In4.Cu" "In5.Cu")
		(hatch none 0.5)
		(connect_pads
			(clearance 0)
		)
		(min_thickness 0.25)
		(keepout
			(tracks not_allowed)
			(vias allowed)
			(pads allowed)
			(copperpour not_allowed)
			(footprints allowed)
		)
		(placement
			(enabled no)
			(sheetname "")
		)
		(fill yes
			(thermal_gap 0.5)
			(thermal_bridge_width 0.5)
			(island_removal_mode 0)
		)
		(polygon
			(pts
				(arc
					(start 429.6664 -36.97224)
					(mid 427.8884 -36.97224)
					(end 429.6664 -36.97224)
				)
			)
		)
	)
	(zone
		(layers "In4.Cu" "In5.Cu")
		(hatch none 0.5)
		(connect_pads
			(clearance 0)
		)
		(min_thickness 0.25)
		(keepout
			(tracks not_allowed)
			(vias allowed)
			(pads allowed)
			(copperpour not_allowed)
			(footprints allowed)
		)
		(placement
			(enabled no)
			(sheetname "")
		)
		(fill yes
			(thermal_gap 0.5)
			(thermal_bridge_width 0.5)
			(island_removal_mode 0)
		)
		(polygon
			(pts
				(arc
					(start 379.836172 -28.136342)
					(mid 378.058172 -28.136342)
					(end 379.836172 -28.136342)
				)
			)
		)
	)
	(zone
		(layers "In4.Cu" "In5.Cu")
		(hatch none 0.5)
		(connect_pads
			(clearance 0)
		)
		(min_thickness 0.25)
		(keepout
			(tracks not_allowed)
			(vias allowed)
			(pads allowed)
			(copperpour not_allowed)
			(footprints allowed)
		)
		(placement
			(enabled no)
			(sheetname "")
		)
		(fill yes
			(thermal_gap 0.5)
			(thermal_bridge_width 0.5)
			(island_removal_mode 0)
		)
		(polygon
			(pts
				(arc
					(start 221.1324 -7.112)
					(mid 219.3544 -7.112)
					(end 221.1324 -7.112)
				)
			)
		)
	)
	(zone
		(layers "In4.Cu" "In5.Cu")
		(hatch none 0.5)
		(connect_pads
			(clearance 0)
		)
		(min_thickness 0.25)
		(keepout
			(tracks not_allowed)
			(vias allowed)
			(pads allowed)
			(copperpour not_allowed)
			(footprints allowed)
		)
		(placement
			(enabled no)
			(sheetname "")
		)
		(fill yes
			(thermal_gap 0.5)
			(thermal_bridge_width 0.5)
			(island_removal_mode 0)
		)
		(polygon
			(pts
				(arc
					(start 83.185 -19.558)
					(mid 81.407 -19.558)
					(end 83.185 -19.558)
				)
			)
		)
	)
	(zone
		(layers "In4.Cu" "In5.Cu")
		(hatch none 0.5)
		(connect_pads
			(clearance 0)
		)
		(min_thickness 0.25)
		(keepout
			(tracks not_allowed)
			(vias allowed)
			(pads allowed)
			(copperpour not_allowed)
			(footprints allowed)
		)
		(placement
			(enabled no)
			(sheetname "")
		)
		(fill yes
			(thermal_gap 0.5)
			(thermal_bridge_width 0.5)
			(island_removal_mode 0)
		)
		(polygon
			(pts
				(arc
					(start 436.63235 -42.799)
					(mid 434.85435 -42.799)
					(end 436.63235 -42.799)
				)
			)
		)
	)
	(zone
		(layers "In4.Cu" "In5.Cu")
		(hatch none 0.5)
		(connect_pads
			(clearance 0)
		)
		(min_thickness 0.25)
		(keepout
			(tracks not_allowed)
			(vias allowed)
			(pads allowed)
			(copperpour not_allowed)
			(footprints allowed)
		)
		(placement
			(enabled no)
			(sheetname "")
		)
		(fill yes
			(thermal_gap 0.5)
			(thermal_bridge_width 0.5)
			(island_removal_mode 0)
		)
		(polygon
			(pts
				(arc
					(start 377.550172 -28.136342)
					(mid 375.772172 -28.136342)
					(end 377.550172 -28.136342)
				)
			)
		)
	)
	(zone
		(layers "In4.Cu" "In5.Cu")
		(hatch none 0.5)
		(connect_pads
			(clearance 0)
		)
		(min_thickness 0.25)
		(keepout
			(tracks not_allowed)
			(vias allowed)
			(pads allowed)
			(copperpour not_allowed)
			(footprints allowed)
		)
		(placement
			(enabled no)
			(sheetname "")
		)
		(fill yes
			(thermal_gap 0.5)
			(thermal_bridge_width 0.5)
			(island_removal_mode 0)
		)
		(polygon
			(pts
				(arc
					(start 58.013092 -164.829998)
					(mid 55.586884 -164.829998)
					(end 58.013092 -164.829998)
				)
			)
		)
	)
	(zone
		(layers "In4.Cu" "In5.Cu")
		(hatch none 0.5)
		(connect_pads
			(clearance 0)
		)
		(min_thickness 0.25)
		(keepout
			(tracks not_allowed)
			(vias allowed)
			(pads allowed)
			(copperpour not_allowed)
			(footprints allowed)
		)
		(placement
			(enabled no)
			(sheetname "")
		)
		(fill yes
			(thermal_gap 0.5)
			(thermal_bridge_width 0.5)
			(island_removal_mode 0)
		)
		(polygon
			(pts
				(arc
					(start 72.213216 -168.82999)
					(mid 69.787008 -168.82999)
					(end 72.213216 -168.82999)
				)
			)
		)
	)
	(zone
		(layers "In4.Cu" "In5.Cu")
		(hatch none 0.5)
		(connect_pads
			(clearance 0)
		)
		(min_thickness 0.25)
		(keepout
			(tracks not_allowed)
			(vias allowed)
			(pads allowed)
			(copperpour not_allowed)
			(footprints allowed)
		)
		(placement
			(enabled no)
			(sheetname "")
		)
		(fill yes
			(thermal_gap 0.5)
			(thermal_bridge_width 0.5)
			(island_removal_mode 0)
		)
		(polygon
			(pts
				(arc
					(start 377.183142 -5.845048)
					(mid 374.756934 -5.845048)
					(end 377.183142 -5.845048)
				)
			)
		)
	)
	(zone
		(layers "In4.Cu" "In5.Cu")
		(hatch none 0.5)
		(connect_pads
			(clearance 0)
		)
		(min_thickness 0.25)
		(keepout
			(tracks not_allowed)
			(vias allowed)
			(pads allowed)
			(copperpour not_allowed)
			(footprints allowed)
		)
		(placement
			(enabled no)
			(sheetname "")
		)
		(fill yes
			(thermal_gap 0.5)
			(thermal_bridge_width 0.5)
			(island_removal_mode 0)
		)
		(polygon
			(pts
				(arc
					(start 425.0182 -30.5816)
					(mid 423.2402 -30.5816)
					(end 425.0182 -30.5816)
				)
			)
		)
	)
	(zone
		(layers "In4.Cu" "In5.Cu")
		(hatch none 0.5)
		(connect_pads
			(clearance 0)
		)
		(min_thickness 0.25)
		(keepout
			(tracks not_allowed)
			(vias allowed)
			(pads allowed)
			(copperpour not_allowed)
			(footprints allowed)
		)
		(placement
			(enabled no)
			(sheetname "")
		)
		(fill yes
			(thermal_gap 0.5)
			(thermal_bridge_width 0.5)
			(island_removal_mode 0)
		)
		(polygon
			(pts
				(arc
					(start 420.6494 -53.848)
					(mid 418.8714 -53.848)
					(end 420.6494 -53.848)
				)
			)
		)
	)
	(zone
		(layers "In4.Cu" "In5.Cu")
		(hatch none 0.5)
		(connect_pads
			(clearance 0)
		)
		(min_thickness 0.25)
		(keepout
			(tracks not_allowed)
			(vias allowed)
			(pads allowed)
			(copperpour not_allowed)
			(footprints allowed)
		)
		(placement
			(enabled no)
			(sheetname "")
		)
		(fill yes
			(thermal_gap 0.5)
			(thermal_bridge_width 0.5)
			(island_removal_mode 0)
		)
		(polygon
			(pts
				(arc
					(start 392.412982 -166.829994)
					(mid 389.986774 -166.829994)
					(end 392.412982 -166.829994)
				)
			)
		)
	)
	(zone
		(layers "In4.Cu" "In5.Cu")
		(hatch none 0.5)
		(connect_pads
			(clearance 0)
		)
		(min_thickness 0.25)
		(keepout
			(tracks not_allowed)
			(vias allowed)
			(pads allowed)
			(copperpour not_allowed)
			(footprints allowed)
		)
		(placement
			(enabled no)
			(sheetname "")
		)
		(fill yes
			(thermal_gap 0.5)
			(thermal_bridge_width 0.5)
			(island_removal_mode 0)
		)
		(polygon
			(pts
				(arc
					(start 409.6004 -22.606)
					(mid 407.8224 -22.606)
					(end 409.6004 -22.606)
				)
			)
		)
	)
	(zone
		(layers "In4.Cu" "In5.Cu")
		(hatch none 0.5)
		(connect_pads
			(clearance 0)
		)
		(min_thickness 0.25)
		(keepout
			(tracks not_allowed)
			(vias allowed)
			(pads allowed)
			(copperpour not_allowed)
			(footprints allowed)
		)
		(placement
			(enabled no)
			(sheetname "")
		)
		(fill yes
			(thermal_gap 0.5)
			(thermal_bridge_width 0.5)
			(island_removal_mode 0)
		)
		(polygon
			(pts
				(arc
					(start 415.502344 -27.715718)
					(mid 413.724344 -27.715718)
					(end 415.502344 -27.715718)
				)
			)
		)
	)
	(zone
		(layers "In4.Cu" "In5.Cu")
		(hatch none 0.5)
		(connect_pads
			(clearance 0)
		)
		(min_thickness 0.25)
		(keepout
			(tracks not_allowed)
			(vias allowed)
			(pads allowed)
			(copperpour not_allowed)
			(footprints allowed)
		)
		(placement
			(enabled no)
			(sheetname "")
		)
		(fill yes
			(thermal_gap 0.5)
			(thermal_bridge_width 0.5)
			(island_removal_mode 0)
		)
		(polygon
			(pts
				(arc
					(start 449.566538 -60.908692)
					(mid 447.788538 -60.908692)
					(end 449.566538 -60.908692)
				)
			)
		)
	)
	(zone
		(layers "In4.Cu" "In5.Cu")
		(hatch none 0.5)
		(connect_pads
			(clearance 0)
		)
		(min_thickness 0.25)
		(keepout
			(tracks not_allowed)
			(vias allowed)
			(pads allowed)
			(copperpour not_allowed)
			(footprints allowed)
		)
		(placement
			(enabled no)
			(sheetname "")
		)
		(fill yes
			(thermal_gap 0.5)
			(thermal_bridge_width 0.5)
			(island_removal_mode 0)
		)
		(polygon
			(pts
				(arc
					(start 432.174904 -44.577)
					(mid 430.396904 -44.577)
					(end 432.174904 -44.577)
				)
			)
		)
	)
	(zone
		(layers "In4.Cu" "In5.Cu")
		(hatch none 0.5)
		(connect_pads
			(clearance 0)
		)
		(min_thickness 0.25)
		(keepout
			(tracks not_allowed)
			(vias allowed)
			(pads allowed)
			(copperpour not_allowed)
			(footprints allowed)
		)
		(placement
			(enabled no)
			(sheetname "")
		)
		(fill yes
			(thermal_gap 0.5)
			(thermal_bridge_width 0.5)
			(island_removal_mode 0)
		)
		(polygon
			(pts
				(arc
					(start 443.0014 -62.992)
					(mid 441.2234 -62.992)
					(end 443.0014 -62.992)
				)
			)
		)
	)
	(zone
		(layers "In4.Cu" "In5.Cu")
		(hatch none 0.5)
		(connect_pads
			(clearance 0)
		)
		(min_thickness 0.25)
		(keepout
			(tracks not_allowed)
			(vias allowed)
			(pads allowed)
			(copperpour not_allowed)
			(footprints allowed)
		)
		(placement
			(enabled no)
			(sheetname "")
		)
		(fill yes
			(thermal_gap 0.5)
			(thermal_bridge_width 0.5)
			(island_removal_mode 0)
		)
		(polygon
			(pts
				(arc
					(start 445.7954 -64.897)
					(mid 444.0174 -64.897)
					(end 445.7954 -64.897)
				)
			)
		)
	)
	(zone
		(layers "In4.Cu" "In5.Cu")
		(hatch none 0.5)
		(connect_pads
			(clearance 0)
		)
		(min_thickness 0.25)
		(keepout
			(tracks not_allowed)
			(vias allowed)
			(pads allowed)
			(copperpour not_allowed)
			(footprints allowed)
		)
		(placement
			(enabled no)
			(sheetname "")
		)
		(fill yes
			(thermal_gap 0.5)
			(thermal_bridge_width 0.5)
			(island_removal_mode 0)
		)
		(polygon
			(pts
				(arc
					(start 448.9704 -30.353)
					(mid 447.1924 -30.353)
					(end 448.9704 -30.353)
				)
			)
		)
	)
	(zone
		(layers "In4.Cu" "In5.Cu")
		(hatch none 0.5)
		(connect_pads
			(clearance 0)
		)
		(min_thickness 0.25)
		(keepout
			(tracks not_allowed)
			(vias allowed)
			(pads allowed)
			(copperpour not_allowed)
			(footprints allowed)
		)
		(placement
			(enabled no)
			(sheetname "")
		)
		(fill yes
			(thermal_gap 0.5)
			(thermal_bridge_width 0.5)
			(island_removal_mode 0)
		)
		(polygon
			(pts
				(arc
					(start 42.838116 -160.830006)
					(mid 40.411908 -160.830006)
					(end 42.838116 -160.830006)
				)
			)
		)
	)
	(zone
		(layers "In4.Cu" "In5.Cu")
		(hatch none 0.5)
		(connect_pads
			(clearance 0)
		)
		(min_thickness 0.25)
		(keepout
			(tracks not_allowed)
			(vias allowed)
			(pads allowed)
			(copperpour not_allowed)
			(footprints allowed)
		)
		(placement
			(enabled no)
			(sheetname "")
		)
		(fill yes
			(thermal_gap 0.5)
			(thermal_bridge_width 0.5)
			(island_removal_mode 0)
		)
		(polygon
			(pts
				(arc
					(start 417.264088 -29.0703)
					(mid 415.536888 -29.0703)
					(end 417.264088 -29.0703)
				)
			)
		)
	)
	(zone
		(layers "In4.Cu" "In5.Cu")
		(hatch none 0.5)
		(connect_pads
			(clearance 0)
		)
		(min_thickness 0.25)
		(keepout
			(tracks not_allowed)
			(vias allowed)
			(pads allowed)
			(copperpour not_allowed)
			(footprints allowed)
		)
		(placement
			(enabled no)
			(sheetname "")
		)
		(fill yes
			(thermal_gap 0.5)
			(thermal_bridge_width 0.5)
			(island_removal_mode 0)
		)
		(polygon
			(pts
				(arc
					(start 429.126904 -45.974)
					(mid 427.348904 -45.974)
					(end 429.126904 -45.974)
				)
			)
		)
	)
	(zone
		(layers "In4.Cu" "In5.Cu")
		(hatch none 0.5)
		(connect_pads
			(clearance 0)
		)
		(min_thickness 0.25)
		(keepout
			(tracks not_allowed)
			(vias allowed)
			(pads allowed)
			(copperpour not_allowed)
			(footprints allowed)
		)
		(placement
			(enabled no)
			(sheetname "")
		)
		(fill yes
			(thermal_gap 0.5)
			(thermal_bridge_width 0.5)
			(island_removal_mode 0)
		)
		(polygon
			(pts
				(arc
					(start 83.125564 -9.959594)
					(mid 81.347564 -9.959594)
					(end 83.125564 -9.959594)
				)
			)
		)
	)
	(zone
		(layers "In4.Cu" "In5.Cu")
		(hatch none 0.5)
		(connect_pads
			(clearance 0)
		)
		(min_thickness 0.25)
		(keepout
			(tracks not_allowed)
			(vias allowed)
			(pads allowed)
			(copperpour not_allowed)
			(footprints allowed)
		)
		(placement
			(enabled no)
			(sheetname "")
		)
		(fill yes
			(thermal_gap 0.5)
			(thermal_bridge_width 0.5)
			(island_removal_mode 0)
		)
		(polygon
			(pts
				(arc
					(start 413.385 -48.006)
					(mid 411.607 -48.006)
					(end 413.385 -48.006)
				)
			)
		)
	)
	(zone
		(layers "In4.Cu" "In5.Cu")
		(hatch none 0.5)
		(connect_pads
			(clearance 0)
		)
		(min_thickness 0.25)
		(keepout
			(tracks not_allowed)
			(vias allowed)
			(pads allowed)
			(copperpour not_allowed)
			(footprints allowed)
		)
		(placement
			(enabled no)
			(sheetname "")
		)
		(fill yes
			(thermal_gap 0.5)
			(thermal_bridge_width 0.5)
			(island_removal_mode 0)
		)
		(polygon
			(pts
				(arc
					(start 382.835912 -18.917158)
					(mid 381.057912 -18.917158)
					(end 382.835912 -18.917158)
				)
			)
		)
	)
	(zone
		(layers "In4.Cu" "In5.Cu")
		(hatch none 0.5)
		(connect_pads
			(clearance 0)
		)
		(min_thickness 0.25)
		(keepout
			(tracks not_allowed)
			(vias allowed)
			(pads allowed)
			(copperpour not_allowed)
			(footprints allowed)
		)
		(placement
			(enabled no)
			(sheetname "")
		)
		(fill yes
			(thermal_gap 0.5)
			(thermal_bridge_width 0.5)
			(island_removal_mode 0)
		)
		(polygon
			(pts
				(arc
					(start 345.0844 -40.64)
					(mid 343.3064 -40.64)
					(end 345.0844 -40.64)
				)
			)
		)
	)
	(zone
		(layers "In4.Cu" "In5.Cu")
		(hatch none 0.5)
		(connect_pads
			(clearance 0)
		)
		(min_thickness 0.25)
		(keepout
			(tracks not_allowed)
			(vias allowed)
			(pads allowed)
			(copperpour not_allowed)
			(footprints allowed)
		)
		(placement
			(enabled no)
			(sheetname "")
		)
		(fill yes
			(thermal_gap 0.5)
			(thermal_bridge_width 0.5)
			(island_removal_mode 0)
		)
		(polygon
			(pts
				(arc
					(start 78.213204 -164.829998)
					(mid 75.786996 -164.829998)
					(end 78.213204 -164.829998)
				)
			)
		)
	)
	(zone
		(layers "In4.Cu" "In5.Cu")
		(hatch none 0.5)
		(connect_pads
			(clearance 0)
		)
		(min_thickness 0.25)
		(keepout
			(tracks not_allowed)
			(vias allowed)
			(pads allowed)
			(copperpour not_allowed)
			(footprints allowed)
		)
		(placement
			(enabled no)
			(sheetname "")
		)
		(fill yes
			(thermal_gap 0.5)
			(thermal_bridge_width 0.5)
			(island_removal_mode 0)
		)
		(polygon
			(pts
				(arc
					(start 417.264088 -28.4353)
					(mid 415.536888 -28.4353)
					(end 417.264088 -28.4353)
				)
			)
		)
	)
	(zone
		(layers "In4.Cu" "In5.Cu")
		(hatch none 0.5)
		(connect_pads
			(clearance 0)
		)
		(min_thickness 0.25)
		(keepout
			(tracks not_allowed)
			(vias allowed)
			(pads allowed)
			(copperpour not_allowed)
			(footprints allowed)
		)
		(placement
			(enabled no)
			(sheetname "")
		)
		(fill yes
			(thermal_gap 0.5)
			(thermal_bridge_width 0.5)
			(island_removal_mode 0)
		)
		(polygon
			(pts
				(arc
					(start 66.213228 -168.82999)
					(mid 63.78702 -168.82999)
					(end 66.213228 -168.82999)
				)
			)
		)
	)
	(zone
		(layers "In4.Cu" "In5.Cu")
		(hatch none 0.5)
		(connect_pads
			(clearance 0)
		)
		(min_thickness 0.25)
		(keepout
			(tracks not_allowed)
			(vias allowed)
			(pads allowed)
			(copperpour not_allowed)
			(footprints allowed)
		)
		(placement
			(enabled no)
			(sheetname "")
		)
		(fill yes
			(thermal_gap 0.5)
			(thermal_bridge_width 0.5)
			(island_removal_mode 0)
		)
		(polygon
			(pts
				(arc
					(start 398.653254 -99.06)
					(mid 396.620746 -99.06)
					(end 398.653254 -99.06)
				)
			)
		)
	)
	(zone
		(layers "In4.Cu" "In5.Cu")
		(hatch none 0.5)
		(connect_pads
			(clearance 0)
		)
		(min_thickness 0.25)
		(keepout
			(tracks not_allowed)
			(vias allowed)
			(pads allowed)
			(copperpour not_allowed)
			(footprints allowed)
		)
		(placement
			(enabled no)
			(sheetname "")
		)
		(fill yes
			(thermal_gap 0.5)
			(thermal_bridge_width 0.5)
			(island_removal_mode 0)
		)
		(polygon
			(pts
				(arc
					(start 450.088 -40.13835)
					(mid 448.31 -40.13835)
					(end 450.088 -40.13835)
				)
			)
		)
	)
	(zone
		(layers "In4.Cu" "In5.Cu")
		(hatch none 0.5)
		(connect_pads
			(clearance 0)
		)
		(min_thickness 0.25)
		(keepout
			(tracks not_allowed)
			(vias allowed)
			(pads allowed)
			(copperpour not_allowed)
			(footprints allowed)
		)
		(placement
			(enabled no)
			(sheetname "")
		)
		(fill yes
			(thermal_gap 0.5)
			(thermal_bridge_width 0.5)
			(island_removal_mode 0)
		)
		(polygon
			(pts
				(arc
					(start 423.545 -51.435)
					(mid 421.767 -51.435)
					(end 423.545 -51.435)
				)
			)
		)
	)
	(zone
		(layers "In4.Cu" "In5.Cu")
		(hatch none 0.5)
		(connect_pads
			(clearance 0)
		)
		(min_thickness 0.25)
		(keepout
			(tracks not_allowed)
			(vias allowed)
			(pads allowed)
			(copperpour not_allowed)
			(footprints allowed)
		)
		(placement
			(enabled no)
			(sheetname "")
		)
		(fill yes
			(thermal_gap 0.5)
			(thermal_bridge_width 0.5)
			(island_removal_mode 0)
		)
		(polygon
			(pts
				(arc
					(start 427.399704 -49.46904)
					(mid 425.621704 -49.46904)
					(end 427.399704 -49.46904)
				)
			)
		)
	)
	(zone
		(layers "In4.Cu" "In5.Cu")
		(hatch none 0.5)
		(connect_pads
			(clearance 0)
		)
		(min_thickness 0.25)
		(keepout
			(tracks not_allowed)
			(vias allowed)
			(pads allowed)
			(copperpour not_allowed)
			(footprints allowed)
		)
		(placement
			(enabled no)
			(sheetname "")
		)
		(fill yes
			(thermal_gap 0.5)
			(thermal_bridge_width 0.5)
			(island_removal_mode 0)
		)
		(polygon
			(pts
				(arc
					(start 378.312172 -28.898342)
					(mid 376.534172 -28.898342)
					(end 378.312172 -28.898342)
				)
			)
		)
	)
	(zone
		(layers "In4.Cu" "In5.Cu")
		(hatch none 0.5)
		(connect_pads
			(clearance 0)
		)
		(min_thickness 0.25)
		(keepout
			(tracks not_allowed)
			(vias allowed)
			(pads allowed)
			(copperpour not_allowed)
			(footprints allowed)
		)
		(placement
			(enabled no)
			(sheetname "")
		)
		(fill yes
			(thermal_gap 0.5)
			(thermal_bridge_width 0.5)
			(island_removal_mode 0)
		)
		(polygon
			(pts
				(arc
					(start 372.213124 -168.82999)
					(mid 369.786916 -168.82999)
					(end 372.213124 -168.82999)
				)
			)
		)
	)
	(zone
		(layers "In4.Cu" "In5.Cu")
		(hatch none 0.5)
		(connect_pads
			(clearance 0)
		)
		(min_thickness 0.25)
		(keepout
			(tracks not_allowed)
			(vias allowed)
			(pads allowed)
			(copperpour not_allowed)
			(footprints allowed)
		)
		(placement
			(enabled no)
			(sheetname "")
		)
		(fill yes
			(thermal_gap 0.5)
			(thermal_bridge_width 0.5)
			(island_removal_mode 0)
		)
		(polygon
			(pts
				(arc
					(start 432.9684 -45.339)
					(mid 431.1904 -45.339)
					(end 432.9684 -45.339)
				)
			)
		)
	)
	(zone
		(layers "In4.Cu" "In5.Cu")
		(hatch none 0.5)
		(connect_pads
			(clearance 0)
		)
		(min_thickness 0.25)
		(keepout
			(tracks not_allowed)
			(vias allowed)
			(pads allowed)
			(copperpour not_allowed)
			(footprints allowed)
		)
		(placement
			(enabled no)
			(sheetname "")
		)
		(fill yes
			(thermal_gap 0.5)
			(thermal_bridge_width 0.5)
			(island_removal_mode 0)
		)
		(polygon
			(pts
				(arc
					(start 60.170314 -23.44547)
					(mid 58.392314 -23.44547)
					(end 60.170314 -23.44547)
				)
			)
		)
	)
	(zone
		(layers "In4.Cu" "In5.Cu")
		(hatch none 0.5)
		(connect_pads
			(clearance 0)
		)
		(min_thickness 0.25)
		(keepout
			(tracks not_allowed)
			(vias allowed)
			(pads allowed)
			(copperpour not_allowed)
			(footprints allowed)
		)
		(placement
			(enabled no)
			(sheetname "")
		)
		(fill yes
			(thermal_gap 0.5)
			(thermal_bridge_width 0.5)
			(island_removal_mode 0)
		)
		(polygon
			(pts
				(arc
					(start 437.1594 -40.132)
					(mid 435.3814 -40.132)
					(end 437.1594 -40.132)
				)
			)
		)
	)
	(zone
		(layers "In4.Cu" "In5.Cu")
		(hatch none 0.5)
		(connect_pads
			(clearance 0)
		)
		(min_thickness 0.25)
		(keepout
			(tracks not_allowed)
			(vias allowed)
			(pads allowed)
			(copperpour not_allowed)
			(footprints allowed)
		)
		(placement
			(enabled no)
			(sheetname "")
		)
		(fill yes
			(thermal_gap 0.5)
			(thermal_bridge_width 0.5)
			(island_removal_mode 0)
		)
		(polygon
			(pts
				(arc
					(start 82.55 -18.91665)
					(mid 80.772 -18.91665)
					(end 82.55 -18.91665)
				)
			)
		)
	)
	(zone
		(layers "In4.Cu" "In5.Cu")
		(hatch none 0.5)
		(connect_pads
			(clearance 0)
		)
		(min_thickness 0.25)
		(keepout
			(tracks not_allowed)
			(vias allowed)
			(pads allowed)
			(copperpour not_allowed)
			(footprints allowed)
		)
		(placement
			(enabled no)
			(sheetname "")
		)
		(fill yes
			(thermal_gap 0.5)
			(thermal_bridge_width 0.5)
			(island_removal_mode 0)
		)
		(polygon
			(pts
				(arc
					(start 415.31159 -47.949358)
					(mid 413.53359 -47.949358)
					(end 415.31159 -47.949358)
				)
			)
		)
	)
	(zone
		(layers "In4.Cu" "In5.Cu")
		(hatch none 0.5)
		(connect_pads
			(clearance 0)
		)
		(min_thickness 0.25)
		(keepout
			(tracks not_allowed)
			(vias allowed)
			(pads allowed)
			(copperpour not_allowed)
			(footprints allowed)
		)
		(placement
			(enabled no)
			(sheetname "")
		)
		(fill yes
			(thermal_gap 0.5)
			(thermal_bridge_width 0.5)
			(island_removal_mode 0)
		)
		(polygon
			(pts
				(arc
					(start 73.513188 -2.035048)
					(mid 71.08698 -2.035048)
					(end 73.513188 -2.035048)
				)
			)
		)
	)
	(zone
		(layers "In4.Cu" "In5.Cu")
		(hatch none 0.5)
		(connect_pads
			(clearance 0)
		)
		(min_thickness 0.25)
		(keepout
			(tracks not_allowed)
			(vias allowed)
			(pads allowed)
			(copperpour not_allowed)
			(footprints allowed)
		)
		(placement
			(enabled no)
			(sheetname "")
		)
		(fill yes
			(thermal_gap 0.5)
			(thermal_bridge_width 0.5)
			(island_removal_mode 0)
		)
		(polygon
			(pts
				(arc
					(start 404.338282 -164.829998)
					(mid 401.912074 -164.829998)
					(end 404.338282 -164.829998)
				)
			)
		)
	)
	(zone
		(layers "In4.Cu" "In5.Cu")
		(hatch none 0.5)
		(connect_pads
			(clearance 0)
		)
		(min_thickness 0.25)
		(keepout
			(tracks not_allowed)
			(vias allowed)
			(pads allowed)
			(copperpour not_allowed)
			(footprints allowed)
		)
		(placement
			(enabled no)
			(sheetname "")
		)
		(fill yes
			(thermal_gap 0.5)
			(thermal_bridge_width 0.5)
			(island_removal_mode 0)
		)
		(polygon
			(pts
				(arc
					(start 445.7954 -59.182)
					(mid 444.0174 -59.182)
					(end 445.7954 -59.182)
				)
			)
		)
	)
	(zone
		(layers "In4.Cu" "In5.Cu")
		(hatch none 0.5)
		(connect_pads
			(clearance 0)
		)
		(min_thickness 0.25)
		(keepout
			(tracks not_allowed)
			(vias allowed)
			(pads allowed)
			(copperpour not_allowed)
			(footprints allowed)
		)
		(placement
			(enabled no)
			(sheetname "")
		)
		(fill yes
			(thermal_gap 0.5)
			(thermal_bridge_width 0.5)
			(island_removal_mode 0)
		)
		(polygon
			(pts
				(arc
					(start 407.8224 -17.653)
					(mid 406.0444 -17.653)
					(end 407.8224 -17.653)
				)
			)
		)
	)
	(zone
		(layers "In4.Cu" "In5.Cu")
		(hatch none 0.5)
		(connect_pads
			(clearance 0)
		)
		(min_thickness 0.25)
		(keepout
			(tracks not_allowed)
			(vias allowed)
			(pads allowed)
			(copperpour not_allowed)
			(footprints allowed)
		)
		(placement
			(enabled no)
			(sheetname "")
		)
		(fill yes
			(thermal_gap 0.5)
			(thermal_bridge_width 0.5)
			(island_removal_mode 0)
		)
		(polygon
			(pts
				(arc
					(start 381.692912 -18.923)
					(mid 379.914912 -18.923)
					(end 381.692912 -18.923)
				)
			)
		)
	)
	(zone
		(layers "In4.Cu" "In5.Cu")
		(hatch none 0.5)
		(connect_pads
			(clearance 0)
		)
		(min_thickness 0.25)
		(keepout
			(tracks not_allowed)
			(vias allowed)
			(pads allowed)
			(copperpour not_allowed)
			(footprints allowed)
		)
		(placement
			(enabled no)
			(sheetname "")
		)
		(fill yes
			(thermal_gap 0.5)
			(thermal_bridge_width 0.5)
			(island_removal_mode 0)
		)
		(polygon
			(pts
				(arc
					(start 74.783188 -3.305048)
					(mid 72.35698 -3.305048)
					(end 74.783188 -3.305048)
				)
			)
		)
	)
	(zone
		(layers "In4.Cu" "In5.Cu")
		(hatch none 0.5)
		(connect_pads
			(clearance 0)
		)
		(min_thickness 0.25)
		(keepout
			(tracks not_allowed)
			(vias allowed)
			(pads allowed)
			(copperpour not_allowed)
			(footprints allowed)
		)
		(placement
			(enabled no)
			(sheetname "")
		)
		(fill yes
			(thermal_gap 0.5)
			(thermal_bridge_width 0.5)
			(island_removal_mode 0)
		)
		(polygon
			(pts
				(arc
					(start 40.83812 -168.82999)
					(mid 38.411912 -168.82999)
					(end 40.83812 -168.82999)
				)
			)
		)
	)
	(zone
		(layers "In4.Cu" "In5.Cu")
		(hatch none 0.5)
		(connect_pads
			(clearance 0)
		)
		(min_thickness 0.25)
		(keepout
			(tracks not_allowed)
			(vias allowed)
			(pads allowed)
			(copperpour not_allowed)
			(footprints allowed)
		)
		(placement
			(enabled no)
			(sheetname "")
		)
		(fill yes
			(thermal_gap 0.5)
			(thermal_bridge_width 0.5)
			(island_removal_mode 0)
		)
		(polygon
			(pts
				(arc
					(start 378.312172 -27.374342)
					(mid 376.534172 -27.374342)
					(end 378.312172 -27.374342)
				)
			)
		)
	)
	(zone
		(layers "In4.Cu" "In5.Cu")
		(hatch none 0.5)
		(connect_pads
			(clearance 0)
		)
		(min_thickness 0.25)
		(keepout
			(tracks not_allowed)
			(vias allowed)
			(pads allowed)
			(copperpour not_allowed)
			(footprints allowed)
		)
		(placement
			(enabled no)
			(sheetname "")
		)
		(fill yes
			(thermal_gap 0.5)
			(thermal_bridge_width 0.5)
			(island_removal_mode 0)
		)
		(polygon
			(pts
				(arc
					(start 67.473068 -5.290058)
					(mid 65.04686 -5.290058)
					(end 67.473068 -5.290058)
				)
			)
		)
	)
	(zone
		(layers "In4.Cu" "In5.Cu")
		(hatch none 0.5)
		(connect_pads
			(clearance 0)
		)
		(min_thickness 0.25)
		(keepout
			(tracks not_allowed)
			(vias allowed)
			(pads allowed)
			(copperpour not_allowed)
			(footprints allowed)
		)
		(placement
			(enabled no)
			(sheetname "")
		)
		(fill yes
			(thermal_gap 0.5)
			(thermal_bridge_width 0.5)
			(island_removal_mode 0)
		)
		(polygon
			(pts
				(arc
					(start 410.8704 -27.94)
					(mid 409.0924 -27.94)
					(end 410.8704 -27.94)
				)
			)
		)
	)
	(zone
		(layers "In4.Cu" "In5.Cu")
		(hatch none 0.5)
		(connect_pads
			(clearance 0)
		)
		(min_thickness 0.25)
		(keepout
			(tracks not_allowed)
			(vias allowed)
			(pads allowed)
			(copperpour not_allowed)
			(footprints allowed)
		)
		(placement
			(enabled no)
			(sheetname "")
		)
		(fill yes
			(thermal_gap 0.5)
			(thermal_bridge_width 0.5)
			(island_removal_mode 0)
		)
		(polygon
			(pts
				(arc
					(start 443.0014 -61.087)
					(mid 441.2234 -61.087)
					(end 443.0014 -61.087)
				)
			)
		)
	)
	(zone
		(layers "In4.Cu" "In5.Cu")
		(hatch none 0.5)
		(connect_pads
			(clearance 0)
		)
		(min_thickness 0.25)
		(keepout
			(tracks not_allowed)
			(vias allowed)
			(pads allowed)
			(copperpour not_allowed)
			(footprints allowed)
		)
		(placement
			(enabled no)
			(sheetname "")
		)
		(fill yes
			(thermal_gap 0.5)
			(thermal_bridge_width 0.5)
			(island_removal_mode 0)
		)
		(polygon
			(pts
				(arc
					(start 381.42672 -16.129)
					(mid 379.64872 -16.129)
					(end 381.42672 -16.129)
				)
			)
		)
	)
	(zone
		(layers "In4.Cu" "In5.Cu")
		(hatch none 0.5)
		(connect_pads
			(clearance 0)
		)
		(min_thickness 0.25)
		(keepout
			(tracks not_allowed)
			(vias allowed)
			(pads allowed)
			(copperpour not_allowed)
			(footprints allowed)
		)
		(placement
			(enabled no)
			(sheetname "")
		)
		(fill yes
			(thermal_gap 0.5)
			(thermal_bridge_width 0.5)
			(island_removal_mode 0)
		)
		(polygon
			(pts
				(arc
					(start 437.53405 -28.448)
					(mid 435.75605 -28.448)
					(end 437.53405 -28.448)
				)
			)
		)
	)
	(zone
		(layers "In4.Cu" "In5.Cu")
		(hatch none 0.5)
		(connect_pads
			(clearance 0)
		)
		(min_thickness 0.25)
		(keepout
			(tracks not_allowed)
			(vias allowed)
			(pads allowed)
			(copperpour not_allowed)
			(footprints allowed)
		)
		(placement
			(enabled no)
			(sheetname "")
		)
		(fill yes
			(thermal_gap 0.5)
			(thermal_bridge_width 0.5)
			(island_removal_mode 0)
		)
		(polygon
			(pts
				(arc
					(start 408.8384 -21.717)
					(mid 407.0604 -21.717)
					(end 408.8384 -21.717)
				)
			)
		)
	)
	(zone
		(layers "In4.Cu" "In5.Cu")
		(hatch none 0.5)
		(connect_pads
			(clearance 0)
		)
		(min_thickness 0.25)
		(keepout
			(tracks not_allowed)
			(vias allowed)
			(pads allowed)
			(copperpour not_allowed)
			(footprints allowed)
		)
		(placement
			(enabled no)
			(sheetname "")
		)
		(fill yes
			(thermal_gap 0.5)
			(thermal_bridge_width 0.5)
			(island_removal_mode 0)
		)
		(polygon
			(pts
				(arc
					(start 374.643142 -1.527048)
					(mid 372.216934 -1.527048)
					(end 374.643142 -1.527048)
				)
			)
		)
	)
	(zone
		(layers "In4.Cu" "In5.Cu")
		(hatch none 0.5)
		(connect_pads
			(clearance 0)
		)
		(min_thickness 0.25)
		(keepout
			(tracks not_allowed)
			(vias allowed)
			(pads allowed)
			(copperpour not_allowed)
			(footprints allowed)
		)
		(placement
			(enabled no)
			(sheetname "")
		)
		(fill yes
			(thermal_gap 0.5)
			(thermal_bridge_width 0.5)
			(island_removal_mode 0)
		)
		(polygon
			(pts
				(arc
					(start 83.4644 -16.256)
					(mid 81.6864 -16.256)
					(end 83.4644 -16.256)
				)
			)
		)
	)
	(zone
		(layers "In4.Cu" "In5.Cu")
		(hatch none 0.5)
		(connect_pads
			(clearance 0)
		)
		(min_thickness 0.25)
		(keepout
			(tracks not_allowed)
			(vias allowed)
			(pads allowed)
			(copperpour not_allowed)
			(footprints allowed)
		)
		(placement
			(enabled no)
			(sheetname "")
		)
		(fill yes
			(thermal_gap 0.5)
			(thermal_bridge_width 0.5)
			(island_removal_mode 0)
		)
		(polygon
			(pts
				(arc
					(start 416.5854 -44.069)
					(mid 414.8074 -44.069)
					(end 416.5854 -44.069)
				)
			)
		)
	)
	(zone
		(layers "In4.Cu" "In5.Cu")
		(hatch none 0.5)
		(connect_pads
			(clearance 0)
		)
		(min_thickness 0.25)
		(keepout
			(tracks not_allowed)
			(vias allowed)
			(pads allowed)
			(copperpour not_allowed)
			(footprints allowed)
		)
		(placement
			(enabled no)
			(sheetname "")
		)
		(fill yes
			(thermal_gap 0.5)
			(thermal_bridge_width 0.5)
			(island_removal_mode 0)
		)
		(polygon
			(pts
				(arc
					(start 76.213208 -168.82999)
					(mid 73.787 -168.82999)
					(end 76.213208 -168.82999)
				)
			)
		)
	)
	(zone
		(layers "In4.Cu" "In5.Cu")
		(hatch none 0.5)
		(connect_pads
			(clearance 0)
		)
		(min_thickness 0.25)
		(keepout
			(tracks not_allowed)
			(vias allowed)
			(pads allowed)
			(copperpour not_allowed)
			(footprints allowed)
		)
		(placement
			(enabled no)
			(sheetname "")
		)
		(fill yes
			(thermal_gap 0.5)
			(thermal_bridge_width 0.5)
			(island_removal_mode 0)
		)
		(polygon
			(pts
				(arc
					(start 406.338278 -166.829994)
					(mid 403.91207 -166.829994)
					(end 406.338278 -166.829994)
				)
			)
		)
	)
	(zone
		(layers "In4.Cu" "In5.Cu")
		(hatch none 0.5)
		(connect_pads
			(clearance 0)
		)
		(min_thickness 0.25)
		(keepout
			(tracks not_allowed)
			(vias allowed)
			(pads allowed)
			(copperpour not_allowed)
			(footprints allowed)
		)
		(placement
			(enabled no)
			(sheetname "")
		)
		(fill yes
			(thermal_gap 0.5)
			(thermal_bridge_width 0.5)
			(island_removal_mode 0)
		)
		(polygon
			(pts
				(arc
					(start 404.338282 -152.830022)
					(mid 401.912074 -152.830022)
					(end 404.338282 -152.830022)
				)
			)
		)
	)
	(zone
		(layers "In4.Cu" "In5.Cu")
		(hatch none 0.5)
		(connect_pads
			(clearance 0)
		)
		(min_thickness 0.25)
		(keepout
			(tracks not_allowed)
			(vias allowed)
			(pads allowed)
			(copperpour not_allowed)
			(footprints allowed)
		)
		(placement
			(enabled no)
			(sheetname "")
		)
		(fill yes
			(thermal_gap 0.5)
			(thermal_bridge_width 0.5)
			(island_removal_mode 0)
		)
		(polygon
			(pts
				(arc
					(start 406.00122 -29.21)
					(mid 404.22322 -29.21)
					(end 406.00122 -29.21)
				)
			)
		)
	)
	(zone
		(layers "In4.Cu" "In5.Cu")
		(hatch none 0.5)
		(connect_pads
			(clearance 0)
		)
		(min_thickness 0.25)
		(keepout
			(tracks not_allowed)
			(vias allowed)
			(pads allowed)
			(copperpour not_allowed)
			(footprints allowed)
		)
		(placement
			(enabled no)
			(sheetname "")
		)
		(fill yes
			(thermal_gap 0.5)
			(thermal_bridge_width 0.5)
			(island_removal_mode 0)
		)
		(polygon
			(pts
				(arc
					(start 448.92595 -43.429936)
					(mid 447.14795 -43.429936)
					(end 448.92595 -43.429936)
				)
			)
		)
	)
	(zone
		(layers "In4.Cu" "In5.Cu")
		(hatch none 0.5)
		(connect_pads
			(clearance 0)
		)
		(min_thickness 0.25)
		(keepout
			(tracks not_allowed)
			(vias allowed)
			(pads allowed)
			(copperpour not_allowed)
			(footprints allowed)
		)
		(placement
			(enabled no)
			(sheetname "")
		)
		(fill yes
			(thermal_gap 0.5)
			(thermal_bridge_width 0.5)
			(island_removal_mode 0)
		)
		(polygon
			(pts
				(arc
					(start 379.095254 -119.38)
					(mid 377.062746 -119.38)
					(end 379.095254 -119.38)
				)
			)
		)
	)
	(zone
		(layers "In4.Cu" "In5.Cu")
		(hatch none 0.5)
		(connect_pads
			(clearance 0)
		)
		(min_thickness 0.25)
		(keepout
			(tracks not_allowed)
			(vias allowed)
			(pads allowed)
			(copperpour not_allowed)
			(footprints allowed)
		)
		(placement
			(enabled no)
			(sheetname "")
		)
		(fill yes
			(thermal_gap 0.5)
			(thermal_bridge_width 0.5)
			(island_removal_mode 0)
		)
		(polygon
			(pts
				(arc
					(start 379.603 -132.199888)
					(mid 376.555 -132.199888)
					(end 379.603 -132.199888)
				)
			)
		)
	)
	(zone
		(layers "In4.Cu" "In5.Cu")
		(hatch none 0.5)
		(connect_pads
			(clearance 0)
		)
		(min_thickness 0.25)
		(keepout
			(tracks not_allowed)
			(vias allowed)
			(pads allowed)
			(copperpour not_allowed)
			(footprints allowed)
		)
		(placement
			(enabled no)
			(sheetname "")
		)
		(fill yes
			(thermal_gap 0.5)
			(thermal_bridge_width 0.5)
			(island_removal_mode 0)
		)
		(polygon
			(pts
				(arc
					(start 378.312172 -26.612342)
					(mid 376.534172 -26.612342)
					(end 378.312172 -26.612342)
				)
			)
		)
	)
	(zone
		(layers "In4.Cu" "In5.Cu")
		(hatch none 0.5)
		(connect_pads
			(clearance 0)
		)
		(min_thickness 0.25)
		(keepout
			(tracks not_allowed)
			(vias allowed)
			(pads allowed)
			(copperpour not_allowed)
			(footprints allowed)
		)
		(placement
			(enabled no)
			(sheetname "")
		)
		(fill yes
			(thermal_gap 0.5)
			(thermal_bridge_width 0.5)
			(island_removal_mode 0)
		)
		(polygon
			(pts
				(arc
					(start 96.949768 -9.757918)
					(mid 95.171768 -9.757918)
					(end 96.949768 -9.757918)
				)
			)
		)
	)
	(zone
		(layers "In4.Cu" "In5.Cu")
		(hatch none 0.5)
		(connect_pads
			(clearance 0)
		)
		(min_thickness 0.25)
		(keepout
			(tracks not_allowed)
			(vias allowed)
			(pads allowed)
			(copperpour not_allowed)
			(footprints allowed)
		)
		(placement
			(enabled no)
			(sheetname "")
		)
		(fill yes
			(thermal_gap 0.5)
			(thermal_bridge_width 0.5)
			(island_removal_mode 0)
		)
		(polygon
			(pts
				(arc
					(start 419.964108 -29.0703)
					(mid 418.236908 -29.0703)
					(end 419.964108 -29.0703)
				)
			)
		)
	)
	(zone
		(layers "In4.Cu" "In5.Cu")
		(hatch none 0.5)
		(connect_pads
			(clearance 0)
		)
		(min_thickness 0.25)
		(keepout
			(tracks not_allowed)
			(vias allowed)
			(pads allowed)
			(copperpour not_allowed)
			(footprints allowed)
		)
		(placement
			(enabled no)
			(sheetname "")
		)
		(fill yes
			(thermal_gap 0.5)
			(thermal_bridge_width 0.5)
			(island_removal_mode 0)
		)
		(polygon
			(pts
				(arc
					(start 423.037 -26.924)
					(mid 421.259 -26.924)
					(end 423.037 -26.924)
				)
			)
		)
	)
	(zone
		(layers "In4.Cu" "In5.Cu")
		(hatch none 0.5)
		(connect_pads
			(clearance 0)
		)
		(min_thickness 0.25)
		(keepout
			(tracks not_allowed)
			(vias allowed)
			(pads allowed)
			(copperpour not_allowed)
			(footprints allowed)
		)
		(placement
			(enabled no)
			(sheetname "")
		)
		(fill yes
			(thermal_gap 0.5)
			(thermal_bridge_width 0.5)
			(island_removal_mode 0)
		)
		(polygon
			(pts
				(arc
					(start 450.61505 -34.798)
					(mid 448.83705 -34.798)
					(end 450.61505 -34.798)
				)
			)
		)
	)
	(zone
		(layers "In4.Cu" "In5.Cu")
		(hatch none 0.5)
		(connect_pads
			(clearance 0)
		)
		(min_thickness 0.25)
		(keepout
			(tracks not_allowed)
			(vias allowed)
			(pads allowed)
			(copperpour not_allowed)
			(footprints allowed)
		)
		(placement
			(enabled no)
			(sheetname "")
		)
		(fill yes
			(thermal_gap 0.5)
			(thermal_bridge_width 0.5)
			(island_removal_mode 0)
		)
		(polygon
			(pts
				(arc
					(start 70.21322 -168.82999)
					(mid 67.787012 -168.82999)
					(end 70.21322 -168.82999)
				)
			)
		)
	)
	(zone
		(layers "In4.Cu" "In5.Cu")
		(hatch none 0.5)
		(connect_pads
			(clearance 0)
		)
		(min_thickness 0.25)
		(keepout
			(tracks not_allowed)
			(vias allowed)
			(pads allowed)
			(copperpour not_allowed)
			(footprints allowed)
		)
		(placement
			(enabled no)
			(sheetname "")
		)
		(fill yes
			(thermal_gap 0.5)
			(thermal_bridge_width 0.5)
			(island_removal_mode 0)
		)
		(polygon
			(pts
				(arc
					(start 63.44539 -111.879888)
					(mid 60.39739 -111.879888)
					(end 63.44539 -111.879888)
				)
			)
		)
	)
	(zone
		(layers "In4.Cu" "In5.Cu")
		(hatch none 0.5)
		(connect_pads
			(clearance 0)
		)
		(min_thickness 0.25)
		(keepout
			(tracks not_allowed)
			(vias allowed)
			(pads allowed)
			(copperpour not_allowed)
			(footprints allowed)
		)
		(placement
			(enabled no)
			(sheetname "")
		)
		(fill yes
			(thermal_gap 0.5)
			(thermal_bridge_width 0.5)
			(island_removal_mode 0)
		)
		(polygon
			(pts
				(arc
					(start 379.603 -71.239888)
					(mid 376.555 -71.239888)
					(end 379.603 -71.239888)
				)
			)
		)
	)
	(zone
		(layers "In4.Cu" "In5.Cu")
		(hatch none 0.5)
		(connect_pads
			(clearance 0)
		)
		(min_thickness 0.25)
		(keepout
			(tracks not_allowed)
			(vias allowed)
			(pads allowed)
			(copperpour not_allowed)
			(footprints allowed)
		)
		(placement
			(enabled no)
			(sheetname "")
		)
		(fill yes
			(thermal_gap 0.5)
			(thermal_bridge_width 0.5)
			(island_removal_mode 0)
		)
		(polygon
			(pts
				(arc
					(start 422.5925 -28.92044)
					(mid 420.8145 -28.92044)
					(end 422.5925 -28.92044)
				)
			)
		)
	)
	(zone
		(layers "In4.Cu" "In5.Cu")
		(hatch none 0.5)
		(connect_pads
			(clearance 0)
		)
		(min_thickness 0.25)
		(keepout
			(tracks not_allowed)
			(vias allowed)
			(pads allowed)
			(copperpour not_allowed)
			(footprints allowed)
		)
		(placement
			(enabled no)
			(sheetname "")
		)
		(fill yes
			(thermal_gap 0.5)
			(thermal_bridge_width 0.5)
			(island_removal_mode 0)
		)
		(polygon
			(pts
				(arc
					(start 373.373142 -4.575048)
					(mid 370.946934 -4.575048)
					(end 373.373142 -4.575048)
				)
			)
		)
	)
	(zone
		(layers "In4.Cu" "In5.Cu")
		(hatch none 0.5)
		(connect_pads
			(clearance 0)
		)
		(min_thickness 0.25)
		(keepout
			(tracks not_allowed)
			(vias allowed)
			(pads allowed)
			(copperpour not_allowed)
			(footprints allowed)
		)
		(placement
			(enabled no)
			(sheetname "")
		)
		(fill yes
			(thermal_gap 0.5)
			(thermal_bridge_width 0.5)
			(island_removal_mode 0)
		)
		(polygon
			(pts
				(arc
					(start 392.412982 -164.829998)
					(mid 389.986774 -164.829998)
					(end 392.412982 -164.829998)
				)
			)
		)
	)
	(zone
		(layers "In4.Cu" "In5.Cu")
		(hatch none 0.5)
		(connect_pads
			(clearance 0)
		)
		(min_thickness 0.25)
		(keepout
			(tracks not_allowed)
			(vias allowed)
			(pads allowed)
			(copperpour not_allowed)
			(footprints allowed)
		)
		(placement
			(enabled no)
			(sheetname "")
		)
		(fill yes
			(thermal_gap 0.5)
			(thermal_bridge_width 0.5)
			(island_removal_mode 0)
		)
		(polygon
			(pts
				(arc
					(start 409.6004 -21.717)
					(mid 407.8224 -21.717)
					(end 409.6004 -21.717)
				)
			)
		)
	)
	(zone
		(layers "In4.Cu" "In5.Cu")
		(hatch none 0.5)
		(connect_pads
			(clearance 0)
		)
		(min_thickness 0.25)
		(keepout
			(tracks not_allowed)
			(vias allowed)
			(pads allowed)
			(copperpour not_allowed)
			(footprints allowed)
		)
		(placement
			(enabled no)
			(sheetname "")
		)
		(fill yes
			(thermal_gap 0.5)
			(thermal_bridge_width 0.5)
			(island_removal_mode 0)
		)
		(polygon
			(pts
				(arc
					(start 104.5464 -57.023)
					(mid 102.7684 -57.023)
					(end 104.5464 -57.023)
				)
			)
		)
	)
	(zone
		(layers "In4.Cu" "In5.Cu")
		(hatch none 0.5)
		(connect_pads
			(clearance 0)
		)
		(min_thickness 0.25)
		(keepout
			(tracks not_allowed)
			(vias allowed)
			(pads allowed)
			(copperpour not_allowed)
			(footprints allowed)
		)
		(placement
			(enabled no)
			(sheetname "")
		)
		(fill yes
			(thermal_gap 0.5)
			(thermal_bridge_width 0.5)
			(island_removal_mode 0)
		)
		(polygon
			(pts
				(arc
					(start 378.213112 -164.829998)
					(mid 375.786904 -164.829998)
					(end 378.213112 -164.829998)
				)
			)
		)
	)
	(zone
		(layers "In4.Cu" "In5.Cu")
		(hatch none 0.5)
		(connect_pads
			(clearance 0)
		)
		(min_thickness 0.25)
		(keepout
			(tracks not_allowed)
			(vias allowed)
			(pads allowed)
			(copperpour not_allowed)
			(footprints allowed)
		)
		(placement
			(enabled no)
			(sheetname "")
		)
		(fill yes
			(thermal_gap 0.5)
			(thermal_bridge_width 0.5)
			(island_removal_mode 0)
		)
		(polygon
			(pts
				(arc
					(start 422.529 -49.149)
					(mid 420.751 -49.149)
					(end 422.529 -49.149)
				)
			)
		)
	)
	(zone
		(layers "In4.Cu" "In5.Cu")
		(hatch none 0.5)
		(connect_pads
			(clearance 0)
		)
		(min_thickness 0.25)
		(keepout
			(tracks not_allowed)
			(vias allowed)
			(pads allowed)
			(copperpour not_allowed)
			(footprints allowed)
		)
		(placement
			(enabled no)
			(sheetname "")
		)
		(fill yes
			(thermal_gap 0.5)
			(thermal_bridge_width 0.5)
			(island_removal_mode 0)
		)
		(polygon
			(pts
				(arc
					(start 72.243188 -5.845048)
					(mid 69.81698 -5.845048)
					(end 72.243188 -5.845048)
				)
			)
		)
	)
	(zone
		(layers "In4.Cu" "In5.Cu")
		(hatch none 0.5)
		(connect_pads
			(clearance 0)
		)
		(min_thickness 0.25)
		(keepout
			(tracks not_allowed)
			(vias allowed)
			(pads allowed)
			(copperpour not_allowed)
			(footprints allowed)
		)
		(placement
			(enabled no)
			(sheetname "")
		)
		(fill yes
			(thermal_gap 0.5)
			(thermal_bridge_width 0.5)
			(island_removal_mode 0)
		)
		(polygon
			(pts
				(arc
					(start 436.12435 -32.893)
					(mid 434.34635 -32.893)
					(end 436.12435 -32.893)
				)
			)
		)
	)
	(zone
		(layers "In4.Cu" "In5.Cu")
		(hatch none 0.5)
		(connect_pads
			(clearance 0)
		)
		(min_thickness 0.25)
		(keepout
			(tracks not_allowed)
			(vias allowed)
			(pads allowed)
			(copperpour not_allowed)
			(footprints allowed)
		)
		(placement
			(enabled no)
			(sheetname "")
		)
		(fill yes
			(thermal_gap 0.5)
			(thermal_bridge_width 0.5)
			(island_removal_mode 0)
		)
		(polygon
			(pts
				(arc
					(start 72.213216 -164.829998)
					(mid 69.787008 -164.829998)
					(end 72.213216 -164.829998)
				)
			)
		)
	)
	(zone
		(layers "In4.Cu" "In5.Cu")
		(hatch none 0.5)
		(connect_pads
			(clearance 0)
		)
		(min_thickness 0.25)
		(keepout
			(tracks not_allowed)
			(vias allowed)
			(pads allowed)
			(copperpour not_allowed)
			(footprints allowed)
		)
		(placement
			(enabled no)
			(sheetname "")
		)
		(fill yes
			(thermal_gap 0.5)
			(thermal_bridge_width 0.5)
			(island_removal_mode 0)
		)
		(polygon
			(pts
				(arc
					(start 61.170566 -25.273762)
					(mid 59.392566 -25.273762)
					(end 61.170566 -25.273762)
				)
			)
		)
	)
	(zone
		(layers "In4.Cu" "In5.Cu")
		(hatch none 0.5)
		(connect_pads
			(clearance 0)
		)
		(min_thickness 0.25)
		(keepout
			(tracks not_allowed)
			(vias allowed)
			(pads allowed)
			(copperpour not_allowed)
			(footprints allowed)
		)
		(placement
			(enabled no)
			(sheetname "")
		)
		(fill yes
			(thermal_gap 0.5)
			(thermal_bridge_width 0.5)
			(island_removal_mode 0)
		)
		(polygon
			(pts
				(arc
					(start 335.245964 -9.774428)
					(mid 333.467964 -9.774428)
					(end 335.245964 -9.774428)
				)
			)
		)
	)
	(zone
		(layers "In4.Cu" "In5.Cu")
		(hatch none 0.5)
		(connect_pads
			(clearance 0)
		)
		(min_thickness 0.25)
		(keepout
			(tracks not_allowed)
			(vias allowed)
			(pads allowed)
			(copperpour not_allowed)
			(footprints allowed)
		)
		(placement
			(enabled no)
			(sheetname "")
		)
		(fill yes
			(thermal_gap 0.5)
			(thermal_bridge_width 0.5)
			(island_removal_mode 0)
		)
		(polygon
			(pts
				(arc
					(start 42.838116 -162.830002)
					(mid 40.411908 -162.830002)
					(end 42.838116 -162.830002)
				)
			)
		)
	)
	(zone
		(layers "In4.Cu" "In5.Cu")
		(hatch none 0.5)
		(connect_pads
			(clearance 0)
		)
		(min_thickness 0.25)
		(keepout
			(tracks not_allowed)
			(vias allowed)
			(pads allowed)
			(copperpour not_allowed)
			(footprints allowed)
		)
		(placement
			(enabled no)
			(sheetname "")
		)
		(fill yes
			(thermal_gap 0.5)
			(thermal_bridge_width 0.5)
			(island_removal_mode 0)
		)
		(polygon
			(pts
				(arc
					(start 431.546 -19.431)
					(mid 429.768 -19.431)
					(end 431.546 -19.431)
				)
			)
		)
	)
	(zone
		(layers "In4.Cu" "In5.Cu")
		(hatch none 0.5)
		(connect_pads
			(clearance 0)
		)
		(min_thickness 0.25)
		(keepout
			(tracks not_allowed)
			(vias allowed)
			(pads allowed)
			(copperpour not_allowed)
			(footprints allowed)
		)
		(placement
			(enabled no)
			(sheetname "")
		)
		(fill yes
			(thermal_gap 0.5)
			(thermal_bridge_width 0.5)
			(island_removal_mode 0)
		)
		(polygon
			(pts
				(arc
					(start 431.8254 -30.226)
					(mid 430.0474 -30.226)
					(end 431.8254 -30.226)
				)
			)
		)
	)
	(zone
		(layers "In4.Cu" "In5.Cu")
		(hatch none 0.5)
		(connect_pads
			(clearance 0)
		)
		(min_thickness 0.25)
		(keepout
			(tracks not_allowed)
			(vias allowed)
			(pads allowed)
			(copperpour not_allowed)
			(footprints allowed)
		)
		(placement
			(enabled no)
			(sheetname "")
		)
		(fill yes
			(thermal_gap 0.5)
			(thermal_bridge_width 0.5)
			(island_removal_mode 0)
		)
		(polygon
			(pts
				(arc
					(start 72.213216 -166.829994)
					(mid 69.787008 -166.829994)
					(end 72.213216 -166.829994)
				)
			)
		)
	)
	(zone
		(layers "In4.Cu" "In5.Cu")
		(hatch none 0.5)
		(connect_pads
			(clearance 0)
		)
		(min_thickness 0.25)
		(keepout
			(tracks not_allowed)
			(vias allowed)
			(pads allowed)
			(copperpour not_allowed)
			(footprints allowed)
		)
		(placement
			(enabled no)
			(sheetname "")
		)
		(fill yes
			(thermal_gap 0.5)
			(thermal_bridge_width 0.5)
			(island_removal_mode 0)
		)
		(polygon
			(pts
				(arc
					(start 409.6004 -16.764)
					(mid 407.8224 -16.764)
					(end 409.6004 -16.764)
				)
			)
		)
	)
	(zone
		(layers "In4.Cu" "In5.Cu")
		(hatch none 0.5)
		(connect_pads
			(clearance 0)
		)
		(min_thickness 0.25)
		(keepout
			(tracks not_allowed)
			(vias allowed)
			(pads allowed)
			(copperpour not_allowed)
			(footprints allowed)
		)
		(placement
			(enabled no)
			(sheetname "")
		)
		(fill yes
			(thermal_gap 0.5)
			(thermal_bridge_width 0.5)
			(island_removal_mode 0)
		)
		(polygon
			(pts
				(arc
					(start 421.7797 -26.00452)
					(mid 420.0017 -26.00452)
					(end 421.7797 -26.00452)
				)
			)
		)
	)
	(zone
		(layers "In4.Cu" "In5.Cu")
		(hatch none 0.5)
		(connect_pads
			(clearance 0)
		)
		(min_thickness 0.25)
		(keepout
			(tracks not_allowed)
			(vias allowed)
			(pads allowed)
			(copperpour not_allowed)
			(footprints allowed)
		)
		(placement
			(enabled no)
			(sheetname "")
		)
		(fill yes
			(thermal_gap 0.5)
			(thermal_bridge_width 0.5)
			(island_removal_mode 0)
		)
		(polygon
			(pts
				(arc
					(start 366.213136 -168.82999)
					(mid 363.786928 -168.82999)
					(end 366.213136 -168.82999)
				)
			)
		)
	)
	(zone
		(layers "In4.Cu" "In5.Cu")
		(hatch none 0.5)
		(connect_pads
			(clearance 0)
		)
		(min_thickness 0.25)
		(keepout
			(tracks not_allowed)
			(vias allowed)
			(pads allowed)
			(copperpour not_allowed)
			(footprints allowed)
		)
		(placement
			(enabled no)
			(sheetname "")
		)
		(fill yes
			(thermal_gap 0.5)
			(thermal_bridge_width 0.5)
			(island_removal_mode 0)
		)
		(polygon
			(pts
				(arc
					(start 95.425768 -9.757918)
					(mid 93.647768 -9.757918)
					(end 95.425768 -9.757918)
				)
			)
		)
	)
	(zone
		(layers "In4.Cu" "In5.Cu")
		(hatch none 0.5)
		(connect_pads
			(clearance 0)
		)
		(min_thickness 0.25)
		(keepout
			(tracks not_allowed)
			(vias allowed)
			(pads allowed)
			(copperpour not_allowed)
			(footprints allowed)
		)
		(placement
			(enabled no)
			(sheetname "")
		)
		(fill yes
			(thermal_gap 0.5)
			(thermal_bridge_width 0.5)
			(island_removal_mode 0)
		)
		(polygon
			(pts
				(arc
					(start 409.6004 -15.875)
					(mid 407.8224 -15.875)
					(end 409.6004 -15.875)
				)
			)
		)
	)
	(zone
		(layers "In4.Cu" "In5.Cu")
		(hatch none 0.5)
		(connect_pads
			(clearance 0)
		)
		(min_thickness 0.25)
		(keepout
			(tracks not_allowed)
			(vias allowed)
			(pads allowed)
			(copperpour not_allowed)
			(footprints allowed)
		)
		(placement
			(enabled no)
			(sheetname "")
		)
		(fill yes
			(thermal_gap 0.5)
			(thermal_bridge_width 0.5)
			(island_removal_mode 0)
		)
		(polygon
			(pts
				(arc
					(start 70.973188 -2.035048)
					(mid 68.54698 -2.035048)
					(end 70.973188 -2.035048)
				)
			)
		)
	)
	(zone
		(layers "In4.Cu" "In5.Cu")
		(hatch none 0.5)
		(connect_pads
			(clearance 0)
		)
		(min_thickness 0.25)
		(keepout
			(tracks not_allowed)
			(vias allowed)
			(pads allowed)
			(copperpour not_allowed)
			(footprints allowed)
		)
		(placement
			(enabled no)
			(sheetname "")
		)
		(fill yes
			(thermal_gap 0.5)
			(thermal_bridge_width 0.5)
			(island_removal_mode 0)
		)
		(polygon
			(pts
				(arc
					(start 62.937644 -58.42)
					(mid 60.905136 -58.42)
					(end 62.937644 -58.42)
				)
			)
		)
	)
	(zone
		(layers "In4.Cu" "In5.Cu")
		(hatch none 0.5)
		(connect_pads
			(clearance 0)
		)
		(min_thickness 0.25)
		(keepout
			(tracks not_allowed)
			(vias allowed)
			(pads allowed)
			(copperpour not_allowed)
			(footprints allowed)
		)
		(placement
			(enabled no)
			(sheetname "")
		)
		(fill yes
			(thermal_gap 0.5)
			(thermal_bridge_width 0.5)
			(island_removal_mode 0)
		)
		(polygon
			(pts
				(arc
					(start 50.013108 -166.829994)
					(mid 47.5869 -166.829994)
					(end 50.013108 -166.829994)
				)
			)
		)
	)
	(zone
		(layers "In4.Cu" "In5.Cu")
		(hatch none 0.5)
		(connect_pads
			(clearance 0)
		)
		(min_thickness 0.25)
		(keepout
			(tracks not_allowed)
			(vias allowed)
			(pads allowed)
			(copperpour not_allowed)
			(footprints allowed)
		)
		(placement
			(enabled no)
			(sheetname "")
		)
		(fill yes
			(thermal_gap 0.5)
			(thermal_bridge_width 0.5)
			(island_removal_mode 0)
		)
		(polygon
			(pts
				(arc
					(start 384.412998 -164.829998)
					(mid 381.98679 -164.829998)
					(end 384.412998 -164.829998)
				)
			)
		)
	)
	(zone
		(layers "In4.Cu" "In5.Cu")
		(hatch none 0.5)
		(connect_pads
			(clearance 0)
		)
		(min_thickness 0.25)
		(keepout
			(tracks not_allowed)
			(vias allowed)
			(pads allowed)
			(copperpour not_allowed)
			(footprints allowed)
		)
		(placement
			(enabled no)
			(sheetname "")
		)
		(fill yes
			(thermal_gap 0.5)
			(thermal_bridge_width 0.5)
			(island_removal_mode 0)
		)
		(polygon
			(pts
				(arc
					(start 433.3494 -43.561)
					(mid 431.5714 -43.561)
					(end 433.3494 -43.561)
				)
			)
		)
	)
	(zone
		(layers "In4.Cu" "In5.Cu")
		(hatch none 0.5)
		(connect_pads
			(clearance 0)
		)
		(min_thickness 0.25)
		(keepout
			(tracks not_allowed)
			(vias allowed)
			(pads allowed)
			(copperpour not_allowed)
			(footprints allowed)
		)
		(placement
			(enabled no)
			(sheetname "")
		)
		(fill yes
			(thermal_gap 0.5)
			(thermal_bridge_width 0.5)
			(island_removal_mode 0)
		)
		(polygon
			(pts
				(arc
					(start 379.406912 -16.891)
					(mid 377.628912 -16.891)
					(end 379.406912 -16.891)
				)
			)
		)
	)
	(zone
		(layers "In4.Cu" "In5.Cu")
		(hatch none 0.5)
		(connect_pads
			(clearance 0)
		)
		(min_thickness 0.25)
		(keepout
			(tracks not_allowed)
			(vias allowed)
			(pads allowed)
			(copperpour not_allowed)
			(footprints allowed)
		)
		(placement
			(enabled no)
			(sheetname "")
		)
		(fill yes
			(thermal_gap 0.5)
			(thermal_bridge_width 0.5)
			(island_removal_mode 0)
		)
		(polygon
			(pts
				(arc
					(start 443.0014 -64.262)
					(mid 441.2234 -64.262)
					(end 443.0014 -64.262)
				)
			)
		)
	)
	(zone
		(layers "In4.Cu" "In5.Cu")
		(hatch none 0.5)
		(connect_pads
			(clearance 0)
		)
		(min_thickness 0.25)
		(keepout
			(tracks not_allowed)
			(vias allowed)
			(pads allowed)
			(copperpour not_allowed)
			(footprints allowed)
		)
		(placement
			(enabled no)
			(sheetname "")
		)
		(fill yes
			(thermal_gap 0.5)
			(thermal_bridge_width 0.5)
			(island_removal_mode 0)
		)
		(polygon
			(pts
				(arc
					(start 437.43245 -22.352)
					(mid 435.65445 -22.352)
					(end 437.43245 -22.352)
				)
			)
		)
	)
	(zone
		(layers "In4.Cu" "In5.Cu")
		(hatch none 0.5)
		(connect_pads
			(clearance 0)
		)
		(min_thickness 0.25)
		(keepout
			(tracks not_allowed)
			(vias allowed)
			(pads allowed)
			(copperpour not_allowed)
			(footprints allowed)
		)
		(placement
			(enabled no)
			(sheetname "")
		)
		(fill yes
			(thermal_gap 0.5)
			(thermal_bridge_width 0.5)
			(island_removal_mode 0)
		)
		(polygon
			(pts
				(arc
					(start 35.0774 -34.036)
					(mid 33.2994 -34.036)
					(end 35.0774 -34.036)
				)
			)
		)
	)
	(zone
		(layers "In4.Cu" "In5.Cu")
		(hatch none 0.5)
		(connect_pads
			(clearance 0)
		)
		(min_thickness 0.25)
		(keepout
			(tracks not_allowed)
			(vias allowed)
			(pads allowed)
			(copperpour not_allowed)
			(footprints allowed)
		)
		(placement
			(enabled no)
			(sheetname "")
		)
		(fill yes
			(thermal_gap 0.5)
			(thermal_bridge_width 0.5)
			(island_removal_mode 0)
		)
		(polygon
			(pts
				(arc
					(start 42.838116 -166.829994)
					(mid 40.411908 -166.829994)
					(end 42.838116 -166.829994)
				)
			)
		)
	)
	(zone
		(layers "In4.Cu" "In5.Cu")
		(hatch none 0.5)
		(connect_pads
			(clearance 0)
		)
		(min_thickness 0.25)
		(keepout
			(tracks not_allowed)
			(vias allowed)
			(pads allowed)
			(copperpour not_allowed)
			(footprints allowed)
		)
		(placement
			(enabled no)
			(sheetname "")
		)
		(fill yes
			(thermal_gap 0.5)
			(thermal_bridge_width 0.5)
			(island_removal_mode 0)
		)
		(polygon
			(pts
				(arc
					(start 426.6819 -40.703754)
					(mid 424.9039 -40.703754)
					(end 426.6819 -40.703754)
				)
			)
		)
	)
	(zone
		(layers "In4.Cu" "In5.Cu")
		(hatch none 0.5)
		(connect_pads
			(clearance 0)
		)
		(min_thickness 0.25)
		(keepout
			(tracks not_allowed)
			(vias allowed)
			(pads allowed)
			(copperpour not_allowed)
			(footprints allowed)
		)
		(placement
			(enabled no)
			(sheetname "")
		)
		(fill yes
			(thermal_gap 0.5)
			(thermal_bridge_width 0.5)
			(island_removal_mode 0)
		)
		(polygon
			(pts
				(arc
					(start 432.9684 -46.228)
					(mid 431.1904 -46.228)
					(end 432.9684 -46.228)
				)
			)
		)
	)
	(zone
		(layers "In4.Cu" "In5.Cu")
		(hatch none 0.5)
		(connect_pads
			(clearance 0)
		)
		(min_thickness 0.25)
		(keepout
			(tracks not_allowed)
			(vias allowed)
			(pads allowed)
			(copperpour not_allowed)
			(footprints allowed)
		)
		(placement
			(enabled no)
			(sheetname "")
		)
		(fill yes
			(thermal_gap 0.5)
			(thermal_bridge_width 0.5)
			(island_removal_mode 0)
		)
		(polygon
			(pts
				(arc
					(start 73.513188 -4.575048)
					(mid 71.08698 -4.575048)
					(end 73.513188 -4.575048)
				)
			)
		)
	)
	(zone
		(layers "In4.Cu" "In5.Cu")
		(hatch none 0.5)
		(connect_pads
			(clearance 0)
		)
		(min_thickness 0.25)
		(keepout
			(tracks not_allowed)
			(vias allowed)
			(pads allowed)
			(copperpour not_allowed)
			(footprints allowed)
		)
		(placement
			(enabled no)
			(sheetname "")
		)
		(fill yes
			(thermal_gap 0.5)
			(thermal_bridge_width 0.5)
			(island_removal_mode 0)
		)
		(polygon
			(pts
				(arc
					(start 419.063932 -29.0703)
					(mid 417.336732 -29.0703)
					(end 419.063932 -29.0703)
				)
			)
		)
	)
	(zone
		(layers "In4.Cu" "In5.Cu")
		(hatch none 0.5)
		(connect_pads
			(clearance 0)
		)
		(min_thickness 0.25)
		(keepout
			(tracks not_allowed)
			(vias allowed)
			(pads allowed)
			(copperpour not_allowed)
			(footprints allowed)
		)
		(placement
			(enabled no)
			(sheetname "")
		)
		(fill yes
			(thermal_gap 0.5)
			(thermal_bridge_width 0.5)
			(island_removal_mode 0)
		)
		(polygon
			(pts
				(arc
					(start 439.318146 -38.862)
					(mid 437.540146 -38.862)
					(end 439.318146 -38.862)
				)
			)
		)
	)
	(zone
		(layers "In4.Cu" "In5.Cu")
		(hatch none 0.5)
		(connect_pads
			(clearance 0)
		)
		(min_thickness 0.25)
		(keepout
			(tracks not_allowed)
			(vias allowed)
			(pads allowed)
			(copperpour not_allowed)
			(footprints allowed)
		)
		(placement
			(enabled no)
			(sheetname "")
		)
		(fill yes
			(thermal_gap 0.5)
			(thermal_bridge_width 0.5)
			(island_removal_mode 0)
		)
		(polygon
			(pts
				(arc
					(start 436.124096 -30.353)
					(mid 434.346096 -30.353)
					(end 436.124096 -30.353)
				)
			)
		)
	)
	(zone
		(layers "In4.Cu" "In5.Cu")
		(hatch none 0.5)
		(connect_pads
			(clearance 0)
		)
		(min_thickness 0.25)
		(keepout
			(tracks not_allowed)
			(vias allowed)
			(pads allowed)
			(copperpour not_allowed)
			(footprints allowed)
		)
		(placement
			(enabled no)
			(sheetname "")
		)
		(fill yes
			(thermal_gap 0.5)
			(thermal_bridge_width 0.5)
			(island_removal_mode 0)
		)
		(polygon
			(pts
				(arc
					(start 419.4302 -19.6088)
					(mid 417.6522 -19.6088)
					(end 419.4302 -19.6088)
				)
			)
		)
	)
	(zone
		(layers "In4.Cu" "In5.Cu")
		(hatch none 0.5)
		(connect_pads
			(clearance 0)
		)
		(min_thickness 0.25)
		(keepout
			(tracks not_allowed)
			(vias allowed)
			(pads allowed)
			(copperpour not_allowed)
			(footprints allowed)
		)
		(placement
			(enabled no)
			(sheetname "")
		)
		(fill yes
			(thermal_gap 0.5)
			(thermal_bridge_width 0.5)
			(island_removal_mode 0)
		)
		(polygon
			(pts
				(arc
					(start 372.213124 -166.829994)
					(mid 369.786916 -166.829994)
					(end 372.213124 -166.829994)
				)
			)
		)
	)
	(zone
		(layers "In4.Cu" "In5.Cu")
		(hatch none 0.5)
		(connect_pads
			(clearance 0)
		)
		(min_thickness 0.25)
		(keepout
			(tracks not_allowed)
			(vias allowed)
			(pads allowed)
			(copperpour not_allowed)
			(footprints allowed)
		)
		(placement
			(enabled no)
			(sheetname "")
		)
		(fill yes
			(thermal_gap 0.5)
			(thermal_bridge_width 0.5)
			(island_removal_mode 0)
		)
		(polygon
			(pts
				(arc
					(start 412.95193 -30.21076)
					(mid 411.17393 -30.21076)
					(end 412.95193 -30.21076)
				)
			)
		)
	)
	(zone
		(layers "In4.Cu" "In5.Cu")
		(hatch none 0.5)
		(connect_pads
			(clearance 0)
		)
		(min_thickness 0.25)
		(keepout
			(tracks not_allowed)
			(vias allowed)
			(pads allowed)
			(copperpour not_allowed)
			(footprints allowed)
		)
		(placement
			(enabled no)
			(sheetname "")
		)
		(fill yes
			(thermal_gap 0.5)
			(thermal_bridge_width 0.5)
			(island_removal_mode 0)
		)
		(polygon
			(pts
				(arc
					(start 462.534 -47.752)
					(mid 460.756 -47.752)
					(end 462.534 -47.752)
				)
			)
		)
	)
	(zone
		(layers "In4.Cu" "In5.Cu")
		(hatch none 0.5)
		(connect_pads
			(clearance 0)
		)
		(min_thickness 0.25)
		(keepout
			(tracks not_allowed)
			(vias allowed)
			(pads allowed)
			(copperpour not_allowed)
			(footprints allowed)
		)
		(placement
			(enabled no)
			(sheetname "")
		)
		(fill yes
			(thermal_gap 0.5)
			(thermal_bridge_width 0.5)
			(island_removal_mode 0)
		)
		(polygon
			(pts
				(arc
					(start 448.71005 -45.4406)
					(mid 446.93205 -45.4406)
					(end 448.71005 -45.4406)
				)
			)
		)
	)
	(zone
		(layers "In4.Cu" "In5.Cu")
		(hatch none 0.5)
		(connect_pads
			(clearance 0)
		)
		(min_thickness 0.25)
		(keepout
			(tracks not_allowed)
			(vias allowed)
			(pads allowed)
			(copperpour not_allowed)
			(footprints allowed)
		)
		(placement
			(enabled no)
			(sheetname "")
		)
		(fill yes
			(thermal_gap 0.5)
			(thermal_bridge_width 0.5)
			(island_removal_mode 0)
		)
		(polygon
			(pts
				(arc
					(start 451.852538 -60.908692)
					(mid 450.074538 -60.908692)
					(end 451.852538 -60.908692)
				)
			)
		)
	)
	(zone
		(layers "In4.Cu" "In5.Cu")
		(hatch none 0.5)
		(connect_pads
			(clearance 0)
		)
		(min_thickness 0.25)
		(keepout
			(tracks not_allowed)
			(vias allowed)
			(pads allowed)
			(copperpour not_allowed)
			(footprints allowed)
		)
		(placement
			(enabled no)
			(sheetname "")
		)
		(fill yes
			(thermal_gap 0.5)
			(thermal_bridge_width 0.5)
			(island_removal_mode 0)
		)
		(polygon
			(pts
				(arc
					(start 62.937644 -99.06)
					(mid 60.905136 -99.06)
					(end 62.937644 -99.06)
				)
			)
		)
	)
	(zone
		(layers "In4.Cu" "In5.Cu")
		(hatch none 0.5)
		(connect_pads
			(clearance 0)
		)
		(min_thickness 0.25)
		(keepout
			(tracks not_allowed)
			(vias allowed)
			(pads allowed)
			(copperpour not_allowed)
			(footprints allowed)
		)
		(placement
			(enabled no)
			(sheetname "")
		)
		(fill yes
			(thermal_gap 0.5)
			(thermal_bridge_width 0.5)
			(island_removal_mode 0)
		)
		(polygon
			(pts
				(arc
					(start 388.7724 -27.559)
					(mid 386.9944 -27.559)
					(end 388.7724 -27.559)
				)
			)
		)
	)
	(zone
		(layers "In4.Cu" "In5.Cu")
		(hatch none 0.5)
		(connect_pads
			(clearance 0)
		)
		(min_thickness 0.25)
		(keepout
			(tracks not_allowed)
			(vias allowed)
			(pads allowed)
			(copperpour not_allowed)
			(footprints allowed)
		)
		(placement
			(enabled no)
			(sheetname "")
		)
		(fill yes
			(thermal_gap 0.5)
			(thermal_bridge_width 0.5)
			(island_removal_mode 0)
		)
		(polygon
			(pts
				(arc
					(start 43.88739 -71.239888)
					(mid 40.83939 -71.239888)
					(end 43.88739 -71.239888)
				)
			)
		)
	)
	(zone
		(layers "In4.Cu" "In5.Cu")
		(hatch none 0.5)
		(connect_pads
			(clearance 0)
		)
		(min_thickness 0.25)
		(keepout
			(tracks not_allowed)
			(vias allowed)
			(pads allowed)
			(copperpour not_allowed)
			(footprints allowed)
		)
		(placement
			(enabled no)
			(sheetname "")
		)
		(fill yes
			(thermal_gap 0.5)
			(thermal_bridge_width 0.5)
			(island_removal_mode 0)
		)
		(polygon
			(pts
				(arc
					(start 418.16401 -28.4353)
					(mid 416.43681 -28.4353)
					(end 418.16401 -28.4353)
				)
			)
		)
	)
	(zone
		(layers "In4.Cu" "In5.Cu")
		(hatch none 0.5)
		(connect_pads
			(clearance 0)
		)
		(min_thickness 0.25)
		(keepout
			(tracks not_allowed)
			(vias allowed)
			(pads allowed)
			(copperpour not_allowed)
			(footprints allowed)
		)
		(placement
			(enabled no)
			(sheetname "")
		)
		(fill yes
			(thermal_gap 0.5)
			(thermal_bridge_width 0.5)
			(island_removal_mode 0)
		)
		(polygon
			(pts
				(arc
					(start 398.653254 -78.74)
					(mid 396.620746 -78.74)
					(end 398.653254 -78.74)
				)
			)
		)
	)
	(zone
		(layers "In4.Cu" "In5.Cu")
		(hatch none 0.5)
		(connect_pads
			(clearance 0)
		)
		(min_thickness 0.25)
		(keepout
			(tracks not_allowed)
			(vias allowed)
			(pads allowed)
			(copperpour not_allowed)
			(footprints allowed)
		)
		(placement
			(enabled no)
			(sheetname "")
		)
		(fill yes
			(thermal_gap 0.5)
			(thermal_bridge_width 0.5)
			(island_removal_mode 0)
		)
		(polygon
			(pts
				(arc
					(start 454.007728 -63.590678)
					(mid 452.229728 -63.590678)
					(end 454.007728 -63.590678)
				)
			)
		)
	)
	(zone
		(layers "In4.Cu" "In5.Cu")
		(hatch none 0.5)
		(connect_pads
			(clearance 0)
		)
		(min_thickness 0.25)
		(keepout
			(tracks not_allowed)
			(vias allowed)
			(pads allowed)
			(copperpour not_allowed)
			(footprints allowed)
		)
		(placement
			(enabled no)
			(sheetname "")
		)
		(fill yes
			(thermal_gap 0.5)
			(thermal_bridge_width 0.5)
			(island_removal_mode 0)
		)
		(polygon
			(pts
				(arc
					(start 40.83812 -164.829998)
					(mid 38.411912 -164.829998)
					(end 40.83812 -164.829998)
				)
			)
		)
	)
	(zone
		(layers "In4.Cu" "In5.Cu")
		(hatch none 0.5)
		(connect_pads
			(clearance 0)
		)
		(min_thickness 0.25)
		(keepout
			(tracks not_allowed)
			(vias allowed)
			(pads allowed)
			(copperpour not_allowed)
			(footprints allowed)
		)
		(placement
			(enabled no)
			(sheetname "")
		)
		(fill yes
			(thermal_gap 0.5)
			(thermal_bridge_width 0.5)
			(island_removal_mode 0)
		)
		(polygon
			(pts
				(arc
					(start 398.653254 -139.7)
					(mid 396.620746 -139.7)
					(end 398.653254 -139.7)
				)
			)
		)
	)
	(zone
		(layers "In4.Cu" "In5.Cu")
		(hatch none 0.5)
		(connect_pads
			(clearance 0)
		)
		(min_thickness 0.25)
		(keepout
			(tracks not_allowed)
			(vias allowed)
			(pads allowed)
			(copperpour not_allowed)
			(footprints allowed)
		)
		(placement
			(enabled no)
			(sheetname "")
		)
		(fill yes
			(thermal_gap 0.5)
			(thermal_bridge_width 0.5)
			(island_removal_mode 0)
		)
		(polygon
			(pts
				(arc
					(start 60.186062 -24.32812)
					(mid 58.408062 -24.32812)
					(end 60.186062 -24.32812)
				)
			)
		)
	)
	(zone
		(layers "In4.Cu" "In5.Cu")
		(hatch none 0.5)
		(connect_pads
			(clearance 0)
		)
		(min_thickness 0.25)
		(keepout
			(tracks not_allowed)
			(vias allowed)
			(pads allowed)
			(copperpour not_allowed)
			(footprints allowed)
		)
		(placement
			(enabled no)
			(sheetname "")
		)
		(fill yes
			(thermal_gap 0.5)
			(thermal_bridge_width 0.5)
			(island_removal_mode 0)
		)
		(polygon
			(pts
				(arc
					(start 412.0642 -19.4818)
					(mid 410.2862 -19.4818)
					(end 412.0642 -19.4818)
				)
			)
		)
	)
	(zone
		(layers "In4.Cu" "In5.Cu")
		(hatch none 0.5)
		(connect_pads
			(clearance 0)
		)
		(min_thickness 0.25)
		(keepout
			(tracks not_allowed)
			(vias allowed)
			(pads allowed)
			(copperpour not_allowed)
			(footprints allowed)
		)
		(placement
			(enabled no)
			(sheetname "")
		)
		(fill yes
			(thermal_gap 0.5)
			(thermal_bridge_width 0.5)
			(island_removal_mode 0)
		)
		(polygon
			(pts
				(arc
					(start 66.213228 -164.829998)
					(mid 63.78702 -164.829998)
					(end 66.213228 -164.829998)
				)
			)
		)
	)
	(zone
		(layers "In4.Cu" "In5.Cu")
		(hatch none 0.5)
		(connect_pads
			(clearance 0)
		)
		(min_thickness 0.25)
		(keepout
			(tracks not_allowed)
			(vias allowed)
			(pads allowed)
			(copperpour not_allowed)
			(footprints allowed)
		)
		(placement
			(enabled no)
			(sheetname "")
		)
		(fill yes
			(thermal_gap 0.5)
			(thermal_bridge_width 0.5)
			(island_removal_mode 0)
		)
		(polygon
			(pts
				(arc
					(start 436.12435 -34.163)
					(mid 434.34635 -34.163)
					(end 436.12435 -34.163)
				)
			)
		)
	)
	(zone
		(layers "In4.Cu" "In5.Cu")
		(hatch none 0.5)
		(connect_pads
			(clearance 0)
		)
		(min_thickness 0.25)
		(keepout
			(tracks not_allowed)
			(vias allowed)
			(pads allowed)
			(copperpour not_allowed)
			(footprints allowed)
		)
		(placement
			(enabled no)
			(sheetname "")
		)
		(fill yes
			(thermal_gap 0.5)
			(thermal_bridge_width 0.5)
			(island_removal_mode 0)
		)
		(polygon
			(pts
				(arc
					(start 406.5524 -36.83)
					(mid 404.7744 -36.83)
					(end 406.5524 -36.83)
				)
			)
		)
	)
	(zone
		(layers "In4.Cu" "In5.Cu")
		(hatch none 0.5)
		(connect_pads
			(clearance 0)
		)
		(min_thickness 0.25)
		(keepout
			(tracks not_allowed)
			(vias allowed)
			(pads allowed)
			(copperpour not_allowed)
			(footprints allowed)
		)
		(placement
			(enabled no)
			(sheetname "")
		)
		(fill yes
			(thermal_gap 0.5)
			(thermal_bridge_width 0.5)
			(island_removal_mode 0)
		)
		(polygon
			(pts
				(arc
					(start 386.412994 -168.82999)
					(mid 383.986786 -168.82999)
					(end 386.412994 -168.82999)
				)
			)
		)
	)
	(zone
		(layers "In4.Cu" "In5.Cu")
		(hatch none 0.5)
		(connect_pads
			(clearance 0)
		)
		(min_thickness 0.25)
		(keepout
			(tracks not_allowed)
			(vias allowed)
			(pads allowed)
			(copperpour not_allowed)
			(footprints allowed)
		)
		(placement
			(enabled no)
			(sheetname "")
		)
		(fill yes
			(thermal_gap 0.5)
			(thermal_bridge_width 0.5)
			(island_removal_mode 0)
		)
		(polygon
			(pts
				(arc
					(start 450.335904 -42.799)
					(mid 448.557904 -42.799)
					(end 450.335904 -42.799)
				)
			)
		)
	)
	(zone
		(layers "In4.Cu" "In5.Cu")
		(hatch none 0.5)
		(connect_pads
			(clearance 0)
		)
		(min_thickness 0.25)
		(keepout
			(tracks not_allowed)
			(vias allowed)
			(pads allowed)
			(copperpour not_allowed)
			(footprints allowed)
		)
		(placement
			(enabled no)
			(sheetname "")
		)
		(fill yes
			(thermal_gap 0.5)
			(thermal_bridge_width 0.5)
			(island_removal_mode 0)
		)
		(polygon
			(pts
				(arc
					(start 410.8704 -31.75)
					(mid 409.0924 -31.75)
					(end 410.8704 -31.75)
				)
			)
		)
	)
	(zone
		(layers "In4.Cu" "In5.Cu")
		(hatch none 0.5)
		(connect_pads
			(clearance 0)
		)
		(min_thickness 0.25)
		(keepout
			(tracks not_allowed)
			(vias allowed)
			(pads allowed)
			(copperpour not_allowed)
			(footprints allowed)
		)
		(placement
			(enabled no)
			(sheetname "")
		)
		(fill yes
			(thermal_gap 0.5)
			(thermal_bridge_width 0.5)
			(island_removal_mode 0)
		)
		(polygon
			(pts
				(arc
					(start 375.913142 -4.575048)
					(mid 373.486934 -4.575048)
					(end 375.913142 -4.575048)
				)
			)
		)
	)
	(zone
		(layers "In4.Cu" "In5.Cu")
		(hatch none 0.5)
		(connect_pads
			(clearance 0)
		)
		(min_thickness 0.25)
		(keepout
			(tracks not_allowed)
			(vias allowed)
			(pads allowed)
			(copperpour not_allowed)
			(footprints allowed)
		)
		(placement
			(enabled no)
			(sheetname "")
		)
		(fill yes
			(thermal_gap 0.5)
			(thermal_bridge_width 0.5)
			(island_removal_mode 0)
		)
		(polygon
			(pts
				(arc
					(start 451.852538 -61.670692)
					(mid 450.074538 -61.670692)
					(end 451.852538 -61.670692)
				)
			)
		)
	)
	(zone
		(layers "In4.Cu" "In5.Cu")
		(hatch none 0.5)
		(connect_pads
			(clearance 0)
		)
		(min_thickness 0.25)
		(keepout
			(tracks not_allowed)
			(vias allowed)
			(pads allowed)
			(copperpour not_allowed)
			(footprints allowed)
		)
		(placement
			(enabled no)
			(sheetname "")
		)
		(fill yes
			(thermal_gap 0.5)
			(thermal_bridge_width 0.5)
			(island_removal_mode 0)
		)
		(polygon
			(pts
				(arc
					(start 445.7954 -65.532)
					(mid 444.0174 -65.532)
					(end 445.7954 -65.532)
				)
			)
		)
	)
	(zone
		(layers "In4.Cu" "In5.Cu")
		(hatch none 0.5)
		(connect_pads
			(clearance 0)
		)
		(min_thickness 0.25)
		(keepout
			(tracks not_allowed)
			(vias allowed)
			(pads allowed)
			(copperpour not_allowed)
			(footprints allowed)
		)
		(placement
			(enabled no)
			(sheetname "")
		)
		(fill yes
			(thermal_gap 0.5)
			(thermal_bridge_width 0.5)
			(island_removal_mode 0)
		)
		(polygon
			(pts
				(arc
					(start 429.126904 -44.577)
					(mid 427.348904 -44.577)
					(end 429.126904 -44.577)
				)
			)
		)
	)
	(zone
		(layers "In4.Cu" "In5.Cu")
		(hatch none 0.5)
		(connect_pads
			(clearance 0)
		)
		(min_thickness 0.25)
		(keepout
			(tracks not_allowed)
			(vias allowed)
			(pads allowed)
			(copperpour not_allowed)
			(footprints allowed)
		)
		(placement
			(enabled no)
			(sheetname "")
		)
		(fill yes
			(thermal_gap 0.5)
			(thermal_bridge_width 0.5)
			(island_removal_mode 0)
		)
		(polygon
			(pts
				(arc
					(start 413.1564 -45.212)
					(mid 411.3784 -45.212)
					(end 413.1564 -45.212)
				)
			)
		)
	)
	(zone
		(layers "In4.Cu" "In5.Cu")
		(hatch none 0.5)
		(connect_pads
			(clearance 0)
		)
		(min_thickness 0.25)
		(keepout
			(tracks not_allowed)
			(vias allowed)
			(pads allowed)
			(copperpour not_allowed)
			(footprints allowed)
		)
		(placement
			(enabled no)
			(sheetname "")
		)
		(fill yes
			(thermal_gap 0.5)
			(thermal_bridge_width 0.5)
			(island_removal_mode 0)
		)
		(polygon
			(pts
				(arc
					(start 418.347398 -25.764236)
					(mid 416.569398 -25.764236)
					(end 418.347398 -25.764236)
				)
			)
		)
	)
	(zone
		(layers "In4.Cu" "In5.Cu")
		(hatch none 0.5)
		(connect_pads
			(clearance 0)
		)
		(min_thickness 0.25)
		(keepout
			(tracks not_allowed)
			(vias allowed)
			(pads allowed)
			(copperpour not_allowed)
			(footprints allowed)
		)
		(placement
			(enabled no)
			(sheetname "")
		)
		(fill yes
			(thermal_gap 0.5)
			(thermal_bridge_width 0.5)
			(island_removal_mode 0)
		)
		(polygon
			(pts
				(arc
					(start 62.937644 -139.7)
					(mid 60.905136 -139.7)
					(end 62.937644 -139.7)
				)
			)
		)
	)
	(zone
		(layers "In4.Cu" "In5.Cu")
		(hatch none 0.5)
		(connect_pads
			(clearance 0)
		)
		(min_thickness 0.25)
		(keepout
			(tracks not_allowed)
			(vias allowed)
			(pads allowed)
			(copperpour not_allowed)
			(footprints allowed)
		)
		(placement
			(enabled no)
			(sheetname "")
		)
		(fill yes
			(thermal_gap 0.5)
			(thermal_bridge_width 0.5)
			(island_removal_mode 0)
		)
		(polygon
			(pts
				(arc
					(start 438.15 -52.07)
					(mid 436.372 -52.07)
					(end 438.15 -52.07)
				)
			)
		)
	)
	(zone
		(layers "In4.Cu" "In5.Cu")
		(hatch none 0.5)
		(connect_pads
			(clearance 0)
		)
		(min_thickness 0.25)
		(keepout
			(tracks not_allowed)
			(vias allowed)
			(pads allowed)
			(copperpour not_allowed)
			(footprints allowed)
		)
		(placement
			(enabled no)
			(sheetname "")
		)
		(fill yes
			(thermal_gap 0.5)
			(thermal_bridge_width 0.5)
			(island_removal_mode 0)
		)
		(polygon
			(pts
				(arc
					(start 370.213128 -166.829994)
					(mid 367.78692 -166.829994)
					(end 370.213128 -166.829994)
				)
			)
		)
	)
	(zone
		(layers "In4.Cu" "In5.Cu")
		(hatch none 0.5)
		(connect_pads
			(clearance 0)
		)
		(min_thickness 0.25)
		(keepout
			(tracks not_allowed)
			(vias allowed)
			(pads allowed)
			(copperpour not_allowed)
			(footprints allowed)
		)
		(placement
			(enabled no)
			(sheetname "")
		)
		(fill yes
			(thermal_gap 0.5)
			(thermal_bridge_width 0.5)
			(island_removal_mode 0)
		)
		(polygon
			(pts
				(arc
					(start 437.43245 -25.146)
					(mid 435.65445 -25.146)
					(end 437.43245 -25.146)
				)
			)
		)
	)
	(zone
		(layers "In4.Cu" "In5.Cu")
		(hatch none 0.5)
		(connect_pads
			(clearance 0)
		)
		(min_thickness 0.25)
		(keepout
			(tracks not_allowed)
			(vias allowed)
			(pads allowed)
			(copperpour not_allowed)
			(footprints allowed)
		)
		(placement
			(enabled no)
			(sheetname "")
		)
		(fill yes
			(thermal_gap 0.5)
			(thermal_bridge_width 0.5)
			(island_removal_mode 0)
		)
		(polygon
			(pts
				(arc
					(start 379.349 -21.336)
					(mid 377.571 -21.336)
					(end 379.349 -21.336)
				)
			)
		)
	)
	(zone
		(layers "In4.Cu" "In5.Cu")
		(hatch none 0.5)
		(connect_pads
			(clearance 0)
		)
		(min_thickness 0.25)
		(keepout
			(tracks not_allowed)
			(vias allowed)
			(pads allowed)
			(copperpour not_allowed)
			(footprints allowed)
		)
		(placement
			(enabled no)
			(sheetname "")
		)
		(fill yes
			(thermal_gap 0.5)
			(thermal_bridge_width 0.5)
			(island_removal_mode 0)
		)
		(polygon
			(pts
				(arc
					(start 429.12665 -47.371)
					(mid 427.34865 -47.371)
					(end 429.12665 -47.371)
				)
			)
		)
	)
	(zone
		(layers "In4.Cu" "In5.Cu")
		(hatch none 0.5)
		(connect_pads
			(clearance 0)
		)
		(min_thickness 0.25)
		(keepout
			(tracks not_allowed)
			(vias allowed)
			(pads allowed)
			(copperpour not_allowed)
			(footprints allowed)
		)
		(placement
			(enabled no)
			(sheetname "")
		)
		(fill yes
			(thermal_gap 0.5)
			(thermal_bridge_width 0.5)
			(island_removal_mode 0)
		)
		(polygon
			(pts
				(arc
					(start 417.957 -46.863)
					(mid 416.179 -46.863)
					(end 417.957 -46.863)
				)
			)
		)
	)
	(zone
		(layers "In4.Cu" "In5.Cu")
		(hatch none 0.5)
		(connect_pads
			(clearance 0)
		)
		(min_thickness 0.25)
		(keepout
			(tracks not_allowed)
			(vias allowed)
			(pads allowed)
			(copperpour not_allowed)
			(footprints allowed)
		)
		(placement
			(enabled no)
			(sheetname "")
		)
		(fill yes
			(thermal_gap 0.5)
			(thermal_bridge_width 0.5)
			(island_removal_mode 0)
		)
		(polygon
			(pts
				(arc
					(start 445.7954 -62.992)
					(mid 444.0174 -62.992)
					(end 445.7954 -62.992)
				)
			)
		)
	)
	(zone
		(layers "In4.Cu" "In5.Cu")
		(hatch none 0.5)
		(connect_pads
			(clearance 0)
		)
		(min_thickness 0.25)
		(keepout
			(tracks not_allowed)
			(vias allowed)
			(pads allowed)
			(copperpour not_allowed)
			(footprints allowed)
		)
		(placement
			(enabled no)
			(sheetname "")
		)
		(fill yes
			(thermal_gap 0.5)
			(thermal_bridge_width 0.5)
			(island_removal_mode 0)
		)
		(polygon
			(pts
				(arc
					(start 409.6004 -20.828)
					(mid 407.8224 -20.828)
					(end 409.6004 -20.828)
				)
			)
		)
	)
	(zone
		(layers "In4.Cu" "In5.Cu")
		(hatch none 0.5)
		(connect_pads
			(clearance 0)
		)
		(min_thickness 0.25)
		(keepout
			(tracks not_allowed)
			(vias allowed)
			(pads allowed)
			(copperpour not_allowed)
			(footprints allowed)
		)
		(placement
			(enabled no)
			(sheetname "")
		)
		(fill yes
			(thermal_gap 0.5)
			(thermal_bridge_width 0.5)
			(island_removal_mode 0)
		)
		(polygon
			(pts
				(arc
					(start 438.994296 -52.140104)
					(mid 437.216296 -52.140104)
					(end 438.994296 -52.140104)
				)
			)
		)
	)
	(zone
		(layers "In4.Cu" "In5.Cu")
		(hatch none 0.5)
		(connect_pads
			(clearance 0)
		)
		(min_thickness 0.25)
		(keepout
			(tracks not_allowed)
			(vias allowed)
			(pads allowed)
			(copperpour not_allowed)
			(footprints allowed)
		)
		(placement
			(enabled no)
			(sheetname "")
		)
		(fill yes
			(thermal_gap 0.5)
			(thermal_bridge_width 0.5)
			(island_removal_mode 0)
		)
		(polygon
			(pts
				(arc
					(start 370.213128 -164.829998)
					(mid 367.78692 -164.829998)
					(end 370.213128 -164.829998)
				)
			)
		)
	)
	(zone
		(layers "In4.Cu" "In5.Cu")
		(hatch none 0.5)
		(connect_pads
			(clearance 0)
		)
		(min_thickness 0.25)
		(keepout
			(tracks not_allowed)
			(vias allowed)
			(pads allowed)
			(copperpour not_allowed)
			(footprints allowed)
		)
		(placement
			(enabled no)
			(sheetname "")
		)
		(fill yes
			(thermal_gap 0.5)
			(thermal_bridge_width 0.5)
			(island_removal_mode 0)
		)
		(polygon
			(pts
				(arc
					(start 370.213128 -168.82999)
					(mid 367.78692 -168.82999)
					(end 370.213128 -168.82999)
				)
			)
		)
	)
	(zone
		(layers "In4.Cu" "In5.Cu")
		(hatch none 0.5)
		(connect_pads
			(clearance 0)
		)
		(min_thickness 0.25)
		(keepout
			(tracks not_allowed)
			(vias allowed)
			(pads allowed)
			(copperpour not_allowed)
			(footprints allowed)
		)
		(placement
			(enabled no)
			(sheetname "")
		)
		(fill yes
			(thermal_gap 0.5)
			(thermal_bridge_width 0.5)
			(island_removal_mode 0)
		)
		(polygon
			(pts
				(arc
					(start 422.91 -50.546)
					(mid 421.132 -50.546)
					(end 422.91 -50.546)
				)
			)
		)
	)
	(zone
		(layers "In4.Cu" "In5.Cu")
		(hatch none 0.5)
		(connect_pads
			(clearance 0)
		)
		(min_thickness 0.25)
		(keepout
			(tracks not_allowed)
			(vias allowed)
			(pads allowed)
			(copperpour not_allowed)
			(footprints allowed)
		)
		(placement
			(enabled no)
			(sheetname "")
		)
		(fill yes
			(thermal_gap 0.5)
			(thermal_bridge_width 0.5)
			(island_removal_mode 0)
		)
		(polygon
			(pts
				(arc
					(start 378.312172 -28.136342)
					(mid 376.534172 -28.136342)
					(end 378.312172 -28.136342)
				)
			)
		)
	)
	(zone
		(layers "In4.Cu" "In5.Cu")
		(hatch none 0.5)
		(connect_pads
			(clearance 0)
		)
		(min_thickness 0.25)
		(keepout
			(tracks not_allowed)
			(vias allowed)
			(pads allowed)
			(copperpour not_allowed)
			(footprints allowed)
		)
		(placement
			(enabled no)
			(sheetname "")
		)
		(fill yes
			(thermal_gap 0.5)
			(thermal_bridge_width 0.5)
			(island_removal_mode 0)
		)
		(polygon
			(pts
				(arc
					(start 445.7954 -60.452)
					(mid 444.0174 -60.452)
					(end 445.7954 -60.452)
				)
			)
		)
	)
	(zone
		(layers "In4.Cu" "In5.Cu")
		(hatch none 0.5)
		(connect_pads
			(clearance 0)
		)
		(min_thickness 0.25)
		(keepout
			(tracks not_allowed)
			(vias allowed)
			(pads allowed)
			(copperpour not_allowed)
			(footprints allowed)
		)
		(placement
			(enabled no)
			(sheetname "")
		)
		(fill yes
			(thermal_gap 0.5)
			(thermal_bridge_width 0.5)
			(island_removal_mode 0)
		)
		(polygon
			(pts
				(arc
					(start 407.8224 -22.606)
					(mid 406.0444 -22.606)
					(end 407.8224 -22.606)
				)
			)
		)
	)
	(zone
		(layers "In4.Cu" "In5.Cu")
		(hatch none 0.5)
		(connect_pads
			(clearance 0)
		)
		(min_thickness 0.25)
		(keepout
			(tracks not_allowed)
			(vias allowed)
			(pads allowed)
			(copperpour not_allowed)
			(footprints allowed)
		)
		(placement
			(enabled no)
			(sheetname "")
		)
		(fill yes
			(thermal_gap 0.5)
			(thermal_bridge_width 0.5)
			(island_removal_mode 0)
		)
		(polygon
			(pts
				(arc
					(start 421.894 -48.641)
					(mid 420.116 -48.641)
					(end 421.894 -48.641)
				)
			)
		)
	)
	(zone
		(layers "In4.Cu" "In5.Cu")
		(hatch none 0.5)
		(connect_pads
			(clearance 0)
		)
		(min_thickness 0.25)
		(keepout
			(tracks not_allowed)
			(vias allowed)
			(pads allowed)
			(copperpour not_allowed)
			(footprints allowed)
		)
		(placement
			(enabled no)
			(sheetname "")
		)
		(fill yes
			(thermal_gap 0.5)
			(thermal_bridge_width 0.5)
			(island_removal_mode 0)
		)
		(polygon
			(pts
				(arc
					(start 377.550172 -28.898342)
					(mid 375.772172 -28.898342)
					(end 377.550172 -28.898342)
				)
			)
		)
	)
	(zone
		(layers "In4.Cu" "In5.Cu")
		(hatch none 0.5)
		(connect_pads
			(clearance 0)
		)
		(min_thickness 0.25)
		(keepout
			(tracks not_allowed)
			(vias allowed)
			(pads allowed)
			(copperpour not_allowed)
			(footprints allowed)
		)
		(placement
			(enabled no)
			(sheetname "")
		)
		(fill yes
			(thermal_gap 0.5)
			(thermal_bridge_width 0.5)
			(island_removal_mode 0)
		)
		(polygon
			(pts
				(arc
					(start 430.657 -19.44878)
					(mid 428.879 -19.44878)
					(end 430.657 -19.44878)
				)
			)
		)
	)
	(zone
		(layers "In4.Cu" "In5.Cu")
		(hatch none 0.5)
		(connect_pads
			(clearance 0)
		)
		(min_thickness 0.25)
		(keepout
			(tracks not_allowed)
			(vias allowed)
			(pads allowed)
			(copperpour not_allowed)
			(footprints allowed)
		)
		(placement
			(enabled no)
			(sheetname "")
		)
		(fill yes
			(thermal_gap 0.5)
			(thermal_bridge_width 0.5)
			(island_removal_mode 0)
		)
		(polygon
			(pts
				(arc
					(start 421.7797 -28.92044)
					(mid 420.0017 -28.92044)
					(end 421.7797 -28.92044)
				)
			)
		)
	)
	(zone
		(layers "In4.Cu" "In5.Cu")
		(hatch none 0.5)
		(connect_pads
			(clearance 0)
		)
		(min_thickness 0.25)
		(keepout
			(tracks not_allowed)
			(vias allowed)
			(pads allowed)
			(copperpour not_allowed)
			(footprints allowed)
		)
		(placement
			(enabled no)
			(sheetname "")
		)
		(fill yes
			(thermal_gap 0.5)
			(thermal_bridge_width 0.5)
			(island_removal_mode 0)
		)
		(polygon
			(pts
				(arc
					(start 64.213232 -164.829998)
					(mid 61.787024 -164.829998)
					(end 64.213232 -164.829998)
				)
			)
		)
	)
	(zone
		(layers "In4.Cu" "In5.Cu")
		(hatch none 0.5)
		(connect_pads
			(clearance 0)
		)
		(min_thickness 0.25)
		(keepout
			(tracks not_allowed)
			(vias allowed)
			(pads allowed)
			(copperpour not_allowed)
			(footprints allowed)
		)
		(placement
			(enabled no)
			(sheetname "")
		)
		(fill yes
			(thermal_gap 0.5)
			(thermal_bridge_width 0.5)
			(island_removal_mode 0)
		)
		(polygon
			(pts
				(arc
					(start 443.0014 -63.627)
					(mid 441.2234 -63.627)
					(end 443.0014 -63.627)
				)
			)
		)
	)
	(zone
		(layers "In4.Cu" "In5.Cu")
		(hatch none 0.5)
		(connect_pads
			(clearance 0)
		)
		(min_thickness 0.25)
		(keepout
			(tracks not_allowed)
			(vias allowed)
			(pads allowed)
			(copperpour not_allowed)
			(footprints allowed)
		)
		(placement
			(enabled no)
			(sheetname "")
		)
		(fill yes
			(thermal_gap 0.5)
			(thermal_bridge_width 0.5)
			(island_removal_mode 0)
		)
		(polygon
			(pts
				(arc
					(start 418.719 -46.863)
					(mid 416.941 -46.863)
					(end 418.719 -46.863)
				)
			)
		)
	)
	(zone
		(layers "In4.Cu" "In5.Cu")
		(hatch none 0.5)
		(connect_pads
			(clearance 0)
		)
		(min_thickness 0.25)
		(keepout
			(tracks not_allowed)
			(vias allowed)
			(pads allowed)
			(copperpour not_allowed)
			(footprints allowed)
		)
		(placement
			(enabled no)
			(sheetname "")
		)
		(fill yes
			(thermal_gap 0.5)
			(thermal_bridge_width 0.5)
			(island_removal_mode 0)
		)
		(polygon
			(pts
				(arc
					(start 345.059 -51.9176)
					(mid 343.281 -51.9176)
					(end 345.059 -51.9176)
				)
			)
		)
	)
	(zone
		(layers "In4.Cu" "In5.Cu")
		(hatch none 0.5)
		(connect_pads
			(clearance 0)
		)
		(min_thickness 0.25)
		(keepout
			(tracks not_allowed)
			(vias allowed)
			(pads allowed)
			(copperpour not_allowed)
			(footprints allowed)
		)
		(placement
			(enabled no)
			(sheetname "")
		)
		(fill yes
			(thermal_gap 0.5)
			(thermal_bridge_width 0.5)
			(island_removal_mode 0)
		)
		(polygon
			(pts
				(arc
					(start 407.8224 -15.875)
					(mid 406.0444 -15.875)
					(end 407.8224 -15.875)
				)
			)
		)
	)
	(zone
		(layers "In4.Cu" "In5.Cu")
		(hatch none 0.5)
		(connect_pads
			(clearance 0)
		)
		(min_thickness 0.25)
		(keepout
			(tracks not_allowed)
			(vias allowed)
			(pads allowed)
			(copperpour not_allowed)
			(footprints allowed)
		)
		(placement
			(enabled no)
			(sheetname "")
		)
		(fill yes
			(thermal_gap 0.5)
			(thermal_bridge_width 0.5)
			(island_removal_mode 0)
		)
		(polygon
			(pts
				(arc
					(start 424.4594 -50.419)
					(mid 422.6814 -50.419)
					(end 424.4594 -50.419)
				)
			)
		)
	)
	(zone
		(layers "In4.Cu" "In5.Cu")
		(hatch none 0.5)
		(connect_pads
			(clearance 0)
		)
		(min_thickness 0.25)
		(keepout
			(tracks not_allowed)
			(vias allowed)
			(pads allowed)
			(copperpour not_allowed)
			(footprints allowed)
		)
		(placement
			(enabled no)
			(sheetname "")
		)
		(fill yes
			(thermal_gap 0.5)
			(thermal_bridge_width 0.5)
			(island_removal_mode 0)
		)
		(polygon
			(pts
				(arc
					(start 364.21314 -166.829994)
					(mid 361.786932 -166.829994)
					(end 364.21314 -166.829994)
				)
			)
		)
	)
	(zone
		(layers "In4.Cu" "In5.Cu")
		(hatch none 0.5)
		(connect_pads
			(clearance 0)
		)
		(min_thickness 0.25)
		(keepout
			(tracks not_allowed)
			(vias allowed)
			(pads allowed)
			(copperpour not_allowed)
			(footprints allowed)
		)
		(placement
			(enabled no)
			(sheetname "")
		)
		(fill yes
			(thermal_gap 0.5)
			(thermal_bridge_width 0.5)
			(island_removal_mode 0)
		)
		(polygon
			(pts
				(arc
					(start 440.79795 -50.546)
					(mid 439.01995 -50.546)
					(end 440.79795 -50.546)
				)
			)
		)
	)
	(zone
		(layers "In4.Cu" "In5.Cu")
		(hatch none 0.5)
		(connect_pads
			(clearance 0)
		)
		(min_thickness 0.25)
		(keepout
			(tracks not_allowed)
			(vias allowed)
			(pads allowed)
			(copperpour not_allowed)
			(footprints allowed)
		)
		(placement
			(enabled no)
			(sheetname "")
		)
		(fill yes
			(thermal_gap 0.5)
			(thermal_bridge_width 0.5)
			(island_removal_mode 0)
		)
		(polygon
			(pts
				(arc
					(start 445.7954 -64.262)
					(mid 444.0174 -64.262)
					(end 445.7954 -64.262)
				)
			)
		)
	)
	(zone
		(layers "In4.Cu" "In5.Cu")
		(hatch none 0.5)
		(connect_pads
			(clearance 0)
		)
		(min_thickness 0.25)
		(keepout
			(tracks not_allowed)
			(vias allowed)
			(pads allowed)
			(copperpour not_allowed)
			(footprints allowed)
		)
		(placement
			(enabled no)
			(sheetname "")
		)
		(fill yes
			(thermal_gap 0.5)
			(thermal_bridge_width 0.5)
			(island_removal_mode 0)
		)
		(polygon
			(pts
				(arc
					(start 82.423 -16.002)
					(mid 80.645 -16.002)
					(end 82.423 -16.002)
				)
			)
		)
	)
	(zone
		(layers "In4.Cu" "In5.Cu")
		(hatch none 0.5)
		(connect_pads
			(clearance 0)
		)
		(min_thickness 0.25)
		(keepout
			(tracks not_allowed)
			(vias allowed)
			(pads allowed)
			(copperpour not_allowed)
			(footprints allowed)
		)
		(placement
			(enabled no)
			(sheetname "")
		)
		(fill yes
			(thermal_gap 0.5)
			(thermal_bridge_width 0.5)
			(island_removal_mode 0)
		)
		(polygon
			(pts
				(arc
					(start 388.1374 -28.321)
					(mid 386.3594 -28.321)
					(end 388.1374 -28.321)
				)
			)
		)
	)
	(zone
		(layers "In4.Cu" "In5.Cu")
		(hatch none 0.5)
		(connect_pads
			(clearance 0)
		)
		(min_thickness 0.25)
		(keepout
			(tracks not_allowed)
			(vias allowed)
			(pads allowed)
			(copperpour not_allowed)
			(footprints allowed)
		)
		(placement
			(enabled no)
			(sheetname "")
		)
		(fill yes
			(thermal_gap 0.5)
			(thermal_bridge_width 0.5)
			(island_removal_mode 0)
		)
		(polygon
			(pts
				(arc
					(start 445.7954 -61.087)
					(mid 444.0174 -61.087)
					(end 445.7954 -61.087)
				)
			)
		)
	)
	(zone
		(layers "In4.Cu" "In5.Cu")
		(hatch none 0.5)
		(connect_pads
			(clearance 0)
		)
		(min_thickness 0.25)
		(keepout
			(tracks not_allowed)
			(vias allowed)
			(pads allowed)
			(copperpour not_allowed)
			(footprints allowed)
		)
		(placement
			(enabled no)
			(sheetname "")
		)
		(fill yes
			(thermal_gap 0.5)
			(thermal_bridge_width 0.5)
			(island_removal_mode 0)
		)
		(polygon
			(pts
				(arc
					(start 81.407 -16.383)
					(mid 79.629 -16.383)
					(end 81.407 -16.383)
				)
			)
		)
	)
	(zone
		(layers "In4.Cu" "In5.Cu")
		(hatch none 0.5)
		(connect_pads
			(clearance 0)
		)
		(min_thickness 0.25)
		(keepout
			(tracks not_allowed)
			(vias allowed)
			(pads allowed)
			(copperpour not_allowed)
			(footprints allowed)
		)
		(placement
			(enabled no)
			(sheetname "")
		)
		(fill yes
			(thermal_gap 0.5)
			(thermal_bridge_width 0.5)
			(island_removal_mode 0)
		)
		(polygon
			(pts
				(arc
					(start 432.174904 -37.592)
					(mid 430.396904 -37.592)
					(end 432.174904 -37.592)
				)
			)
		)
	)
	(zone
		(layers "In4.Cu" "In5.Cu")
		(hatch none 0.5)
		(connect_pads
			(clearance 0)
		)
		(min_thickness 0.25)
		(keepout
			(tracks not_allowed)
			(vias allowed)
			(pads allowed)
			(copperpour not_allowed)
			(footprints allowed)
		)
		(placement
			(enabled no)
			(sheetname "")
		)
		(fill yes
			(thermal_gap 0.5)
			(thermal_bridge_width 0.5)
			(island_removal_mode 0)
		)
		(polygon
			(pts
				(arc
					(start 70.21322 -164.829998)
					(mid 67.787012 -164.829998)
					(end 70.21322 -164.829998)
				)
			)
		)
	)
	(zone
		(layers "In4.Cu" "In5.Cu")
		(hatch none 0.5)
		(connect_pads
			(clearance 0)
		)
		(min_thickness 0.25)
		(keepout
			(tracks not_allowed)
			(vias allowed)
			(pads allowed)
			(copperpour not_allowed)
			(footprints allowed)
		)
		(placement
			(enabled no)
			(sheetname "")
		)
		(fill yes
			(thermal_gap 0.5)
			(thermal_bridge_width 0.5)
			(island_removal_mode 0)
		)
		(polygon
			(pts
				(arc
					(start 379.074172 -27.374342)
					(mid 377.296172 -27.374342)
					(end 379.074172 -27.374342)
				)
			)
		)
	)
	(zone
		(layers "In4.Cu" "In5.Cu")
		(hatch none 0.5)
		(connect_pads
			(clearance 0)
		)
		(min_thickness 0.25)
		(keepout
			(tracks not_allowed)
			(vias allowed)
			(pads allowed)
			(copperpour not_allowed)
			(footprints allowed)
		)
		(placement
			(enabled no)
			(sheetname "")
		)
		(fill yes
			(thermal_gap 0.5)
			(thermal_bridge_width 0.5)
			(island_removal_mode 0)
		)
		(polygon
			(pts
				(arc
					(start 379.836172 -28.898342)
					(mid 378.058172 -28.898342)
					(end 379.836172 -28.898342)
				)
			)
		)
	)
	(zone
		(layers "In4.Cu" "In5.Cu")
		(hatch none 0.5)
		(connect_pads
			(clearance 0)
		)
		(min_thickness 0.25)
		(keepout
			(tracks not_allowed)
			(vias allowed)
			(pads allowed)
			(copperpour not_allowed)
			(footprints allowed)
		)
		(placement
			(enabled no)
			(sheetname "")
		)
		(fill yes
			(thermal_gap 0.5)
			(thermal_bridge_width 0.5)
			(island_removal_mode 0)
		)
		(polygon
			(pts
				(arc
					(start 411.3022 -21.0058)
					(mid 409.5242 -21.0058)
					(end 411.3022 -21.0058)
				)
			)
		)
	)
	(zone
		(layers "In4.Cu" "In5.Cu")
		(hatch none 0.5)
		(connect_pads
			(clearance 0)
		)
		(min_thickness 0.25)
		(keepout
			(tracks not_allowed)
			(vias allowed)
			(pads allowed)
			(copperpour not_allowed)
			(footprints allowed)
		)
		(placement
			(enabled no)
			(sheetname "")
		)
		(fill yes
			(thermal_gap 0.5)
			(thermal_bridge_width 0.5)
			(island_removal_mode 0)
		)
		(polygon
			(pts
				(arc
					(start 334.865472 -92.500196)
					(mid 340.00059 -97.635314)
					(end 345.135454 -92.500196)
				)
				(arc
					(start 345.135454 -87.500206)
					(mid 340.00059 -82.365342)
					(end 334.865472 -87.500206)
				)
			)
		)
	)
	(zone
		(layers "In4.Cu" "In5.Cu")
		(hatch none 0.5)
		(connect_pads
			(clearance 0)
		)
		(min_thickness 0.25)
		(keepout
			(tracks not_allowed)
			(vias allowed)
			(pads allowed)
			(copperpour not_allowed)
			(footprints allowed)
		)
		(placement
			(enabled no)
			(sheetname "")
		)
		(fill yes
			(thermal_gap 0.5)
			(thermal_bridge_width 0.5)
			(island_removal_mode 0)
		)
		(polygon
			(pts
				(arc
					(start 438.1754 -49.46904)
					(mid 436.3974 -49.46904)
					(end 438.1754 -49.46904)
				)
			)
		)
	)
	(zone
		(layers "In4.Cu" "In5.Cu")
		(hatch none 0.5)
		(connect_pads
			(clearance 0)
		)
		(min_thickness 0.25)
		(keepout
			(tracks not_allowed)
			(vias allowed)
			(pads allowed)
			(copperpour not_allowed)
			(footprints allowed)
		)
		(placement
			(enabled no)
			(sheetname "")
		)
		(fill yes
			(thermal_gap 0.5)
			(thermal_bridge_width 0.5)
			(island_removal_mode 0)
		)
		(polygon
			(pts
				(arc
					(start 399.034 -17.018)
					(mid 397.256 -17.018)
					(end 399.034 -17.018)
				)
			)
		)
	)
	(zone
		(layers "In4.Cu" "In5.Cu")
		(hatch none 0.5)
		(connect_pads
			(clearance 0)
		)
		(min_thickness 0.25)
		(keepout
			(tracks not_allowed)
			(vias allowed)
			(pads allowed)
			(copperpour not_allowed)
			(footprints allowed)
		)
		(placement
			(enabled no)
			(sheetname "")
		)
		(fill yes
			(thermal_gap 0.5)
			(thermal_bridge_width 0.5)
			(island_removal_mode 0)
		)
		(polygon
			(pts
				(arc
					(start 35.0774 -38.1)
					(mid 33.2994 -38.1)
					(end 35.0774 -38.1)
				)
			)
		)
	)
	(zone
		(layers "In4.Cu" "In5.Cu")
		(hatch none 0.5)
		(connect_pads
			(clearance 0)
		)
		(min_thickness 0.25)
		(keepout
			(tracks not_allowed)
			(vias allowed)
			(pads allowed)
			(copperpour not_allowed)
			(footprints allowed)
		)
		(placement
			(enabled no)
			(sheetname "")
		)
		(fill yes
			(thermal_gap 0.5)
			(thermal_bridge_width 0.5)
			(island_removal_mode 0)
		)
		(polygon
			(pts
				(arc
					(start 440.055 -46.609)
					(mid 438.277 -46.609)
					(end 440.055 -46.609)
				)
			)
		)
	)
	(zone
		(layers "In4.Cu" "In5.Cu")
		(hatch none 0.5)
		(connect_pads
			(clearance 0)
		)
		(min_thickness 0.25)
		(keepout
			(tracks not_allowed)
			(vias allowed)
			(pads allowed)
			(copperpour not_allowed)
			(footprints allowed)
		)
		(placement
			(enabled no)
			(sheetname "")
		)
		(fill yes
			(thermal_gap 0.5)
			(thermal_bridge_width 0.5)
			(island_removal_mode 0)
		)
		(polygon
			(pts
				(arc
					(start 436.124096 -27.813)
					(mid 434.346096 -27.813)
					(end 436.124096 -27.813)
				)
			)
		)
	)
	(zone
		(layers "In4.Cu" "In5.Cu")
		(hatch none 0.5)
		(connect_pads
			(clearance 0)
		)
		(min_thickness 0.25)
		(keepout
			(tracks not_allowed)
			(vias allowed)
			(pads allowed)
			(copperpour not_allowed)
			(footprints allowed)
		)
		(placement
			(enabled no)
			(sheetname "")
		)
		(fill yes
			(thermal_gap 0.5)
			(thermal_bridge_width 0.5)
			(island_removal_mode 0)
		)
		(polygon
			(pts
				(arc
					(start 62.937644 -119.38)
					(mid 60.905136 -119.38)
					(end 62.937644 -119.38)
				)
			)
		)
	)
	(zone
		(layers "In4.Cu" "In5.Cu")
		(hatch none 0.5)
		(connect_pads
			(clearance 0)
		)
		(min_thickness 0.25)
		(keepout
			(tracks not_allowed)
			(vias allowed)
			(pads allowed)
			(copperpour not_allowed)
			(footprints allowed)
		)
		(placement
			(enabled no)
			(sheetname "")
		)
		(fill yes
			(thermal_gap 0.5)
			(thermal_bridge_width 0.5)
			(island_removal_mode 0)
		)
		(polygon
			(pts
				(arc
					(start 455.4474 -62.738)
					(mid 453.6694 -62.738)
					(end 455.4474 -62.738)
				)
			)
		)
	)
	(zone
		(layers "In4.Cu" "In5.Cu")
		(hatch none 0.5)
		(connect_pads
			(clearance 0)
		)
		(min_thickness 0.25)
		(keepout
			(tracks not_allowed)
			(vias allowed)
			(pads allowed)
			(copperpour not_allowed)
			(footprints allowed)
		)
		(placement
			(enabled no)
			(sheetname "")
		)
		(fill yes
			(thermal_gap 0.5)
			(thermal_bridge_width 0.5)
			(island_removal_mode 0)
		)
		(polygon
			(pts
				(arc
					(start 420.32555 -31.769304)
					(mid 418.54755 -31.769304)
					(end 420.32555 -31.769304)
				)
			)
		)
	)
	(zone
		(layers "In4.Cu" "In5.Cu")
		(hatch none 0.5)
		(connect_pads
			(clearance 0)
		)
		(min_thickness 0.25)
		(keepout
			(tracks not_allowed)
			(vias allowed)
			(pads allowed)
			(copperpour not_allowed)
			(footprints allowed)
		)
		(placement
			(enabled no)
			(sheetname "")
		)
		(fill yes
			(thermal_gap 0.5)
			(thermal_bridge_width 0.5)
			(island_removal_mode 0)
		)
		(polygon
			(pts
				(arc
					(start 219.9894 -7.493)
					(mid 218.2114 -7.493)
					(end 219.9894 -7.493)
				)
			)
		)
	)
	(zone
		(layers "In4.Cu" "In5.Cu")
		(hatch none 0.5)
		(connect_pads
			(clearance 0)
		)
		(min_thickness 0.25)
		(keepout
			(tracks not_allowed)
			(vias allowed)
			(pads allowed)
			(copperpour not_allowed)
			(footprints allowed)
		)
		(placement
			(enabled no)
			(sheetname "")
		)
		(fill yes
			(thermal_gap 0.5)
			(thermal_bridge_width 0.5)
			(island_removal_mode 0)
		)
		(polygon
			(pts
				(arc
					(start 428.244 -30.94355)
					(mid 426.466 -30.94355)
					(end 428.244 -30.94355)
				)
			)
		)
	)
	(zone
		(layers "In4.Cu" "In5.Cu")
		(hatch none 0.5)
		(connect_pads
			(clearance 0)
		)
		(min_thickness 0.25)
		(keepout
			(tracks not_allowed)
			(vias allowed)
			(pads allowed)
			(copperpour not_allowed)
			(footprints allowed)
		)
		(placement
			(enabled no)
			(sheetname "")
		)
		(fill yes
			(thermal_gap 0.5)
			(thermal_bridge_width 0.5)
			(island_removal_mode 0)
		)
		(polygon
			(pts
				(arc
					(start 394.843 -24.511)
					(mid 393.065 -24.511)
					(end 394.843 -24.511)
				)
			)
		)
	)
	(zone
		(layers "In4.Cu" "In5.Cu")
		(hatch none 0.5)
		(connect_pads
			(clearance 0)
		)
		(min_thickness 0.25)
		(keepout
			(tracks not_allowed)
			(vias allowed)
			(pads allowed)
			(copperpour not_allowed)
			(footprints allowed)
		)
		(placement
			(enabled no)
			(sheetname "")
		)
		(fill yes
			(thermal_gap 0.5)
			(thermal_bridge_width 0.5)
			(island_removal_mode 0)
		)
		(polygon
			(pts
				(arc
					(start 399.161 -91.559888)
					(mid 396.113 -91.559888)
					(end 399.161 -91.559888)
				)
			)
		)
	)
	(zone
		(layers "In4.Cu" "In5.Cu")
		(hatch none 0.5)
		(connect_pads
			(clearance 0)
		)
		(min_thickness 0.25)
		(keepout
			(tracks not_allowed)
			(vias allowed)
			(pads allowed)
			(copperpour not_allowed)
			(footprints allowed)
		)
		(placement
			(enabled no)
			(sheetname "")
		)
		(fill yes
			(thermal_gap 0.5)
			(thermal_bridge_width 0.5)
			(island_removal_mode 0)
		)
		(polygon
			(pts
				(arc
					(start 422.5925 -29.65704)
					(mid 420.8145 -29.65704)
					(end 422.5925 -29.65704)
				)
			)
		)
	)
	(zone
		(layers "In4.Cu" "In5.Cu")
		(hatch none 0.5)
		(connect_pads
			(clearance 0)
		)
		(min_thickness 0.25)
		(keepout
			(tracks not_allowed)
			(vias allowed)
			(pads allowed)
			(copperpour not_allowed)
			(footprints allowed)
		)
		(placement
			(enabled no)
			(sheetname "")
		)
		(fill yes
			(thermal_gap 0.5)
			(thermal_bridge_width 0.5)
			(island_removal_mode 0)
		)
		(polygon
			(pts
				(arc
					(start 449.81495 -34.798)
					(mid 448.03695 -34.798)
					(end 449.81495 -34.798)
				)
			)
		)
	)
	(zone
		(layers "In4.Cu" "In5.Cu")
		(hatch none 0.5)
		(connect_pads
			(clearance 0)
		)
		(min_thickness 0.25)
		(keepout
			(tracks not_allowed)
			(vias allowed)
			(pads allowed)
			(copperpour not_allowed)
			(footprints allowed)
		)
		(placement
			(enabled no)
			(sheetname "")
		)
		(fill yes
			(thermal_gap 0.5)
			(thermal_bridge_width 0.5)
			(island_removal_mode 0)
		)
		(polygon
			(pts
				(arc
					(start 222.512382 -7.475728)
					(mid 220.734382 -7.475728)
					(end 222.512382 -7.475728)
				)
			)
		)
	)
	(zone
		(layers "In4.Cu" "In5.Cu")
		(hatch none 0.5)
		(connect_pads
			(clearance 0)
		)
		(min_thickness 0.25)
		(keepout
			(tracks not_allowed)
			(vias allowed)
			(pads allowed)
			(copperpour not_allowed)
			(footprints allowed)
		)
		(placement
			(enabled no)
			(sheetname "")
		)
		(fill yes
			(thermal_gap 0.5)
			(thermal_bridge_width 0.5)
			(island_removal_mode 0)
		)
		(polygon
			(pts
				(arc
					(start 412.0642 -21.0058)
					(mid 410.2862 -21.0058)
					(end 412.0642 -21.0058)
				)
			)
		)
	)
	(zone
		(layers "In4.Cu" "In5.Cu")
		(hatch none 0.5)
		(connect_pads
			(clearance 0)
		)
		(min_thickness 0.25)
		(keepout
			(tracks not_allowed)
			(vias allowed)
			(pads allowed)
			(copperpour not_allowed)
			(footprints allowed)
		)
		(placement
			(enabled no)
			(sheetname "")
		)
		(fill yes
			(thermal_gap 0.5)
			(thermal_bridge_width 0.5)
			(island_removal_mode 0)
		)
		(polygon
			(pts
				(arc
					(start 83.693 -18.916904)
					(mid 81.915 -18.916904)
					(end 83.693 -18.916904)
				)
			)
		)
	)
	(zone
		(layers "In4.Cu" "In5.Cu")
		(hatch none 0.5)
		(connect_pads
			(clearance 0)
		)
		(min_thickness 0.25)
		(keepout
			(tracks not_allowed)
			(vias allowed)
			(pads allowed)
			(copperpour not_allowed)
			(footprints allowed)
		)
		(placement
			(enabled no)
			(sheetname "")
		)
		(fill yes
			(thermal_gap 0.5)
			(thermal_bridge_width 0.5)
			(island_removal_mode 0)
		)
		(polygon
			(pts
				(arc
					(start 411.3022 -19.4818)
					(mid 409.5242 -19.4818)
					(end 411.3022 -19.4818)
				)
			)
		)
	)
	(zone
		(layers "In4.Cu" "In5.Cu")
		(hatch none 0.5)
		(connect_pads
			(clearance 0)
		)
		(min_thickness 0.25)
		(keepout
			(tracks not_allowed)
			(vias allowed)
			(pads allowed)
			(copperpour not_allowed)
			(footprints allowed)
		)
		(placement
			(enabled no)
			(sheetname "")
		)
		(fill yes
			(thermal_gap 0.5)
			(thermal_bridge_width 0.5)
			(island_removal_mode 0)
		)
		(polygon
			(pts
				(arc
					(start 408.8384 -22.606)
					(mid 407.0604 -22.606)
					(end 408.8384 -22.606)
				)
			)
		)
	)
	(zone
		(layers "In4.Cu" "In5.Cu")
		(hatch none 0.5)
		(connect_pads
			(clearance 0)
		)
		(min_thickness 0.25)
		(keepout
			(tracks not_allowed)
			(vias allowed)
			(pads allowed)
			(copperpour not_allowed)
			(footprints allowed)
		)
		(placement
			(enabled no)
			(sheetname "")
		)
		(fill yes
			(thermal_gap 0.5)
			(thermal_bridge_width 0.5)
			(island_removal_mode 0)
		)
		(polygon
			(pts
				(arc
					(start 40.83812 -154.830018)
					(mid 38.411912 -154.830018)
					(end 40.83812 -154.830018)
				)
			)
		)
	)
	(zone
		(layers "In4.Cu" "In5.Cu")
		(hatch none 0.5)
		(connect_pads
			(clearance 0)
		)
		(min_thickness 0.25)
		(keepout
			(tracks not_allowed)
			(vias allowed)
			(pads allowed)
			(copperpour not_allowed)
			(footprints allowed)
		)
		(placement
			(enabled no)
			(sheetname "")
		)
		(fill yes
			(thermal_gap 0.5)
			(thermal_bridge_width 0.5)
			(island_removal_mode 0)
		)
		(polygon
			(pts
				(arc
					(start 64.933068 -5.290058)
					(mid 62.50686 -5.290058)
					(end 64.933068 -5.290058)
				)
			)
		)
	)
	(zone
		(layers "In4.Cu" "In5.Cu")
		(hatch none 0.5)
		(connect_pads
			(clearance 0)
		)
		(min_thickness 0.25)
		(keepout
			(tracks not_allowed)
			(vias allowed)
			(pads allowed)
			(copperpour not_allowed)
			(footprints allowed)
		)
		(placement
			(enabled no)
			(sheetname "")
		)
		(fill yes
			(thermal_gap 0.5)
			(thermal_bridge_width 0.5)
			(island_removal_mode 0)
		)
		(polygon
			(pts
				(arc
					(start 454.011538 -61.670692)
					(mid 452.233538 -61.670692)
					(end 454.011538 -61.670692)
				)
			)
		)
	)
	(zone
		(layers "In4.Cu" "In5.Cu")
		(hatch none 0.5)
		(connect_pads
			(clearance 0)
		)
		(min_thickness 0.25)
		(keepout
			(tracks not_allowed)
			(vias allowed)
			(pads allowed)
			(copperpour not_allowed)
			(footprints allowed)
		)
		(placement
			(enabled no)
			(sheetname "")
		)
		(fill yes
			(thermal_gap 0.5)
			(thermal_bridge_width 0.5)
			(island_removal_mode 0)
		)
		(polygon
			(pts
				(arc
					(start 410.8704 -30.48)
					(mid 409.0924 -30.48)
					(end 410.8704 -30.48)
				)
			)
		)
	)
	(zone
		(layers "In4.Cu" "In5.Cu")
		(hatch none 0.5)
		(connect_pads
			(clearance 0)
		)
		(min_thickness 0.25)
		(keepout
			(tracks not_allowed)
			(vias allowed)
			(pads allowed)
			(copperpour not_allowed)
			(footprints allowed)
		)
		(placement
			(enabled no)
			(sheetname "")
		)
		(fill yes
			(thermal_gap 0.5)
			(thermal_bridge_width 0.5)
			(island_removal_mode 0)
		)
		(polygon
			(pts
				(arc
					(start 419.785038 -33.76041)
					(mid 418.007038 -33.76041)
					(end 419.785038 -33.76041)
				)
			)
		)
	)
	(zone
		(layers "In4.Cu" "In5.Cu")
		(hatch none 0.5)
		(connect_pads
			(clearance 0)
		)
		(min_thickness 0.25)
		(keepout
			(tracks not_allowed)
			(vias allowed)
			(pads allowed)
			(copperpour not_allowed)
			(footprints allowed)
		)
		(placement
			(enabled no)
			(sheetname "")
		)
		(fill yes
			(thermal_gap 0.5)
			(thermal_bridge_width 0.5)
			(island_removal_mode 0)
		)
		(polygon
			(pts
				(arc
					(start 377.550172 -26.612342)
					(mid 375.772172 -26.612342)
					(end 377.550172 -26.612342)
				)
			)
		)
	)
	(zone
		(layers "In4.Cu" "In5.Cu")
		(hatch none 0.5)
		(connect_pads
			(clearance 0)
		)
		(min_thickness 0.25)
		(keepout
			(tracks not_allowed)
			(vias allowed)
			(pads allowed)
			(copperpour not_allowed)
			(footprints allowed)
		)
		(placement
			(enabled no)
			(sheetname "")
		)
		(fill yes
			(thermal_gap 0.5)
			(thermal_bridge_width 0.5)
			(island_removal_mode 0)
		)
		(polygon
			(pts
				(arc
					(start 429.126904 -41.783)
					(mid 427.348904 -41.783)
					(end 429.126904 -41.783)
				)
			)
		)
	)
	(zone
		(layers "In4.Cu" "In5.Cu")
		(hatch none 0.5)
		(connect_pads
			(clearance 0)
		)
		(min_thickness 0.25)
		(keepout
			(tracks not_allowed)
			(vias allowed)
			(pads allowed)
			(copperpour not_allowed)
			(footprints allowed)
		)
		(placement
			(enabled no)
			(sheetname "")
		)
		(fill yes
			(thermal_gap 0.5)
			(thermal_bridge_width 0.5)
			(island_removal_mode 0)
		)
		(polygon
			(pts
				(arc
					(start 70.973188 -4.575048)
					(mid 68.54698 -4.575048)
					(end 70.973188 -4.575048)
				)
			)
		)
	)
	(zone
		(layers "In4.Cu" "In5.Cu")
		(hatch none 0.5)
		(connect_pads
			(clearance 0)
		)
		(min_thickness 0.25)
		(keepout
			(tracks not_allowed)
			(vias allowed)
			(pads allowed)
			(copperpour not_allowed)
			(footprints allowed)
		)
		(placement
			(enabled no)
			(sheetname "")
		)
		(fill yes
			(thermal_gap 0.5)
			(thermal_bridge_width 0.5)
			(island_removal_mode 0)
		)
		(polygon
			(pts
				(arc
					(start 61.170566 -26.266648)
					(mid 59.392566 -26.266648)
					(end 61.170566 -26.266648)
				)
			)
		)
	)
	(zone
		(layers "In4.Cu" "In5.Cu")
		(hatch none 0.5)
		(connect_pads
			(clearance 0)
		)
		(min_thickness 0.25)
		(keepout
			(tracks not_allowed)
			(vias allowed)
			(pads allowed)
			(copperpour not_allowed)
			(footprints allowed)
		)
		(placement
			(enabled no)
			(sheetname "")
		)
		(fill yes
			(thermal_gap 0.5)
			(thermal_bridge_width 0.5)
			(island_removal_mode 0)
		)
		(polygon
			(pts
				(arc
					(start 434.4924 -36.195)
					(mid 432.7144 -36.195)
					(end 434.4924 -36.195)
				)
			)
		)
	)
	(zone
		(layers "In4.Cu" "In5.Cu")
		(hatch none 0.5)
		(connect_pads
			(clearance 0)
		)
		(min_thickness 0.25)
		(keepout
			(tracks not_allowed)
			(vias allowed)
			(pads allowed)
			(copperpour not_allowed)
			(footprints allowed)
		)
		(placement
			(enabled no)
			(sheetname "")
		)
		(fill yes
			(thermal_gap 0.5)
			(thermal_bridge_width 0.5)
			(island_removal_mode 0)
		)
		(polygon
			(pts
				(arc
					(start 443.0014 -59.817)
					(mid 441.2234 -59.817)
					(end 443.0014 -59.817)
				)
			)
		)
	)
	(zone
		(layers "In4.Cu" "In5.Cu")
		(hatch none 0.5)
		(connect_pads
			(clearance 0)
		)
		(min_thickness 0.25)
		(keepout
			(tracks not_allowed)
			(vias allowed)
			(pads allowed)
			(copperpour not_allowed)
			(footprints allowed)
		)
		(placement
			(enabled no)
			(sheetname "")
		)
		(fill yes
			(thermal_gap 0.5)
			(thermal_bridge_width 0.5)
			(island_removal_mode 0)
		)
		(polygon
			(pts
				(arc
					(start 43.379644 -139.7)
					(mid 41.347136 -139.7)
					(end 43.379644 -139.7)
				)
			)
		)
	)
	(zone
		(layers "In4.Cu" "In5.Cu")
		(hatch none 0.5)
		(connect_pads
			(clearance 0)
		)
		(min_thickness 0.25)
		(keepout
			(tracks not_allowed)
			(vias allowed)
			(pads allowed)
			(copperpour not_allowed)
			(footprints allowed)
		)
		(placement
			(enabled no)
			(sheetname "")
		)
		(fill yes
			(thermal_gap 0.5)
			(thermal_bridge_width 0.5)
			(island_removal_mode 0)
		)
		(polygon
			(pts
				(arc
					(start 432.943 -41.783)
					(mid 431.165 -41.783)
					(end 432.943 -41.783)
				)
			)
		)
	)
	(zone
		(layers "In4.Cu" "In5.Cu")
		(hatch none 0.5)
		(connect_pads
			(clearance 0)
		)
		(min_thickness 0.25)
		(keepout
			(tracks not_allowed)
			(vias allowed)
			(pads allowed)
			(copperpour not_allowed)
			(footprints allowed)
		)
		(placement
			(enabled no)
			(sheetname "")
		)
		(fill yes
			(thermal_gap 0.5)
			(thermal_bridge_width 0.5)
			(island_removal_mode 0)
		)
		(polygon
			(pts
				(arc
					(start 364.21314 -168.82999)
					(mid 361.786932 -168.82999)
					(end 364.21314 -168.82999)
				)
			)
		)
	)
	(zone
		(layers "In4.Cu" "In5.Cu")
		(hatch none 0.5)
		(connect_pads
			(clearance 0)
		)
		(min_thickness 0.25)
		(keepout
			(tracks not_allowed)
			(vias allowed)
			(pads allowed)
			(copperpour not_allowed)
			(footprints allowed)
		)
		(placement
			(enabled no)
			(sheetname "")
		)
		(fill yes
			(thermal_gap 0.5)
			(thermal_bridge_width 0.5)
			(island_removal_mode 0)
		)
		(polygon
			(pts
				(arc
					(start 432.943 -40.386)
					(mid 431.165 -40.386)
					(end 432.943 -40.386)
				)
			)
		)
	)
	(zone
		(layers "In4.Cu" "In5.Cu")
		(hatch none 0.5)
		(connect_pads
			(clearance 0)
		)
		(min_thickness 0.25)
		(keepout
			(tracks not_allowed)
			(vias allowed)
			(pads allowed)
			(copperpour not_allowed)
			(footprints allowed)
		)
		(placement
			(enabled no)
			(sheetname "")
		)
		(fill yes
			(thermal_gap 0.5)
			(thermal_bridge_width 0.5)
			(island_removal_mode 0)
		)
		(polygon
			(pts
				(arc
					(start 52.013104 -166.829994)
					(mid 49.586896 -166.829994)
					(end 52.013104 -166.829994)
				)
			)
		)
	)
	(zone
		(layers "In4.Cu" "In5.Cu")
		(hatch none 0.5)
		(connect_pads
			(clearance 0)
		)
		(min_thickness 0.25)
		(keepout
			(tracks not_allowed)
			(vias allowed)
			(pads allowed)
			(copperpour not_allowed)
			(footprints allowed)
		)
		(placement
			(enabled no)
			(sheetname "")
		)
		(fill yes
			(thermal_gap 0.5)
			(thermal_bridge_width 0.5)
			(island_removal_mode 0)
		)
		(polygon
			(pts
				(arc
					(start 399.161 -132.199888)
					(mid 396.113 -132.199888)
					(end 399.161 -132.199888)
				)
			)
		)
	)
	(zone
		(layers "In4.Cu" "In5.Cu")
		(hatch none 0.5)
		(connect_pads
			(clearance 0)
		)
		(min_thickness 0.25)
		(keepout
			(tracks not_allowed)
			(vias allowed)
			(pads allowed)
			(copperpour not_allowed)
			(footprints allowed)
		)
		(placement
			(enabled no)
			(sheetname "")
		)
		(fill yes
			(thermal_gap 0.5)
			(thermal_bridge_width 0.5)
			(island_removal_mode 0)
		)
		(polygon
			(pts
				(arc
					(start 376.213116 -168.82999)
					(mid 373.786908 -168.82999)
					(end 376.213116 -168.82999)
				)
			)
		)
	)
	(zone
		(layers "In4.Cu" "In5.Cu")
		(hatch none 0.5)
		(connect_pads
			(clearance 0)
		)
		(min_thickness 0.25)
		(keepout
			(tracks not_allowed)
			(vias allowed)
			(pads allowed)
			(copperpour not_allowed)
			(footprints allowed)
		)
		(placement
			(enabled no)
			(sheetname "")
		)
		(fill yes
			(thermal_gap 0.5)
			(thermal_bridge_width 0.5)
			(island_removal_mode 0)
		)
		(polygon
			(pts
				(arc
					(start 429.6664 -46.79188)
					(mid 427.8884 -46.79188)
					(end 429.6664 -46.79188)
				)
			)
		)
	)
	(zone
		(layers "In4.Cu" "In5.Cu")
		(hatch none 0.5)
		(connect_pads
			(clearance 0)
		)
		(min_thickness 0.25)
		(keepout
			(tracks not_allowed)
			(vias allowed)
			(pads allowed)
			(copperpour not_allowed)
			(footprints allowed)
		)
		(placement
			(enabled no)
			(sheetname "")
		)
		(fill yes
			(thermal_gap 0.5)
			(thermal_bridge_width 0.5)
			(island_removal_mode 0)
		)
		(polygon
			(pts
				(arc
					(start 422.021 -45.593)
					(mid 420.243 -45.593)
					(end 422.021 -45.593)
				)
			)
		)
	)
	(zone
		(layers "In4.Cu" "In5.Cu")
		(hatch none 0.5)
		(connect_pads
			(clearance 0)
		)
		(min_thickness 0.25)
		(keepout
			(tracks not_allowed)
			(vias allowed)
			(pads allowed)
			(copperpour not_allowed)
			(footprints allowed)
		)
		(placement
			(enabled no)
			(sheetname "")
		)
		(fill yes
			(thermal_gap 0.5)
			(thermal_bridge_width 0.5)
			(island_removal_mode 0)
		)
		(polygon
			(pts
				(arc
					(start 372.213124 -164.829998)
					(mid 369.786916 -164.829998)
					(end 372.213124 -164.829998)
				)
			)
		)
	)
	(zone
		(layers "In4.Cu" "In5.Cu")
		(hatch none 0.5)
		(connect_pads
			(clearance 0)
		)
		(min_thickness 0.25)
		(keepout
			(tracks not_allowed)
			(vias allowed)
			(pads allowed)
			(copperpour not_allowed)
			(footprints allowed)
		)
		(placement
			(enabled no)
			(sheetname "")
		)
		(fill yes
			(thermal_gap 0.5)
			(thermal_bridge_width 0.5)
			(island_removal_mode 0)
		)
		(polygon
			(pts
				(arc
					(start 64.213232 -168.82999)
					(mid 61.787024 -168.82999)
					(end 64.213232 -168.82999)
				)
			)
		)
	)
	(zone
		(layers "In4.Cu" "In5.Cu")
		(hatch none 0.5)
		(connect_pads
			(clearance 0)
		)
		(min_thickness 0.25)
		(keepout
			(tracks not_allowed)
			(vias allowed)
			(pads allowed)
			(copperpour not_allowed)
			(footprints allowed)
		)
		(placement
			(enabled no)
			(sheetname "")
		)
		(fill yes
			(thermal_gap 0.5)
			(thermal_bridge_width 0.5)
			(island_removal_mode 0)
		)
		(polygon
			(pts
				(arc
					(start 386.412994 -166.829994)
					(mid 383.986786 -166.829994)
					(end 386.412994 -166.829994)
				)
			)
		)
	)
	(zone
		(layers "In4.Cu" "In5.Cu")
		(hatch none 0.5)
		(connect_pads
			(clearance 0)
		)
		(min_thickness 0.25)
		(keepout
			(tracks not_allowed)
			(vias allowed)
			(pads allowed)
			(copperpour not_allowed)
			(footprints allowed)
		)
		(placement
			(enabled no)
			(sheetname "")
		)
		(fill yes
			(thermal_gap 0.5)
			(thermal_bridge_width 0.5)
			(island_removal_mode 0)
		)
		(polygon
			(pts
				(arc
					(start 432.17465 -45.974)
					(mid 430.39665 -45.974)
					(end 432.17465 -45.974)
				)
			)
		)
	)
	(zone
		(layers "In4.Cu" "In5.Cu")
		(hatch none 0.5)
		(connect_pads
			(clearance 0)
		)
		(min_thickness 0.25)
		(keepout
			(tracks not_allowed)
			(vias allowed)
			(pads allowed)
			(copperpour not_allowed)
			(footprints allowed)
		)
		(placement
			(enabled no)
			(sheetname "")
		)
		(fill yes
			(thermal_gap 0.5)
			(thermal_bridge_width 0.5)
			(island_removal_mode 0)
		)
		(polygon
			(pts
				(arc
					(start 72.243188 -3.305048)
					(mid 69.81698 -3.305048)
					(end 72.243188 -3.305048)
				)
			)
		)
	)
	(zone
		(layers "In4.Cu" "In5.Cu")
		(hatch none 0.5)
		(connect_pads
			(clearance 0)
		)
		(min_thickness 0.25)
		(keepout
			(tracks not_allowed)
			(vias allowed)
			(pads allowed)
			(copperpour not_allowed)
			(footprints allowed)
		)
		(placement
			(enabled no)
			(sheetname "")
		)
		(fill yes
			(thermal_gap 0.5)
			(thermal_bridge_width 0.5)
			(island_removal_mode 0)
		)
		(polygon
			(pts
				(arc
					(start 406.338278 -168.82999)
					(mid 403.91207 -168.82999)
					(end 406.338278 -168.82999)
				)
			)
		)
	)
	(zone
		(layers "In4.Cu" "In5.Cu")
		(hatch none 0.5)
		(connect_pads
			(clearance 0)
		)
		(min_thickness 0.25)
		(keepout
			(tracks not_allowed)
			(vias allowed)
			(pads allowed)
			(copperpour not_allowed)
			(footprints allowed)
		)
		(placement
			(enabled no)
			(sheetname "")
		)
		(fill yes
			(thermal_gap 0.5)
			(thermal_bridge_width 0.5)
			(island_removal_mode 0)
		)
		(polygon
			(pts
				(arc
					(start 450.32295 -51.562)
					(mid 448.54495 -51.562)
					(end 450.32295 -51.562)
				)
			)
		)
	)
	(zone
		(layers "In4.Cu" "In5.Cu")
		(hatch none 0.5)
		(connect_pads
			(clearance 0)
		)
		(min_thickness 0.25)
		(keepout
			(tracks not_allowed)
			(vias allowed)
			(pads allowed)
			(copperpour not_allowed)
			(footprints allowed)
		)
		(placement
			(enabled no)
			(sheetname "")
		)
		(fill yes
			(thermal_gap 0.5)
			(thermal_bridge_width 0.5)
			(island_removal_mode 0)
		)
		(polygon
			(pts
				(arc
					(start 436.28945 -47.498)
					(mid 434.51145 -47.498)
					(end 436.28945 -47.498)
				)
			)
		)
	)
	(zone
		(layers "In4.Cu" "In5.Cu")
		(hatch none 0.5)
		(connect_pads
			(clearance 0)
		)
		(min_thickness 0.25)
		(keepout
			(tracks not_allowed)
			(vias allowed)
			(pads allowed)
			(copperpour not_allowed)
			(footprints allowed)
		)
		(placement
			(enabled no)
			(sheetname "")
		)
		(fill yes
			(thermal_gap 0.5)
			(thermal_bridge_width 0.5)
			(island_removal_mode 0)
		)
		(polygon
			(pts
				(arc
					(start 413.73298 -26.40076)
					(mid 411.95498 -26.40076)
					(end 413.73298 -26.40076)
				)
			)
		)
	)
	(zone
		(layers "In4.Cu" "In5.Cu")
		(hatch none 0.5)
		(connect_pads
			(clearance 0)
		)
		(min_thickness 0.25)
		(keepout
			(tracks not_allowed)
			(vias allowed)
			(pads allowed)
			(copperpour not_allowed)
			(footprints allowed)
		)
		(placement
			(enabled no)
			(sheetname "")
		)
		(fill yes
			(thermal_gap 0.5)
			(thermal_bridge_width 0.5)
			(island_removal_mode 0)
		)
		(polygon
			(pts
				(arc
					(start 417.120578 -33.770316)
					(mid 415.342578 -33.770316)
					(end 417.120578 -33.770316)
				)
			)
		)
	)
	(zone
		(layers "In4.Cu" "In5.Cu")
		(hatch none 0.5)
		(connect_pads
			(clearance 0)
		)
		(min_thickness 0.25)
		(keepout
			(tracks not_allowed)
			(vias allowed)
			(pads allowed)
			(copperpour not_allowed)
			(footprints allowed)
		)
		(placement
			(enabled no)
			(sheetname "")
		)
		(fill yes
			(thermal_gap 0.5)
			(thermal_bridge_width 0.5)
			(island_removal_mode 0)
		)
		(polygon
			(pts
				(arc
					(start 389.9154 -24.623014)
					(mid 388.1374 -24.623014)
					(end 389.9154 -24.623014)
				)
			)
		)
	)
	(zone
		(layers "In4.Cu" "In5.Cu")
		(hatch none 0.5)
		(connect_pads
			(clearance 0)
		)
		(min_thickness 0.25)
		(keepout
			(tracks not_allowed)
			(vias allowed)
			(pads allowed)
			(copperpour not_allowed)
			(footprints allowed)
		)
		(placement
			(enabled no)
			(sheetname "")
		)
		(fill yes
			(thermal_gap 0.5)
			(thermal_bridge_width 0.5)
			(island_removal_mode 0)
		)
		(polygon
			(pts
				(arc
					(start 379.603 -50.919888)
					(mid 376.555 -50.919888)
					(end 379.603 -50.919888)
				)
			)
		)
	)
	(zone
		(layers "In4.Cu" "In5.Cu")
		(hatch none 0.5)
		(connect_pads
			(clearance 0)
		)
		(min_thickness 0.25)
		(keepout
			(tracks not_allowed)
			(vias allowed)
			(pads allowed)
			(copperpour not_allowed)
			(footprints allowed)
		)
		(placement
			(enabled no)
			(sheetname "")
		)
		(fill yes
			(thermal_gap 0.5)
			(thermal_bridge_width 0.5)
			(island_removal_mode 0)
		)
		(polygon
			(pts
				(arc
					(start 50.013108 -168.82999)
					(mid 47.5869 -168.82999)
					(end 50.013108 -168.82999)
				)
			)
		)
	)
	(zone
		(layers "In4.Cu" "In5.Cu")
		(hatch none 0.5)
		(connect_pads
			(clearance 0)
		)
		(min_thickness 0.25)
		(keepout
			(tracks not_allowed)
			(vias allowed)
			(pads allowed)
			(copperpour not_allowed)
			(footprints allowed)
		)
		(placement
			(enabled no)
			(sheetname "")
		)
		(fill yes
			(thermal_gap 0.5)
			(thermal_bridge_width 0.5)
			(island_removal_mode 0)
		)
		(polygon
			(pts
				(arc
					(start 444.86195 -51.816)
					(mid 443.08395 -51.816)
					(end 444.86195 -51.816)
				)
			)
		)
	)
	(zone
		(layers "In4.Cu" "In5.Cu")
		(hatch none 0.5)
		(connect_pads
			(clearance 0)
		)
		(min_thickness 0.25)
		(keepout
			(tracks not_allowed)
			(vias allowed)
			(pads allowed)
			(copperpour not_allowed)
			(footprints allowed)
		)
		(placement
			(enabled no)
			(sheetname "")
		)
		(fill yes
			(thermal_gap 0.5)
			(thermal_bridge_width 0.5)
			(island_removal_mode 0)
		)
		(polygon
			(pts
				(arc
					(start 56.013096 -166.829994)
					(mid 53.586888 -166.829994)
					(end 56.013096 -166.829994)
				)
			)
		)
	)
	(zone
		(layers "In4.Cu" "In5.Cu")
		(hatch none 0.5)
		(connect_pads
			(clearance 0)
		)
		(min_thickness 0.25)
		(keepout
			(tracks not_allowed)
			(vias allowed)
			(pads allowed)
			(copperpour not_allowed)
			(footprints allowed)
		)
		(placement
			(enabled no)
			(sheetname "")
		)
		(fill yes
			(thermal_gap 0.5)
			(thermal_bridge_width 0.5)
			(island_removal_mode 0)
		)
		(polygon
			(pts
				(arc
					(start 81.407 -14.732)
					(mid 79.629 -14.732)
					(end 81.407 -14.732)
				)
			)
		)
	)
	(zone
		(layers "In4.Cu" "In5.Cu")
		(hatch none 0.5)
		(connect_pads
			(clearance 0)
		)
		(min_thickness 0.25)
		(keepout
			(tracks not_allowed)
			(vias allowed)
			(pads allowed)
			(copperpour not_allowed)
			(footprints allowed)
		)
		(placement
			(enabled no)
			(sheetname "")
		)
		(fill yes
			(thermal_gap 0.5)
			(thermal_bridge_width 0.5)
			(island_removal_mode 0)
		)
		(polygon
			(pts
				(arc
					(start 63.44539 -71.239888)
					(mid 60.39739 -71.239888)
					(end 63.44539 -71.239888)
				)
			)
		)
	)
	(zone
		(layers "In4.Cu" "In5.Cu")
		(hatch none 0.5)
		(connect_pads
			(clearance 0)
		)
		(min_thickness 0.25)
		(keepout
			(tracks not_allowed)
			(vias allowed)
			(pads allowed)
			(copperpour not_allowed)
			(footprints allowed)
		)
		(placement
			(enabled no)
			(sheetname "")
		)
		(fill yes
			(thermal_gap 0.5)
			(thermal_bridge_width 0.5)
			(island_removal_mode 0)
		)
		(polygon
			(pts
				(arc
					(start 429.6664 -43.95724)
					(mid 427.8884 -43.95724)
					(end 429.6664 -43.95724)
				)
			)
		)
	)
	(zone
		(layers "In4.Cu" "In5.Cu")
		(hatch none 0.5)
		(connect_pads
			(clearance 0)
		)
		(min_thickness 0.25)
		(keepout
			(tracks not_allowed)
			(vias allowed)
			(pads allowed)
			(copperpour not_allowed)
			(footprints allowed)
		)
		(placement
			(enabled no)
			(sheetname "")
		)
		(fill yes
			(thermal_gap 0.5)
			(thermal_bridge_width 0.5)
			(island_removal_mode 0)
		)
		(polygon
			(pts
				(arc
					(start 40.83812 -160.830006)
					(mid 38.411912 -160.830006)
					(end 40.83812 -160.830006)
				)
			)
		)
	)
	(zone
		(layers "In4.Cu" "In5.Cu")
		(hatch none 0.5)
		(connect_pads
			(clearance 0)
		)
		(min_thickness 0.25)
		(keepout
			(tracks not_allowed)
			(vias allowed)
			(pads allowed)
			(copperpour not_allowed)
			(footprints allowed)
		)
		(placement
			(enabled no)
			(sheetname "")
		)
		(fill yes
			(thermal_gap 0.5)
			(thermal_bridge_width 0.5)
			(island_removal_mode 0)
		)
		(polygon
			(pts
				(arc
					(start 446.47104 -47.56404)
					(mid 444.69304 -47.56404)
					(end 446.47104 -47.56404)
				)
			)
		)
	)
	(zone
		(layers "In4.Cu" "In5.Cu")
		(hatch none 0.5)
		(connect_pads
			(clearance 0)
		)
		(min_thickness 0.25)
		(keepout
			(tracks not_allowed)
			(vias allowed)
			(pads allowed)
			(copperpour not_allowed)
			(footprints allowed)
		)
		(placement
			(enabled no)
			(sheetname "")
		)
		(fill yes
			(thermal_gap 0.5)
			(thermal_bridge_width 0.5)
			(island_removal_mode 0)
		)
		(polygon
			(pts
				(arc
					(start 345.89974 -9.878822)
					(mid 344.12174 -9.878822)
					(end 345.89974 -9.878822)
				)
			)
		)
	)
	(zone
		(layers "In4.Cu" "In5.Cu")
		(hatch none 0.5)
		(connect_pads
			(clearance 0)
		)
		(min_thickness 0.25)
		(keepout
			(tracks not_allowed)
			(vias allowed)
			(pads allowed)
			(copperpour not_allowed)
			(footprints allowed)
		)
		(placement
			(enabled no)
			(sheetname "")
		)
		(fill yes
			(thermal_gap 0.5)
			(thermal_bridge_width 0.5)
			(island_removal_mode 0)
		)
		(polygon
			(pts
				(arc
					(start 445.7954 -63.627)
					(mid 444.0174 -63.627)
					(end 445.7954 -63.627)
				)
			)
		)
	)
	(zone
		(layers "In4.Cu" "In5.Cu")
		(hatch none 0.5)
		(connect_pads
			(clearance 0)
		)
		(min_thickness 0.25)
		(keepout
			(tracks not_allowed)
			(vias allowed)
			(pads allowed)
			(copperpour not_allowed)
			(footprints allowed)
		)
		(placement
			(enabled no)
			(sheetname "")
		)
		(fill yes
			(thermal_gap 0.5)
			(thermal_bridge_width 0.5)
			(island_removal_mode 0)
		)
		(polygon
			(pts
				(arc
					(start 104.5464 -45.7454)
					(mid 102.7684 -45.7454)
					(end 104.5464 -45.7454)
				)
			)
		)
	)
	(zone
		(layers "In4.Cu" "In5.Cu")
		(hatch none 0.5)
		(connect_pads
			(clearance 0)
		)
		(min_thickness 0.25)
		(keepout
			(tracks not_allowed)
			(vias allowed)
			(pads allowed)
			(copperpour not_allowed)
			(footprints allowed)
		)
		(placement
			(enabled no)
			(sheetname "")
		)
		(fill yes
			(thermal_gap 0.5)
			(thermal_bridge_width 0.5)
			(island_removal_mode 0)
		)
		(polygon
			(pts
				(arc
					(start 450.088 -36.20135)
					(mid 448.31 -36.20135)
					(end 450.088 -36.20135)
				)
			)
		)
	)
	(zone
		(layers "In4.Cu" "In5.Cu")
		(hatch none 0.5)
		(connect_pads
			(clearance 0)
		)
		(min_thickness 0.25)
		(keepout
			(tracks not_allowed)
			(vias allowed)
			(pads allowed)
			(copperpour not_allowed)
			(footprints allowed)
		)
		(placement
			(enabled no)
			(sheetname "")
		)
		(fill yes
			(thermal_gap 0.5)
			(thermal_bridge_width 0.5)
			(island_removal_mode 0)
		)
		(polygon
			(pts
				(arc
					(start 451.231 -36.20135)
					(mid 449.453 -36.20135)
					(end 451.231 -36.20135)
				)
			)
		)
	)
	(zone
		(layers "In4.Cu" "In5.Cu")
		(hatch none 0.5)
		(connect_pads
			(clearance 0)
		)
		(min_thickness 0.25)
		(keepout
			(tracks not_allowed)
			(vias allowed)
			(pads allowed)
			(copperpour not_allowed)
			(footprints allowed)
		)
		(placement
			(enabled no)
			(sheetname "")
		)
		(fill yes
			(thermal_gap 0.5)
			(thermal_bridge_width 0.5)
			(island_removal_mode 0)
		)
		(polygon
			(pts
				(arc
					(start 78.213204 -166.829994)
					(mid 75.786996 -166.829994)
					(end 78.213204 -166.829994)
				)
			)
		)
	)
	(zone
		(layers "In4.Cu" "In5.Cu")
		(hatch none 0.5)
		(connect_pads
			(clearance 0)
		)
		(min_thickness 0.25)
		(keepout
			(tracks not_allowed)
			(vias allowed)
			(pads allowed)
			(copperpour not_allowed)
			(footprints allowed)
		)
		(placement
			(enabled no)
			(sheetname "")
		)
		(fill yes
			(thermal_gap 0.5)
			(thermal_bridge_width 0.5)
			(island_removal_mode 0)
		)
		(polygon
			(pts
				(arc
					(start 437.53405 -27.182064)
					(mid 435.75605 -27.182064)
					(end 437.53405 -27.182064)
				)
			)
		)
	)
	(zone
		(layers "In4.Cu" "In5.Cu")
		(hatch none 0.5)
		(connect_pads
			(clearance 0)
		)
		(min_thickness 0.25)
		(keepout
			(tracks not_allowed)
			(vias allowed)
			(pads allowed)
			(copperpour not_allowed)
			(footprints allowed)
		)
		(placement
			(enabled no)
			(sheetname "")
		)
		(fill yes
			(thermal_gap 0.5)
			(thermal_bridge_width 0.5)
			(island_removal_mode 0)
		)
		(polygon
			(pts
				(arc
					(start 451.358 -32.893)
					(mid 449.58 -32.893)
					(end 451.358 -32.893)
				)
			)
		)
	)
	(zone
		(layers "In4.Cu" "In5.Cu")
		(hatch none 0.5)
		(connect_pads
			(clearance 0)
		)
		(min_thickness 0.25)
		(keepout
			(tracks not_allowed)
			(vias allowed)
			(pads allowed)
			(copperpour not_allowed)
			(footprints allowed)
		)
		(placement
			(enabled no)
			(sheetname "")
		)
		(fill yes
			(thermal_gap 0.5)
			(thermal_bridge_width 0.5)
			(island_removal_mode 0)
		)
		(polygon
			(pts
				(arc
					(start 449.562728 -62.814454)
					(mid 447.784728 -62.814454)
					(end 449.562728 -62.814454)
				)
			)
		)
	)
	(zone
		(layers "In4.Cu" "In5.Cu")
		(hatch none 0.5)
		(connect_pads
			(clearance 0)
		)
		(min_thickness 0.25)
		(keepout
			(tracks not_allowed)
			(vias allowed)
			(pads allowed)
			(copperpour not_allowed)
			(footprints allowed)
		)
		(placement
			(enabled no)
			(sheetname "")
		)
		(fill yes
			(thermal_gap 0.5)
			(thermal_bridge_width 0.5)
			(island_removal_mode 0)
		)
		(polygon
			(pts
				(arc
					(start 42.838116 -152.830022)
					(mid 40.411908 -152.830022)
					(end 42.838116 -152.830022)
				)
			)
		)
	)
	(zone
		(layers "In4.Cu" "In5.Cu")
		(hatch none 0.5)
		(connect_pads
			(clearance 0)
		)
		(min_thickness 0.25)
		(keepout
			(tracks not_allowed)
			(vias allowed)
			(pads allowed)
			(copperpour not_allowed)
			(footprints allowed)
		)
		(placement
			(enabled no)
			(sheetname "")
		)
		(fill yes
			(thermal_gap 0.5)
			(thermal_bridge_width 0.5)
			(island_removal_mode 0)
		)
		(polygon
			(pts
				(arc
					(start 442.341 -31.623)
					(mid 440.563 -31.623)
					(end 442.341 -31.623)
				)
			)
		)
	)
	(zone
		(layers "In4.Cu" "In5.Cu")
		(hatch none 0.5)
		(connect_pads
			(clearance 0)
		)
		(min_thickness 0.25)
		(keepout
			(tracks not_allowed)
			(vias allowed)
			(pads allowed)
			(copperpour not_allowed)
			(footprints allowed)
		)
		(placement
			(enabled no)
			(sheetname "")
		)
		(fill yes
			(thermal_gap 0.5)
			(thermal_bridge_width 0.5)
			(island_removal_mode 0)
		)
		(polygon
			(pts
				(arc
					(start 404.338282 -162.830002)
					(mid 401.912074 -162.830002)
					(end 404.338282 -162.830002)
				)
			)
		)
	)
	(zone
		(layers "In4.Cu" "In5.Cu")
		(hatch none 0.5)
		(connect_pads
			(clearance 0)
		)
		(min_thickness 0.25)
		(keepout
			(tracks not_allowed)
			(vias allowed)
			(pads allowed)
			(copperpour not_allowed)
			(footprints allowed)
		)
		(placement
			(enabled no)
			(sheetname "")
		)
		(fill yes
			(thermal_gap 0.5)
			(thermal_bridge_width 0.5)
			(island_removal_mode 0)
		)
		(polygon
			(pts
				(arc
					(start 334.483964 -9.774428)
					(mid 332.705964 -9.774428)
					(end 334.483964 -9.774428)
				)
			)
		)
	)
	(zone
		(layers "In4.Cu" "In5.Cu")
		(hatch none 0.5)
		(connect_pads
			(clearance 0)
		)
		(min_thickness 0.25)
		(keepout
			(tracks not_allowed)
			(vias allowed)
			(pads allowed)
			(copperpour not_allowed)
			(footprints allowed)
		)
		(placement
			(enabled no)
			(sheetname "")
		)
		(fill yes
			(thermal_gap 0.5)
			(thermal_bridge_width 0.5)
			(island_removal_mode 0)
		)
		(polygon
			(pts
				(arc
					(start 406.5524 -32.004)
					(mid 404.7744 -32.004)
					(end 406.5524 -32.004)
				)
			)
		)
	)
	(zone
		(layers "In4.Cu" "In5.Cu")
		(hatch none 0.5)
		(connect_pads
			(clearance 0)
		)
		(min_thickness 0.25)
		(keepout
			(tracks not_allowed)
			(vias allowed)
			(pads allowed)
			(copperpour not_allowed)
			(footprints allowed)
		)
		(placement
			(enabled no)
			(sheetname "")
		)
		(fill yes
			(thermal_gap 0.5)
			(thermal_bridge_width 0.5)
			(island_removal_mode 0)
		)
		(polygon
			(pts
				(arc
					(start 96.187768 -9.757918)
					(mid 94.409768 -9.757918)
					(end 96.187768 -9.757918)
				)
			)
		)
	)
	(zone
		(layers "In4.Cu" "In5.Cu")
		(hatch none 0.5)
		(connect_pads
			(clearance 0)
		)
		(min_thickness 0.25)
		(keepout
			(tracks not_allowed)
			(vias allowed)
			(pads allowed)
			(copperpour not_allowed)
			(footprints allowed)
		)
		(placement
			(enabled no)
			(sheetname "")
		)
		(fill yes
			(thermal_gap 0.5)
			(thermal_bridge_width 0.5)
			(island_removal_mode 0)
		)
		(polygon
			(pts
				(arc
					(start 408.8384 -15.875)
					(mid 407.0604 -15.875)
					(end 408.8384 -15.875)
				)
			)
		)
	)
	(zone
		(layers "In4.Cu" "In5.Cu")
		(hatch none 0.5)
		(connect_pads
			(clearance 0)
		)
		(min_thickness 0.25)
		(keepout
			(tracks not_allowed)
			(vias allowed)
			(pads allowed)
			(copperpour not_allowed)
			(footprints allowed)
		)
		(placement
			(enabled no)
			(sheetname "")
		)
		(fill yes
			(thermal_gap 0.5)
			(thermal_bridge_width 0.5)
			(island_removal_mode 0)
		)
		(polygon
			(pts
				(arc
					(start 440.159394 -36.489894)
					(mid 438.381394 -36.489894)
					(end 440.159394 -36.489894)
				)
			)
		)
	)
	(zone
		(layers "In4.Cu" "In5.Cu")
		(hatch none 0.5)
		(connect_pads
			(clearance 0)
		)
		(min_thickness 0.25)
		(keepout
			(tracks not_allowed)
			(vias allowed)
			(pads allowed)
			(copperpour not_allowed)
			(footprints allowed)
		)
		(placement
			(enabled no)
			(sheetname "")
		)
		(fill yes
			(thermal_gap 0.5)
			(thermal_bridge_width 0.5)
			(island_removal_mode 0)
		)
		(polygon
			(pts
				(arc
					(start 56.013096 -168.82999)
					(mid 53.586888 -168.82999)
					(end 56.013096 -168.82999)
				)
			)
		)
	)
	(zone
		(layers "In4.Cu" "In5.Cu")
		(hatch none 0.5)
		(connect_pads
			(clearance 0)
		)
		(min_thickness 0.25)
		(keepout
			(tracks not_allowed)
			(vias allowed)
			(pads allowed)
			(copperpour not_allowed)
			(footprints allowed)
		)
		(placement
			(enabled no)
			(sheetname "")
		)
		(fill yes
			(thermal_gap 0.5)
			(thermal_bridge_width 0.5)
			(island_removal_mode 0)
		)
		(polygon
			(pts
				(arc
					(start 379.095254 -139.7)
					(mid 377.062746 -139.7)
					(end 379.095254 -139.7)
				)
			)
		)
	)
	(zone
		(layers "In4.Cu" "In5.Cu")
		(hatch none 0.5)
		(connect_pads
			(clearance 0)
		)
		(min_thickness 0.25)
		(keepout
			(tracks not_allowed)
			(vias allowed)
			(pads allowed)
			(copperpour not_allowed)
			(footprints allowed)
		)
		(placement
			(enabled no)
			(sheetname "")
		)
		(fill yes
			(thermal_gap 0.5)
			(thermal_bridge_width 0.5)
			(island_removal_mode 0)
		)
		(polygon
			(pts
				(arc
					(start 460.5274 -49.53)
					(mid 458.7494 -49.53)
					(end 460.5274 -49.53)
				)
			)
		)
	)
	(zone
		(layers "In4.Cu" "In5.Cu")
		(hatch none 0.5)
		(connect_pads
			(clearance 0)
		)
		(min_thickness 0.25)
		(keepout
			(tracks not_allowed)
			(vias allowed)
			(pads allowed)
			(copperpour not_allowed)
			(footprints allowed)
		)
		(placement
			(enabled no)
			(sheetname "")
		)
		(fill yes
			(thermal_gap 0.5)
			(thermal_bridge_width 0.5)
			(island_removal_mode 0)
		)
		(polygon
			(pts
				(arc
					(start 408.8384 -17.653)
					(mid 407.0604 -17.653)
					(end 408.8384 -17.653)
				)
			)
		)
	)
	(zone
		(layers "In4.Cu" "In5.Cu")
		(hatch none 0.5)
		(connect_pads
			(clearance 0)
		)
		(min_thickness 0.25)
		(keepout
			(tracks not_allowed)
			(vias allowed)
			(pads allowed)
			(copperpour not_allowed)
			(footprints allowed)
		)
		(placement
			(enabled no)
			(sheetname "")
		)
		(fill yes
			(thermal_gap 0.5)
			(thermal_bridge_width 0.5)
			(island_removal_mode 0)
		)
		(polygon
			(pts
				(arc
					(start 418.855398 -26.450036)
					(mid 417.077398 -26.450036)
					(end 418.855398 -26.450036)
				)
			)
		)
	)
	(zone
		(layers "In4.Cu" "In5.Cu")
		(hatch none 0.5)
		(connect_pads
			(clearance 0)
		)
		(min_thickness 0.25)
		(keepout
			(tracks not_allowed)
			(vias allowed)
			(pads allowed)
			(copperpour not_allowed)
			(footprints allowed)
		)
		(placement
			(enabled no)
			(sheetname "")
		)
		(fill yes
			(thermal_gap 0.5)
			(thermal_bridge_width 0.5)
			(island_removal_mode 0)
		)
		(polygon
			(pts
				(arc
					(start 425.7802 -30.5816)
					(mid 424.0022 -30.5816)
					(end 425.7802 -30.5816)
				)
			)
		)
	)
	(zone
		(layers "In4.Cu" "In5.Cu")
		(hatch none 0.5)
		(connect_pads
			(clearance 0)
		)
		(min_thickness 0.25)
		(keepout
			(tracks not_allowed)
			(vias allowed)
			(pads allowed)
			(copperpour not_allowed)
			(footprints allowed)
		)
		(placement
			(enabled no)
			(sheetname "")
		)
		(fill yes
			(thermal_gap 0.5)
			(thermal_bridge_width 0.5)
			(island_removal_mode 0)
		)
		(polygon
			(pts
				(arc
					(start 430.8094 -34.53765)
					(mid 429.0314 -34.53765)
					(end 430.8094 -34.53765)
				)
			)
		)
	)
	(zone
		(layers "In4.Cu" "In5.Cu")
		(hatch none 0.5)
		(connect_pads
			(clearance 0)
		)
		(min_thickness 0.25)
		(keepout
			(tracks not_allowed)
			(vias allowed)
			(pads allowed)
			(copperpour not_allowed)
			(footprints allowed)
		)
		(placement
			(enabled no)
			(sheetname "")
		)
		(fill yes
			(thermal_gap 0.5)
			(thermal_bridge_width 0.5)
			(island_removal_mode 0)
		)
		(polygon
			(pts
				(arc
					(start 429.6664 -41.16324)
					(mid 427.8884 -41.16324)
					(end 429.6664 -41.16324)
				)
			)
		)
	)
	(zone
		(layers "In4.Cu" "In5.Cu")
		(hatch none 0.5)
		(connect_pads
			(clearance 0)
		)
		(min_thickness 0.25)
		(keepout
			(tracks not_allowed)
			(vias allowed)
			(pads allowed)
			(copperpour not_allowed)
			(footprints allowed)
		)
		(placement
			(enabled no)
			(sheetname "")
		)
		(fill yes
			(thermal_gap 0.5)
			(thermal_bridge_width 0.5)
			(island_removal_mode 0)
		)
		(polygon
			(pts
				(arc
					(start 447.8274 -29.083)
					(mid 446.0494 -29.083)
					(end 447.8274 -29.083)
				)
			)
		)
	)
	(zone
		(layers "In4.Cu" "In5.Cu")
		(hatch none 0.5)
		(connect_pads
			(clearance 0)
		)
		(min_thickness 0.25)
		(keepout
			(tracks not_allowed)
			(vias allowed)
			(pads allowed)
			(copperpour not_allowed)
			(footprints allowed)
		)
		(placement
			(enabled no)
			(sheetname "")
		)
		(fill yes
			(thermal_gap 0.5)
			(thermal_bridge_width 0.5)
			(island_removal_mode 0)
		)
		(polygon
			(pts
				(arc
					(start 439.5978 -26.543)
					(mid 437.8198 -26.543)
					(end 439.5978 -26.543)
				)
			)
		)
	)
	(zone
		(layers "In4.Cu" "In5.Cu")
		(hatch none 0.5)
		(connect_pads
			(clearance 0)
		)
		(min_thickness 0.25)
		(keepout
			(tracks not_allowed)
			(vias allowed)
			(pads allowed)
			(copperpour not_allowed)
			(footprints allowed)
		)
		(placement
			(enabled no)
			(sheetname "")
		)
		(fill yes
			(thermal_gap 0.5)
			(thermal_bridge_width 0.5)
			(island_removal_mode 0)
		)
		(polygon
			(pts
				(arc
					(start 419.4302 -20.3708)
					(mid 417.6522 -20.3708)
					(end 419.4302 -20.3708)
				)
			)
		)
	)
	(zone
		(layers "In4.Cu" "In5.Cu")
		(hatch none 0.5)
		(connect_pads
			(clearance 0)
		)
		(min_thickness 0.25)
		(keepout
			(tracks not_allowed)
			(vias allowed)
			(pads allowed)
			(copperpour not_allowed)
			(footprints allowed)
		)
		(placement
			(enabled no)
			(sheetname "")
		)
		(fill yes
			(thermal_gap 0.5)
			(thermal_bridge_width 0.5)
			(island_removal_mode 0)
		)
		(polygon
			(pts
				(arc
					(start 441.198 -44.13504)
					(mid 439.42 -44.13504)
					(end 441.198 -44.13504)
				)
			)
		)
	)
	(zone
		(layers "In4.Cu" "In5.Cu")
		(hatch none 0.5)
		(connect_pads
			(clearance 0)
		)
		(min_thickness 0.25)
		(keepout
			(tracks not_allowed)
			(vias allowed)
			(pads allowed)
			(copperpour not_allowed)
			(footprints allowed)
		)
		(placement
			(enabled no)
			(sheetname "")
		)
		(fill yes
			(thermal_gap 0.5)
			(thermal_bridge_width 0.5)
			(island_removal_mode 0)
		)
		(polygon
			(pts
				(arc
					(start 379.074172 -28.136342)
					(mid 377.296172 -28.136342)
					(end 379.074172 -28.136342)
				)
			)
		)
	)
	(zone
		(layers "In4.Cu" "In5.Cu")
		(hatch none 0.5)
		(connect_pads
			(clearance 0)
		)
		(min_thickness 0.25)
		(keepout
			(tracks not_allowed)
			(vias allowed)
			(pads allowed)
			(copperpour not_allowed)
			(footprints allowed)
		)
		(placement
			(enabled no)
			(sheetname "")
		)
		(fill yes
			(thermal_gap 0.5)
			(thermal_bridge_width 0.5)
			(island_removal_mode 0)
		)
		(polygon
			(pts
				(arc
					(start 375.913142 -2.035048)
					(mid 373.486934 -2.035048)
					(end 375.913142 -2.035048)
				)
			)
		)
	)
	(zone
		(layers "In4.Cu" "In5.Cu")
		(hatch none 0.5)
		(connect_pads
			(clearance 0)
		)
		(min_thickness 0.25)
		(keepout
			(tracks not_allowed)
			(vias allowed)
			(pads allowed)
			(copperpour not_allowed)
			(footprints allowed)
		)
		(placement
			(enabled no)
			(sheetname "")
		)
		(fill yes
			(thermal_gap 0.5)
			(thermal_bridge_width 0.5)
			(island_removal_mode 0)
		)
		(polygon
			(pts
				(arc
					(start 424.58005 -48.133)
					(mid 422.80205 -48.133)
					(end 424.58005 -48.133)
				)
			)
		)
	)
	(zone
		(layers "In4.Cu" "In5.Cu")
		(hatch none 0.5)
		(connect_pads
			(clearance 0)
		)
		(min_thickness 0.25)
		(keepout
			(tracks not_allowed)
			(vias allowed)
			(pads allowed)
			(copperpour not_allowed)
			(footprints allowed)
		)
		(placement
			(enabled no)
			(sheetname "")
		)
		(fill yes
			(thermal_gap 0.5)
			(thermal_bridge_width 0.5)
			(island_removal_mode 0)
		)
		(polygon
			(pts
				(arc
					(start 452.501 -48.133)
					(mid 450.723 -48.133)
					(end 452.501 -48.133)
				)
			)
		)
	)
	(zone
		(layers "In4.Cu" "In5.Cu")
		(hatch none 0.5)
		(connect_pads
			(clearance 0)
		)
		(min_thickness 0.25)
		(keepout
			(tracks not_allowed)
			(vias allowed)
			(pads allowed)
			(copperpour not_allowed)
			(footprints allowed)
		)
		(placement
			(enabled no)
			(sheetname "")
		)
		(fill yes
			(thermal_gap 0.5)
			(thermal_bridge_width 0.5)
			(island_removal_mode 0)
		)
		(polygon
			(pts
				(arc
					(start 434.3654 -47.371)
					(mid 432.5874 -47.371)
					(end 434.3654 -47.371)
				)
			)
		)
	)
	(zone
		(layers "In4.Cu" "In5.Cu")
		(hatch none 0.5)
		(connect_pads
			(clearance 0)
		)
		(min_thickness 0.25)
		(keepout
			(tracks not_allowed)
			(vias allowed)
			(pads allowed)
			(copperpour not_allowed)
			(footprints allowed)
		)
		(placement
			(enabled no)
			(sheetname "")
		)
		(fill yes
			(thermal_gap 0.5)
			(thermal_bridge_width 0.5)
			(island_removal_mode 0)
		)
		(polygon
			(pts
				(arc
					(start 364.21314 -164.829998)
					(mid 361.786932 -164.829998)
					(end 364.21314 -164.829998)
				)
			)
		)
	)
	(zone
		(layers "In4.Cu" "In5.Cu")
		(hatch none 0.5)
		(connect_pads
			(clearance 0)
		)
		(min_thickness 0.25)
		(keepout
			(tracks not_allowed)
			(vias allowed)
			(pads allowed)
			(copperpour not_allowed)
			(footprints allowed)
		)
		(placement
			(enabled no)
			(sheetname "")
		)
		(fill yes
			(thermal_gap 0.5)
			(thermal_bridge_width 0.5)
			(island_removal_mode 0)
		)
		(polygon
			(pts
				(arc
					(start 390.412986 -164.829998)
					(mid 387.986778 -164.829998)
					(end 390.412986 -164.829998)
				)
			)
		)
	)
	(zone
		(layers "In4.Cu" "In5.Cu")
		(hatch none 0.5)
		(connect_pads
			(clearance 0)
		)
		(min_thickness 0.25)
		(keepout
			(tracks not_allowed)
			(vias allowed)
			(pads allowed)
			(copperpour not_allowed)
			(footprints allowed)
		)
		(placement
			(enabled no)
			(sheetname "")
		)
		(fill yes
			(thermal_gap 0.5)
			(thermal_bridge_width 0.5)
			(island_removal_mode 0)
		)
		(polygon
			(pts
				(arc
					(start 425.5897 -46.1137)
					(mid 423.8117 -46.1137)
					(end 425.5897 -46.1137)
				)
			)
		)
	)
	(zone
		(layers "In4.Cu" "In5.Cu")
		(hatch none 0.5)
		(connect_pads
			(clearance 0)
		)
		(min_thickness 0.25)
		(keepout
			(tracks not_allowed)
			(vias allowed)
			(pads allowed)
			(copperpour not_allowed)
			(footprints allowed)
		)
		(placement
			(enabled no)
			(sheetname "")
		)
		(fill yes
			(thermal_gap 0.5)
			(thermal_bridge_width 0.5)
			(island_removal_mode 0)
		)
		(polygon
			(pts
				(arc
					(start 360.63174 -10.282174)
					(mid 358.85374 -10.282174)
					(end 360.63174 -10.282174)
				)
			)
		)
	)
	(zone
		(layers "In4.Cu" "In5.Cu")
		(hatch none 0.5)
		(connect_pads
			(clearance 0)
		)
		(min_thickness 0.25)
		(keepout
			(tracks not_allowed)
			(vias allowed)
			(pads allowed)
			(copperpour not_allowed)
			(footprints allowed)
		)
		(placement
			(enabled no)
			(sheetname "")
		)
		(fill yes
			(thermal_gap 0.5)
			(thermal_bridge_width 0.5)
			(island_removal_mode 0)
		)
		(polygon
			(pts
				(arc
					(start 392.412982 -168.82999)
					(mid 389.986774 -168.82999)
					(end 392.412982 -168.82999)
				)
			)
		)
	)
	(zone
		(layers "In4.Cu" "In5.Cu")
		(hatch none 0.5)
		(connect_pads
			(clearance 0)
		)
		(min_thickness 0.25)
		(keepout
			(tracks not_allowed)
			(vias allowed)
			(pads allowed)
			(copperpour not_allowed)
			(footprints allowed)
		)
		(placement
			(enabled no)
			(sheetname "")
		)
		(fill yes
			(thermal_gap 0.5)
			(thermal_bridge_width 0.5)
			(island_removal_mode 0)
		)
		(polygon
			(pts
				(arc
					(start 414.655 -44.45)
					(mid 412.877 -44.45)
					(end 414.655 -44.45)
				)
			)
		)
	)
	(zone
		(layers "In4.Cu" "In5.Cu")
		(hatch none 0.5)
		(connect_pads
			(clearance 0)
		)
		(min_thickness 0.25)
		(keepout
			(tracks not_allowed)
			(vias allowed)
			(pads allowed)
			(copperpour not_allowed)
			(footprints allowed)
		)
		(placement
			(enabled no)
			(sheetname "")
		)
		(fill yes
			(thermal_gap 0.5)
			(thermal_bridge_width 0.5)
			(island_removal_mode 0)
		)
		(polygon
			(pts
				(arc
					(start 418.697918 -31.643574)
					(mid 416.919918 -31.643574)
					(end 418.697918 -31.643574)
				)
			)
		)
	)
	(zone
		(layers "In4.Cu" "In5.Cu")
		(hatch none 0.5)
		(connect_pads
			(clearance 0)
		)
		(min_thickness 0.25)
		(keepout
			(tracks not_allowed)
			(vias allowed)
			(pads allowed)
			(copperpour not_allowed)
			(footprints allowed)
		)
		(placement
			(enabled no)
			(sheetname "")
		)
		(fill yes
			(thermal_gap 0.5)
			(thermal_bridge_width 0.5)
			(island_removal_mode 0)
		)
		(polygon
			(pts
				(arc
					(start 432.174904 -40.386)
					(mid 430.396904 -40.386)
					(end 432.174904 -40.386)
				)
			)
		)
	)
	(zone
		(layers "In4.Cu" "In5.Cu")
		(hatch none 0.5)
		(connect_pads
			(clearance 0)
		)
		(min_thickness 0.25)
		(keepout
			(tracks not_allowed)
			(vias allowed)
			(pads allowed)
			(copperpour not_allowed)
			(footprints allowed)
		)
		(placement
			(enabled no)
			(sheetname "")
		)
		(fill yes
			(thermal_gap 0.5)
			(thermal_bridge_width 0.5)
			(island_removal_mode 0)
		)
		(polygon
			(pts
				(arc
					(start 366.213136 -166.829994)
					(mid 363.786928 -166.829994)
					(end 366.213136 -166.829994)
				)
			)
		)
	)
	(zone
		(layers "In4.Cu" "In5.Cu")
		(hatch none 0.5)
		(connect_pads
			(clearance 0)
		)
		(min_thickness 0.25)
		(keepout
			(tracks not_allowed)
			(vias allowed)
			(pads allowed)
			(copperpour not_allowed)
			(footprints allowed)
		)
		(placement
			(enabled no)
			(sheetname "")
		)
		(fill yes
			(thermal_gap 0.5)
			(thermal_bridge_width 0.5)
			(island_removal_mode 0)
		)
		(polygon
			(pts
				(arc
					(start 52.013104 -168.82999)
					(mid 49.586896 -168.82999)
					(end 52.013104 -168.82999)
				)
			)
		)
	)
	(zone
		(layers "In4.Cu" "In5.Cu")
		(hatch none 0.5)
		(connect_pads
			(clearance 0)
		)
		(min_thickness 0.25)
		(keepout
			(tracks not_allowed)
			(vias allowed)
			(pads allowed)
			(copperpour not_allowed)
			(footprints allowed)
		)
		(placement
			(enabled no)
			(sheetname "")
		)
		(fill yes
			(thermal_gap 0.5)
			(thermal_bridge_width 0.5)
			(island_removal_mode 0)
		)
		(polygon
			(pts
				(arc
					(start 404.338282 -166.829994)
					(mid 401.912074 -166.829994)
					(end 404.338282 -166.829994)
				)
			)
		)
	)
	(zone
		(layers "In4.Cu" "In5.Cu")
		(hatch none 0.5)
		(connect_pads
			(clearance 0)
		)
		(min_thickness 0.25)
		(keepout
			(tracks not_allowed)
			(vias allowed)
			(pads allowed)
			(copperpour not_allowed)
			(footprints allowed)
		)
		(placement
			(enabled no)
			(sheetname "")
		)
		(fill yes
			(thermal_gap 0.5)
			(thermal_bridge_width 0.5)
			(island_removal_mode 0)
		)
		(polygon
			(pts
				(arc
					(start 413.893 -42.545)
					(mid 412.115 -42.545)
					(end 413.893 -42.545)
				)
			)
		)
	)
	(zone
		(layers "In4.Cu" "In5.Cu")
		(hatch none 0.5)
		(connect_pads
			(clearance 0)
		)
		(min_thickness 0.25)
		(keepout
			(tracks not_allowed)
			(vias allowed)
			(pads allowed)
			(copperpour not_allowed)
			(footprints allowed)
		)
		(placement
			(enabled no)
			(sheetname "")
		)
		(fill yes
			(thermal_gap 0.5)
			(thermal_bridge_width 0.5)
			(island_removal_mode 0)
		)
		(polygon
			(pts
				(arc
					(start 407.8224 -20.828)
					(mid 406.0444 -20.828)
					(end 407.8224 -20.828)
				)
			)
		)
	)
	(zone
		(layers "In4.Cu" "In5.Cu")
		(hatch none 0.5)
		(connect_pads
			(clearance 0)
		)
		(min_thickness 0.25)
		(keepout
			(tracks not_allowed)
			(vias allowed)
			(pads allowed)
			(copperpour not_allowed)
			(footprints allowed)
		)
		(placement
			(enabled no)
			(sheetname "")
		)
		(fill yes
			(thermal_gap 0.5)
			(thermal_bridge_width 0.5)
			(island_removal_mode 0)
		)
		(polygon
			(pts
				(arc
					(start 429.126904 -40.386)
					(mid 427.348904 -40.386)
					(end 429.126904 -40.386)
				)
			)
		)
	)
	(zone
		(layers "In4.Cu" "In5.Cu")
		(hatch none 0.5)
		(connect_pads
			(clearance 0)
		)
		(min_thickness 0.25)
		(keepout
			(tracks not_allowed)
			(vias allowed)
			(pads allowed)
			(copperpour not_allowed)
			(footprints allowed)
		)
		(placement
			(enabled no)
			(sheetname "")
		)
		(fill yes
			(thermal_gap 0.5)
			(thermal_bridge_width 0.5)
			(island_removal_mode 0)
		)
		(polygon
			(pts
				(arc
					(start 398.653254 -119.38)
					(mid 396.620746 -119.38)
					(end 398.653254 -119.38)
				)
			)
		)
	)
	(zone
		(layers "In4.Cu" "In5.Cu")
		(hatch none 0.5)
		(connect_pads
			(clearance 0)
		)
		(min_thickness 0.25)
		(keepout
			(tracks not_allowed)
			(vias allowed)
			(pads allowed)
			(copperpour not_allowed)
			(footprints allowed)
		)
		(placement
			(enabled no)
			(sheetname "")
		)
		(fill yes
			(thermal_gap 0.5)
			(thermal_bridge_width 0.5)
			(island_removal_mode 0)
		)
		(polygon
			(pts
				(arc
					(start 406.338278 -154.830018)
					(mid 403.91207 -154.830018)
					(end 406.338278 -154.830018)
				)
			)
		)
	)
	(zone
		(layers "In4.Cu" "In5.Cu")
		(hatch none 0.5)
		(connect_pads
			(clearance 0)
		)
		(min_thickness 0.25)
		(keepout
			(tracks not_allowed)
			(vias allowed)
			(pads allowed)
			(copperpour not_allowed)
			(footprints allowed)
		)
		(placement
			(enabled no)
			(sheetname "")
		)
		(fill yes
			(thermal_gap 0.5)
			(thermal_bridge_width 0.5)
			(island_removal_mode 0)
		)
		(polygon
			(pts
				(arc
					(start 362.15574 -10.282174)
					(mid 360.37774 -10.282174)
					(end 362.15574 -10.282174)
				)
			)
		)
	)
	(zone
		(layers "In4.Cu" "In5.Cu")
		(hatch none 0.5)
		(connect_pads
			(clearance 0)
		)
		(min_thickness 0.25)
		(keepout
			(tracks not_allowed)
			(vias allowed)
			(pads allowed)
			(copperpour not_allowed)
			(footprints allowed)
		)
		(placement
			(enabled no)
			(sheetname "")
		)
		(fill yes
			(thermal_gap 0.5)
			(thermal_bridge_width 0.5)
			(island_removal_mode 0)
		)
		(polygon
			(pts
				(arc
					(start 404.338282 -168.82999)
					(mid 401.912074 -168.82999)
					(end 404.338282 -168.82999)
				)
			)
		)
	)
	(zone
		(layers "In4.Cu" "In5.Cu")
		(hatch none 0.5)
		(connect_pads
			(clearance 0)
		)
		(min_thickness 0.25)
		(keepout
			(tracks not_allowed)
			(vias allowed)
			(pads allowed)
			(copperpour not_allowed)
			(footprints allowed)
		)
		(placement
			(enabled no)
			(sheetname "")
		)
		(fill yes
			(thermal_gap 0.5)
			(thermal_bridge_width 0.5)
			(island_removal_mode 0)
		)
		(polygon
			(pts
				(arc
					(start 40.83812 -158.83001)
					(mid 38.411912 -158.83001)
					(end 40.83812 -158.83001)
				)
			)
		)
	)
	(zone
		(layers "In4.Cu" "In5.Cu")
		(hatch none 0.5)
		(connect_pads
			(clearance 0)
		)
		(min_thickness 0.25)
		(keepout
			(tracks not_allowed)
			(vias allowed)
			(pads allowed)
			(copperpour not_allowed)
			(footprints allowed)
		)
		(placement
			(enabled no)
			(sheetname "")
		)
		(fill yes
			(thermal_gap 0.5)
			(thermal_bridge_width 0.5)
			(island_removal_mode 0)
		)
		(polygon
			(pts
				(arc
					(start 380.549912 -16.891)
					(mid 378.771912 -16.891)
					(end 380.549912 -16.891)
				)
			)
		)
	)
	(zone
		(layers "In4.Cu" "In5.Cu")
		(hatch none 0.5)
		(connect_pads
			(clearance 0)
		)
		(min_thickness 0.25)
		(keepout
			(tracks not_allowed)
			(vias allowed)
			(pads allowed)
			(copperpour not_allowed)
			(footprints allowed)
		)
		(placement
			(enabled no)
			(sheetname "")
		)
		(fill yes
			(thermal_gap 0.5)
			(thermal_bridge_width 0.5)
			(island_removal_mode 0)
		)
		(polygon
			(pts
				(arc
					(start 406.338278 -162.830002)
					(mid 403.91207 -162.830002)
					(end 406.338278 -162.830002)
				)
			)
		)
	)
	(zone
		(layers "In4.Cu" "In5.Cu")
		(hatch none 0.5)
		(connect_pads
			(clearance 0)
		)
		(min_thickness 0.25)
		(keepout
			(tracks not_allowed)
			(vias allowed)
			(pads allowed)
			(copperpour not_allowed)
			(footprints allowed)
		)
		(placement
			(enabled no)
			(sheetname "")
		)
		(fill yes
			(thermal_gap 0.5)
			(thermal_bridge_width 0.5)
			(island_removal_mode 0)
		)
		(polygon
			(pts
				(arc
					(start 439.92165 -44.45)
					(mid 438.14365 -44.45)
					(end 439.92165 -44.45)
				)
			)
		)
	)
	(zone
		(layers "In4.Cu" "In5.Cu")
		(hatch none 0.5)
		(connect_pads
			(clearance 0)
		)
		(min_thickness 0.25)
		(keepout
			(tracks not_allowed)
			(vias allowed)
			(pads allowed)
			(copperpour not_allowed)
			(footprints allowed)
		)
		(placement
			(enabled no)
			(sheetname "")
		)
		(fill yes
			(thermal_gap 0.5)
			(thermal_bridge_width 0.5)
			(island_removal_mode 0)
		)
		(polygon
			(pts
				(arc
					(start 428.9044 -32.385)
					(mid 427.1264 -32.385)
					(end 428.9044 -32.385)
				)
			)
		)
	)
	(zone
		(layers "In4.Cu" "In5.Cu")
		(hatch none 0.5)
		(connect_pads
			(clearance 0)
		)
		(min_thickness 0.25)
		(keepout
			(tracks not_allowed)
			(vias allowed)
			(pads allowed)
			(copperpour not_allowed)
			(footprints allowed)
		)
		(placement
			(enabled no)
			(sheetname "")
		)
		(fill yes
			(thermal_gap 0.5)
			(thermal_bridge_width 0.5)
			(island_removal_mode 0)
		)
		(polygon
			(pts
				(arc
					(start 94.663768 -9.757918)
					(mid 92.885768 -9.757918)
					(end 94.663768 -9.757918)
				)
			)
		)
	)
	(zone
		(layers "In4.Cu" "In5.Cu")
		(hatch none 0.5)
		(connect_pads
			(clearance 0)
		)
		(min_thickness 0.25)
		(keepout
			(tracks not_allowed)
			(vias allowed)
			(pads allowed)
			(copperpour not_allowed)
			(footprints allowed)
		)
		(placement
			(enabled no)
			(sheetname "")
		)
		(fill yes
			(thermal_gap 0.5)
			(thermal_bridge_width 0.5)
			(island_removal_mode 0)
		)
		(polygon
			(pts
				(arc
					(start 60.154566 -25.273762)
					(mid 58.376566 -25.273762)
					(end 60.154566 -25.273762)
				)
			)
		)
	)
	(zone
		(layers "In4.Cu" "In5.Cu")
		(hatch none 0.5)
		(connect_pads
			(clearance 0)
		)
		(min_thickness 0.25)
		(keepout
			(tracks not_allowed)
			(vias allowed)
			(pads allowed)
			(copperpour not_allowed)
			(footprints allowed)
		)
		(placement
			(enabled no)
			(sheetname "")
		)
		(fill yes
			(thermal_gap 0.5)
			(thermal_bridge_width 0.5)
			(island_removal_mode 0)
		)
		(polygon
			(pts
				(arc
					(start 60.154566 -26.266648)
					(mid 58.376566 -26.266648)
					(end 60.154566 -26.266648)
				)
			)
		)
	)
	(zone
		(layers "In4.Cu" "In5.Cu")
		(hatch none 0.5)
		(connect_pads
			(clearance 0)
		)
		(min_thickness 0.25)
		(keepout
			(tracks not_allowed)
			(vias allowed)
			(pads allowed)
			(copperpour not_allowed)
			(footprints allowed)
		)
		(placement
			(enabled no)
			(sheetname "")
		)
		(fill yes
			(thermal_gap 0.5)
			(thermal_bridge_width 0.5)
			(island_removal_mode 0)
		)
		(polygon
			(pts
				(arc
					(start 419.063932 -28.4353)
					(mid 417.336732 -28.4353)
					(end 419.063932 -28.4353)
				)
			)
		)
	)
	(zone
		(layers "In4.Cu" "In5.Cu")
		(hatch none 0.5)
		(connect_pads
			(clearance 0)
		)
		(min_thickness 0.25)
		(keepout
			(tracks not_allowed)
			(vias allowed)
			(pads allowed)
			(copperpour not_allowed)
			(footprints allowed)
		)
		(placement
			(enabled no)
			(sheetname "")
		)
		(fill yes
			(thermal_gap 0.5)
			(thermal_bridge_width 0.5)
			(island_removal_mode 0)
		)
		(polygon
			(pts
				(arc
					(start 43.88739 -91.559888)
					(mid 40.83939 -91.559888)
					(end 43.88739 -91.559888)
				)
			)
		)
	)
	(zone
		(layers "In4.Cu" "In5.Cu")
		(hatch none 0.5)
		(connect_pads
			(clearance 0)
		)
		(min_thickness 0.25)
		(keepout
			(tracks not_allowed)
			(vias allowed)
			(pads allowed)
			(copperpour not_allowed)
			(footprints allowed)
		)
		(placement
			(enabled no)
			(sheetname "")
		)
		(fill yes
			(thermal_gap 0.5)
			(thermal_bridge_width 0.5)
			(island_removal_mode 0)
		)
		(polygon
			(pts
				(arc
					(start 406.338278 -152.830022)
					(mid 403.91207 -152.830022)
					(end 406.338278 -152.830022)
				)
			)
		)
	)
	(zone
		(layers "In4.Cu" "In5.Cu")
		(hatch none 0.5)
		(connect_pads
			(clearance 0)
		)
		(min_thickness 0.25)
		(keepout
			(tracks not_allowed)
			(vias allowed)
			(pads allowed)
			(copperpour not_allowed)
			(footprints allowed)
		)
		(placement
			(enabled no)
			(sheetname "")
		)
		(fill yes
			(thermal_gap 0.5)
			(thermal_bridge_width 0.5)
			(island_removal_mode 0)
		)
		(polygon
			(pts
				(arc
					(start 411.3022 -20.2438)
					(mid 409.5242 -20.2438)
					(end 411.3022 -20.2438)
				)
			)
		)
	)
	(zone
		(layers "In4.Cu" "In5.Cu")
		(hatch none 0.5)
		(connect_pads
			(clearance 0)
		)
		(min_thickness 0.25)
		(keepout
			(tracks not_allowed)
			(vias allowed)
			(pads allowed)
			(copperpour not_allowed)
			(footprints allowed)
		)
		(placement
			(enabled no)
			(sheetname "")
		)
		(fill yes
			(thermal_gap 0.5)
			(thermal_bridge_width 0.5)
			(island_removal_mode 0)
		)
		(polygon
			(pts
				(arc
					(start 399.161 -50.919888)
					(mid 396.113 -50.919888)
					(end 399.161 -50.919888)
				)
			)
		)
	)
	(zone
		(layers "In4.Cu" "In5.Cu")
		(hatch none 0.5)
		(connect_pads
			(clearance 0)
		)
		(min_thickness 0.25)
		(keepout
			(tracks not_allowed)
			(vias allowed)
			(pads allowed)
			(copperpour not_allowed)
			(footprints allowed)
		)
		(placement
			(enabled no)
			(sheetname "")
		)
		(fill yes
			(thermal_gap 0.5)
			(thermal_bridge_width 0.5)
			(island_removal_mode 0)
		)
		(polygon
			(pts
				(arc
					(start 40.83812 -156.830014)
					(mid 38.411912 -156.830014)
					(end 40.83812 -156.830014)
				)
			)
		)
	)
	(zone
		(layers "In4.Cu" "In5.Cu")
		(hatch none 0.5)
		(connect_pads
			(clearance 0)
		)
		(min_thickness 0.25)
		(keepout
			(tracks not_allowed)
			(vias allowed)
			(pads allowed)
			(copperpour not_allowed)
			(footprints allowed)
		)
		(placement
			(enabled no)
			(sheetname "")
		)
		(fill yes
			(thermal_gap 0.5)
			(thermal_bridge_width 0.5)
			(island_removal_mode 0)
		)
		(polygon
			(pts
				(arc
					(start 442.52896 -48.641)
					(mid 440.75096 -48.641)
					(end 442.52896 -48.641)
				)
			)
		)
	)
	(zone
		(layers "In4.Cu" "In5.Cu")
		(hatch none 0.5)
		(connect_pads
			(clearance 0)
		)
		(min_thickness 0.25)
		(keepout
			(tracks not_allowed)
			(vias allowed)
			(pads allowed)
			(copperpour not_allowed)
			(footprints allowed)
		)
		(placement
			(enabled no)
			(sheetname "")
		)
		(fill yes
			(thermal_gap 0.5)
			(thermal_bridge_width 0.5)
			(island_removal_mode 0)
		)
		(polygon
			(pts
				(arc
					(start 43.88739 -50.919888)
					(mid 40.83939 -50.919888)
					(end 43.88739 -50.919888)
				)
			)
		)
	)
	(zone
		(layers "In4.Cu" "In5.Cu")
		(hatch none 0.5)
		(connect_pads
			(clearance 0)
		)
		(min_thickness 0.25)
		(keepout
			(tracks not_allowed)
			(vias allowed)
			(pads allowed)
			(copperpour not_allowed)
			(footprints allowed)
		)
		(placement
			(enabled no)
			(sheetname "")
		)
		(fill yes
			(thermal_gap 0.5)
			(thermal_bridge_width 0.5)
			(island_removal_mode 0)
		)
		(polygon
			(pts
				(arc
					(start 432.174904 -41.783)
					(mid 430.396904 -41.783)
					(end 432.174904 -41.783)
				)
			)
		)
	)
	(zone
		(layers "In4.Cu" "In5.Cu")
		(hatch none 0.5)
		(connect_pads
			(clearance 0)
		)
		(min_thickness 0.25)
		(keepout
			(tracks not_allowed)
			(vias allowed)
			(pads allowed)
			(copperpour not_allowed)
			(footprints allowed)
		)
		(placement
			(enabled no)
			(sheetname "")
		)
		(fill yes
			(thermal_gap 0.5)
			(thermal_bridge_width 0.5)
			(island_removal_mode 0)
		)
		(polygon
			(pts
				(arc
					(start 65.865248 -18.499836)
					(mid 71.000366 -23.634954)
					(end 76.13523 -18.499836)
				)
				(arc
					(start 76.13523 -13.499846)
					(mid 71.000366 -8.364982)
					(end 65.865248 -13.499846)
				)
			)
		)
	)
	(zone
		(layers "In4.Cu" "In5.Cu")
		(hatch none 0.5)
		(connect_pads
			(clearance 0)
		)
		(min_thickness 0.25)
		(keepout
			(tracks not_allowed)
			(vias allowed)
			(pads allowed)
			(copperpour not_allowed)
			(footprints allowed)
		)
		(placement
			(enabled no)
			(sheetname "")
		)
		(fill yes
			(thermal_gap 0.5)
			(thermal_bridge_width 0.5)
			(island_removal_mode 0)
		)
		(polygon
			(pts
				(arc
					(start 451.231 -40.132)
					(mid 449.453 -40.132)
					(end 451.231 -40.132)
				)
			)
		)
	)
	(zone
		(layers "In4.Cu" "In5.Cu")
		(hatch none 0.5)
		(connect_pads
			(clearance 0)
		)
		(min_thickness 0.25)
		(keepout
			(tracks not_allowed)
			(vias allowed)
			(pads allowed)
			(copperpour not_allowed)
			(footprints allowed)
		)
		(placement
			(enabled no)
			(sheetname "")
		)
		(fill yes
			(thermal_gap 0.5)
			(thermal_bridge_width 0.5)
			(island_removal_mode 0)
		)
		(polygon
			(pts
				(arc
					(start 43.88739 -111.879888)
					(mid 40.83939 -111.879888)
					(end 43.88739 -111.879888)
				)
			)
		)
	)
	(zone
		(layers "In4.Cu" "In5.Cu")
		(hatch none 0.5)
		(connect_pads
			(clearance 0)
		)
		(min_thickness 0.25)
		(keepout
			(tracks not_allowed)
			(vias allowed)
			(pads allowed)
			(copperpour not_allowed)
			(footprints allowed)
		)
		(placement
			(enabled no)
			(sheetname "")
		)
		(fill yes
			(thermal_gap 0.5)
			(thermal_bridge_width 0.5)
			(island_removal_mode 0)
		)
		(polygon
			(pts
				(arc
					(start 435.737 -38.862)
					(mid 433.959 -38.862)
					(end 435.737 -38.862)
				)
			)
		)
	)
	(zone
		(layers "In4.Cu" "In5.Cu")
		(hatch none 0.5)
		(connect_pads
			(clearance 0)
		)
		(min_thickness 0.25)
		(keepout
			(tracks not_allowed)
			(vias allowed)
			(pads allowed)
			(copperpour not_allowed)
			(footprints allowed)
		)
		(placement
			(enabled no)
			(sheetname "")
		)
		(fill yes
			(thermal_gap 0.5)
			(thermal_bridge_width 0.5)
			(island_removal_mode 0)
		)
		(polygon
			(pts
				(arc
					(start 379.603 -111.879888)
					(mid 376.555 -111.879888)
					(end 379.603 -111.879888)
				)
			)
		)
	)
	(zone
		(layers "In4.Cu" "In5.Cu")
		(hatch none 0.5)
		(connect_pads
			(clearance 0)
		)
		(min_thickness 0.25)
		(keepout
			(tracks not_allowed)
			(vias allowed)
			(pads allowed)
			(copperpour not_allowed)
			(footprints allowed)
		)
		(placement
			(enabled no)
			(sheetname "")
		)
		(fill yes
			(thermal_gap 0.5)
			(thermal_bridge_width 0.5)
			(island_removal_mode 0)
		)
		(polygon
			(pts
				(arc
					(start 376.213116 -166.829994)
					(mid 373.786908 -166.829994)
					(end 376.213116 -166.829994)
				)
			)
		)
	)
	(zone
		(layers "In4.Cu" "In5.Cu")
		(hatch none 0.5)
		(connect_pads
			(clearance 0)
		)
		(min_thickness 0.25)
		(keepout
			(tracks not_allowed)
			(vias allowed)
			(pads allowed)
			(copperpour not_allowed)
			(footprints allowed)
		)
		(placement
			(enabled no)
			(sheetname "")
		)
		(fill yes
			(thermal_gap 0.5)
			(thermal_bridge_width 0.5)
			(island_removal_mode 0)
		)
		(polygon
			(pts
				(arc
					(start 427.609 -39.751)
					(mid 425.831 -39.751)
					(end 427.609 -39.751)
				)
			)
		)
	)
	(zone
		(layers "In4.Cu" "In5.Cu")
		(hatch none 0.5)
		(connect_pads
			(clearance 0)
		)
		(min_thickness 0.25)
		(keepout
			(tracks not_allowed)
			(vias allowed)
			(pads allowed)
			(copperpour not_allowed)
			(footprints allowed)
		)
		(placement
			(enabled no)
			(sheetname "")
		)
		(fill yes
			(thermal_gap 0.5)
			(thermal_bridge_width 0.5)
			(island_removal_mode 0)
		)
		(polygon
			(pts
				(arc
					(start 379.836172 -26.612342)
					(mid 378.058172 -26.612342)
					(end 379.836172 -26.612342)
				)
			)
		)
	)
	(zone
		(layers "In4.Cu" "In5.Cu")
		(hatch none 0.5)
		(connect_pads
			(clearance 0)
		)
		(min_thickness 0.25)
		(keepout
			(tracks not_allowed)
			(vias allowed)
			(pads allowed)
			(copperpour not_allowed)
			(footprints allowed)
		)
		(placement
			(enabled no)
			(sheetname "")
		)
		(fill yes
			(thermal_gap 0.5)
			(thermal_bridge_width 0.5)
			(island_removal_mode 0)
		)
		(polygon
			(pts
				(arc
					(start 420.252398 -25.332436)
					(mid 418.474398 -25.332436)
					(end 420.252398 -25.332436)
				)
			)
		)
	)
	(zone
		(layers "In4.Cu" "In5.Cu")
		(hatch none 0.5)
		(connect_pads
			(clearance 0)
		)
		(min_thickness 0.25)
		(keepout
			(tracks not_allowed)
			(vias allowed)
			(pads allowed)
			(copperpour not_allowed)
			(footprints allowed)
		)
		(placement
			(enabled no)
			(sheetname "")
		)
		(fill yes
			(thermal_gap 0.5)
			(thermal_bridge_width 0.5)
			(island_removal_mode 0)
		)
		(polygon
			(pts
				(arc
					(start 369.873022 -5.290058)
					(mid 367.446814 -5.290058)
					(end 369.873022 -5.290058)
				)
			)
		)
	)
	(zone
		(layers "In4.Cu" "In5.Cu")
		(hatch none 0.5)
		(connect_pads
			(clearance 0)
		)
		(min_thickness 0.25)
		(keepout
			(tracks not_allowed)
			(vias allowed)
			(pads allowed)
			(copperpour not_allowed)
			(footprints allowed)
		)
		(placement
			(enabled no)
			(sheetname "")
		)
		(fill yes
			(thermal_gap 0.5)
			(thermal_bridge_width 0.5)
			(island_removal_mode 0)
		)
		(polygon
			(pts
				(arc
					(start 449.562728 -63.576454)
					(mid 447.784728 -63.576454)
					(end 449.562728 -63.576454)
				)
			)
		)
	)
	(zone
		(layers "In4.Cu" "In5.Cu")
		(hatch none 0.5)
		(connect_pads
			(clearance 0)
		)
		(min_thickness 0.25)
		(keepout
			(tracks not_allowed)
			(vias allowed)
			(pads allowed)
			(copperpour not_allowed)
			(footprints allowed)
		)
		(placement
			(enabled no)
			(sheetname "")
		)
		(fill yes
			(thermal_gap 0.5)
			(thermal_bridge_width 0.5)
			(island_removal_mode 0)
		)
		(polygon
			(pts
				(arc
					(start 332.959964 -9.774428)
					(mid 331.181964 -9.774428)
					(end 332.959964 -9.774428)
				)
			)
		)
	)
	(zone
		(layers "In4.Cu" "In5.Cu")
		(hatch none 0.5)
		(connect_pads
			(clearance 0)
		)
		(min_thickness 0.25)
		(keepout
			(tracks not_allowed)
			(vias allowed)
			(pads allowed)
			(copperpour not_allowed)
			(footprints allowed)
		)
		(placement
			(enabled no)
			(sheetname "")
		)
		(fill yes
			(thermal_gap 0.5)
			(thermal_bridge_width 0.5)
			(island_removal_mode 0)
		)
		(polygon
			(pts
				(arc
					(start 444.373 -48.57496)
					(mid 442.595 -48.57496)
					(end 444.373 -48.57496)
				)
			)
		)
	)
	(zone
		(layers "In4.Cu" "In5.Cu")
		(hatch none 0.5)
		(connect_pads
			(clearance 0)
		)
		(min_thickness 0.25)
		(keepout
			(tracks not_allowed)
			(vias allowed)
			(pads allowed)
			(copperpour not_allowed)
			(footprints allowed)
		)
		(placement
			(enabled no)
			(sheetname "")
		)
		(fill yes
			(thermal_gap 0.5)
			(thermal_bridge_width 0.5)
			(island_removal_mode 0)
		)
		(polygon
			(pts
				(arc
					(start 419.4302 -21.1328)
					(mid 417.6522 -21.1328)
					(end 419.4302 -21.1328)
				)
			)
		)
	)
	(zone
		(layers "In4.Cu" "In5.Cu")
		(hatch none 0.5)
		(connect_pads
			(clearance 0)
		)
		(min_thickness 0.25)
		(keepout
			(tracks not_allowed)
			(vias allowed)
			(pads allowed)
			(copperpour not_allowed)
			(footprints allowed)
		)
		(placement
			(enabled no)
			(sheetname "")
		)
		(fill yes
			(thermal_gap 0.5)
			(thermal_bridge_width 0.5)
			(island_removal_mode 0)
		)
		(polygon
			(pts
				(arc
					(start 383.1844 -16.383)
					(mid 381.4064 -16.383)
					(end 383.1844 -16.383)
				)
			)
		)
	)
	(zone
		(layers "In4.Cu" "In5.Cu")
		(hatch none 0.5)
		(connect_pads
			(clearance 0)
		)
		(min_thickness 0.25)
		(keepout
			(tracks not_allowed)
			(vias allowed)
			(pads allowed)
			(copperpour not_allowed)
			(footprints allowed)
		)
		(placement
			(enabled no)
			(sheetname "")
		)
		(fill yes
			(thermal_gap 0.5)
			(thermal_bridge_width 0.5)
			(island_removal_mode 0)
		)
		(polygon
			(pts
				(arc
					(start 446.63995 -51.562)
					(mid 444.86195 -51.562)
					(end 446.63995 -51.562)
				)
			)
		)
	)
	(zone
		(layers "In4.Cu" "In5.Cu")
		(hatch none 0.5)
		(connect_pads
			(clearance 0)
		)
		(min_thickness 0.25)
		(keepout
			(tracks not_allowed)
			(vias allowed)
			(pads allowed)
			(copperpour not_allowed)
			(footprints allowed)
		)
		(placement
			(enabled no)
			(sheetname "")
		)
		(fill yes
			(thermal_gap 0.5)
			(thermal_bridge_width 0.5)
			(island_removal_mode 0)
		)
		(polygon
			(pts
				(arc
					(start 412.0642 -20.2438)
					(mid 410.2862 -20.2438)
					(end 412.0642 -20.2438)
				)
			)
		)
	)
	(zone
		(layers "In4.Cu" "In5.Cu")
		(hatch none 0.5)
		(connect_pads
			(clearance 0)
		)
		(min_thickness 0.25)
		(keepout
			(tracks not_allowed)
			(vias allowed)
			(pads allowed)
			(copperpour not_allowed)
			(footprints allowed)
		)
		(placement
			(enabled no)
			(sheetname "")
		)
		(fill yes
			(thermal_gap 0.5)
			(thermal_bridge_width 0.5)
			(island_removal_mode 0)
		)
		(polygon
			(pts
				(arc
					(start 43.379644 -58.42)
					(mid 41.347136 -58.42)
					(end 43.379644 -58.42)
				)
			)
		)
	)
	(zone
		(layers "In4.Cu" "In5.Cu")
		(hatch none 0.5)
		(connect_pads
			(clearance 0)
		)
		(min_thickness 0.25)
		(keepout
			(tracks not_allowed)
			(vias allowed)
			(pads allowed)
			(copperpour not_allowed)
			(footprints allowed)
		)
		(placement
			(enabled no)
			(sheetname "")
		)
		(fill yes
			(thermal_gap 0.5)
			(thermal_bridge_width 0.5)
			(island_removal_mode 0)
		)
		(polygon
			(pts
				(arc
					(start 406.338278 -160.830006)
					(mid 403.91207 -160.830006)
					(end 406.338278 -160.830006)
				)
			)
		)
	)
	(zone
		(layers "In4.Cu" "In5.Cu")
		(hatch none 0.5)
		(connect_pads
			(clearance 0)
		)
		(min_thickness 0.25)
		(keepout
			(tracks not_allowed)
			(vias allowed)
			(pads allowed)
			(copperpour not_allowed)
			(footprints allowed)
		)
		(placement
			(enabled no)
			(sheetname "")
		)
		(fill yes
			(thermal_gap 0.5)
			(thermal_bridge_width 0.5)
			(island_removal_mode 0)
		)
		(polygon
			(pts
				(arc
					(start 43.379644 -119.38)
					(mid 41.347136 -119.38)
					(end 43.379644 -119.38)
				)
			)
		)
	)
	(zone
		(layers "In4.Cu" "In5.Cu")
		(hatch none 0.5)
		(connect_pads
			(clearance 0)
		)
		(min_thickness 0.25)
		(keepout
			(tracks not_allowed)
			(vias allowed)
			(pads allowed)
			(copperpour not_allowed)
			(footprints allowed)
		)
		(placement
			(enabled no)
			(sheetname "")
		)
		(fill yes
			(thermal_gap 0.5)
			(thermal_bridge_width 0.5)
			(island_removal_mode 0)
		)
		(polygon
			(pts
				(arc
					(start 458.1144 -47.625)
					(mid 456.3364 -47.625)
					(end 458.1144 -47.625)
				)
			)
		)
	)
	(zone
		(layers "In4.Cu" "In5.Cu")
		(hatch none 0.5)
		(connect_pads
			(clearance 0)
		)
		(min_thickness 0.25)
		(keepout
			(tracks not_allowed)
			(vias allowed)
			(pads allowed)
			(copperpour not_allowed)
			(footprints allowed)
		)
		(placement
			(enabled no)
			(sheetname "")
		)
		(fill yes
			(thermal_gap 0.5)
			(thermal_bridge_width 0.5)
			(island_removal_mode 0)
		)
		(polygon
			(pts
				(arc
					(start 416.179 -38.84295)
					(mid 414.401 -38.84295)
					(end 416.179 -38.84295)
				)
			)
		)
	)
	(zone
		(layers "In4.Cu" "In5.Cu")
		(hatch none 0.5)
		(connect_pads
			(clearance 0)
		)
		(min_thickness 0.25)
		(keepout
			(tracks not_allowed)
			(vias allowed)
			(pads allowed)
			(copperpour not_allowed)
			(footprints allowed)
		)
		(placement
			(enabled no)
			(sheetname "")
		)
		(fill yes
			(thermal_gap 0.5)
			(thermal_bridge_width 0.5)
			(island_removal_mode 0)
		)
		(polygon
			(pts
				(arc
					(start 420.018718 -45.72)
					(mid 418.240718 -45.72)
					(end 420.018718 -45.72)
				)
			)
		)
	)
	(zone
		(layers "In4.Cu" "In5.Cu")
		(hatch none 0.5)
		(connect_pads
			(clearance 0)
		)
		(min_thickness 0.25)
		(keepout
			(tracks not_allowed)
			(vias allowed)
			(pads allowed)
			(copperpour not_allowed)
			(footprints allowed)
		)
		(placement
			(enabled no)
			(sheetname "")
		)
		(fill yes
			(thermal_gap 0.5)
			(thermal_bridge_width 0.5)
			(island_removal_mode 0)
		)
		(polygon
			(pts
				(arc
					(start 408.8384 -20.828)
					(mid 407.0604 -20.828)
					(end 408.8384 -20.828)
				)
			)
		)
	)
	(zone
		(layers "In4.Cu" "In5.Cu")
		(hatch none 0.5)
		(connect_pads
			(clearance 0)
		)
		(min_thickness 0.25)
		(keepout
			(tracks not_allowed)
			(vias allowed)
			(pads allowed)
			(copperpour not_allowed)
			(footprints allowed)
		)
		(placement
			(enabled no)
			(sheetname "")
		)
		(fill yes
			(thermal_gap 0.5)
			(thermal_bridge_width 0.5)
			(island_removal_mode 0)
		)
		(polygon
			(pts
				(arc
					(start 438.023 -36.20135)
					(mid 436.245 -36.20135)
					(end 438.023 -36.20135)
				)
			)
		)
	)
	(zone
		(layers "In4.Cu" "In5.Cu")
		(hatch none 0.5)
		(connect_pads
			(clearance 0)
		)
		(min_thickness 0.25)
		(keepout
			(tracks not_allowed)
			(vias allowed)
			(pads allowed)
			(copperpour not_allowed)
			(footprints allowed)
		)
		(placement
			(enabled no)
			(sheetname "")
		)
		(fill yes
			(thermal_gap 0.5)
			(thermal_bridge_width 0.5)
			(island_removal_mode 0)
		)
		(polygon
			(pts
				(arc
					(start 414.12795 -39.624)
					(mid 412.34995 -39.624)
					(end 414.12795 -39.624)
				)
			)
		)
	)
	(zone
		(layers "In4.Cu" "In5.Cu")
		(hatch none 0.5)
		(connect_pads
			(clearance 0)
		)
		(min_thickness 0.25)
		(keepout
			(tracks not_allowed)
			(vias allowed)
			(pads allowed)
			(copperpour not_allowed)
			(footprints allowed)
		)
		(placement
			(enabled no)
			(sheetname "")
		)
		(fill yes
			(thermal_gap 0.5)
			(thermal_bridge_width 0.5)
			(island_removal_mode 0)
		)
		(polygon
			(pts
				(arc
					(start 413.512 -37.084)
					(mid 411.734 -37.084)
					(end 413.512 -37.084)
				)
			)
		)
	)
	(zone
		(layers "In4.Cu" "In5.Cu")
		(hatch none 0.5)
		(connect_pads
			(clearance 0)
		)
		(min_thickness 0.25)
		(keepout
			(tracks not_allowed)
			(vias allowed)
			(pads allowed)
			(copperpour not_allowed)
			(footprints allowed)
		)
		(placement
			(enabled no)
			(sheetname "")
		)
		(fill yes
			(thermal_gap 0.5)
			(thermal_bridge_width 0.5)
			(island_removal_mode 0)
		)
		(polygon
			(pts
				(arc
					(start 362.91774 -10.282174)
					(mid 361.13974 -10.282174)
					(end 362.91774 -10.282174)
				)
			)
		)
	)
	(zone
		(layers "In4.Cu" "In5.Cu")
		(hatch none 0.5)
		(connect_pads
			(clearance 0)
		)
		(min_thickness 0.25)
		(keepout
			(tracks not_allowed)
			(vias allowed)
			(pads allowed)
			(copperpour not_allowed)
			(footprints allowed)
		)
		(placement
			(enabled no)
			(sheetname "")
		)
		(fill yes
			(thermal_gap 0.5)
			(thermal_bridge_width 0.5)
			(island_removal_mode 0)
		)
		(polygon
			(pts
				(arc
					(start 422.148 -35.052)
					(mid 420.37 -35.052)
					(end 422.148 -35.052)
				)
			)
		)
	)
	(zone
		(layers "In4.Cu" "In5.Cu")
		(hatch none 0.5)
		(connect_pads
			(clearance 0)
		)
		(min_thickness 0.25)
		(keepout
			(tracks not_allowed)
			(vias allowed)
			(pads allowed)
			(copperpour not_allowed)
			(footprints allowed)
		)
		(placement
			(enabled no)
			(sheetname "")
		)
		(fill yes
			(thermal_gap 0.5)
			(thermal_bridge_width 0.5)
			(island_removal_mode 0)
		)
		(polygon
			(pts
				(arc
					(start 437.902096 -44.45)
					(mid 436.124096 -44.45)
					(end 437.902096 -44.45)
				)
			)
		)
	)
	(zone
		(layers "In4.Cu" "In5.Cu")
		(hatch none 0.5)
		(connect_pads
			(clearance 0)
		)
		(min_thickness 0.25)
		(keepout
			(tracks not_allowed)
			(vias allowed)
			(pads allowed)
			(copperpour not_allowed)
			(footprints allowed)
		)
		(placement
			(enabled no)
			(sheetname "")
		)
		(fill yes
			(thermal_gap 0.5)
			(thermal_bridge_width 0.5)
			(island_removal_mode 0)
		)
		(polygon
			(pts
				(arc
					(start 361.39374 -10.282174)
					(mid 359.61574 -10.282174)
					(end 361.39374 -10.282174)
				)
			)
		)
	)
	(zone
		(layers "In4.Cu" "In5.Cu")
		(hatch none 0.5)
		(connect_pads
			(clearance 0)
		)
		(min_thickness 0.25)
		(keepout
			(tracks not_allowed)
			(vias allowed)
			(pads allowed)
			(copperpour not_allowed)
			(footprints allowed)
		)
		(placement
			(enabled no)
			(sheetname "")
		)
		(fill yes
			(thermal_gap 0.5)
			(thermal_bridge_width 0.5)
			(island_removal_mode 0)
		)
		(polygon
			(pts
				(arc
					(start 63.44539 -91.559888)
					(mid 60.39739 -91.559888)
					(end 63.44539 -91.559888)
				)
			)
		)
	)
	(zone
		(layers "In4.Cu" "In5.Cu")
		(hatch none 0.5)
		(connect_pads
			(clearance 0)
		)
		(min_thickness 0.25)
		(keepout
			(tracks not_allowed)
			(vias allowed)
			(pads allowed)
			(copperpour not_allowed)
			(footprints allowed)
		)
		(placement
			(enabled no)
			(sheetname "")
		)
		(fill yes
			(thermal_gap 0.5)
			(thermal_bridge_width 0.5)
			(island_removal_mode 0)
		)
		(polygon
			(pts
				(arc
					(start 62.937644 -78.74)
					(mid 60.905136 -78.74)
					(end 62.937644 -78.74)
				)
			)
		)
	)
	(zone
		(layers "In4.Cu" "In5.Cu")
		(hatch none 0.5)
		(connect_pads
			(clearance 0)
		)
		(min_thickness 0.25)
		(keepout
			(tracks not_allowed)
			(vias allowed)
			(pads allowed)
			(copperpour not_allowed)
			(footprints allowed)
		)
		(placement
			(enabled no)
			(sheetname "")
		)
		(fill yes
			(thermal_gap 0.5)
			(thermal_bridge_width 0.5)
			(island_removal_mode 0)
		)
		(polygon
			(pts
				(arc
					(start 432.174904 -43.18)
					(mid 430.396904 -43.18)
					(end 432.174904 -43.18)
				)
			)
		)
	)
	(zone
		(layers "In4.Cu" "In5.Cu")
		(hatch none 0.5)
		(connect_pads
			(clearance 0)
		)
		(min_thickness 0.25)
		(keepout
			(tracks not_allowed)
			(vias allowed)
			(pads allowed)
			(copperpour not_allowed)
			(footprints allowed)
		)
		(placement
			(enabled no)
			(sheetname "")
		)
		(fill yes
			(thermal_gap 0.5)
			(thermal_bridge_width 0.5)
			(island_removal_mode 0)
		)
		(polygon
			(pts
				(arc
					(start 66.500248 -13.499846)
					(mid 71.000366 -8.999728)
					(end 75.50023 -13.499846)
				)
				(arc
					(start 75.50023 -18.499836)
					(mid 71.000366 -22.9997)
					(end 66.500248 -18.499836)
				)
			)
		)
	)
	(zone
		(layers "In4.Cu" "In5.Cu")
		(hatch none 0.5)
		(connect_pads
			(clearance 0)
		)
		(min_thickness 0.25)
		(keepout
			(tracks not_allowed)
			(vias allowed)
			(pads allowed)
			(copperpour not_allowed)
			(footprints allowed)
		)
		(placement
			(enabled no)
			(sheetname "")
		)
		(fill yes
			(thermal_gap 0.5)
			(thermal_bridge_width 0.5)
			(island_removal_mode 0)
		)
		(polygon
			(pts
				(arc
					(start 388.7724 -25.12695)
					(mid 386.9944 -25.12695)
					(end 388.7724 -25.12695)
				)
			)
		)
	)
	(zone
		(layers "In4.Cu" "In5.Cu")
		(hatch none 0.5)
		(connect_pads
			(clearance 0)
		)
		(min_thickness 0.25)
		(keepout
			(tracks not_allowed)
			(vias allowed)
			(pads allowed)
			(copperpour not_allowed)
			(footprints allowed)
		)
		(placement
			(enabled no)
			(sheetname "")
		)
		(fill yes
			(thermal_gap 0.5)
			(thermal_bridge_width 0.5)
			(island_removal_mode 0)
		)
		(polygon
			(pts
				(arc
					(start 43.379644 -99.06)
					(mid 41.347136 -99.06)
					(end 43.379644 -99.06)
				)
			)
		)
	)
	(zone
		(layers "In4.Cu" "In5.Cu")
		(hatch none 0.5)
		(connect_pads
			(clearance 0)
		)
		(min_thickness 0.25)
		(keepout
			(tracks not_allowed)
			(vias allowed)
			(pads allowed)
			(copperpour not_allowed)
			(footprints allowed)
		)
		(placement
			(enabled no)
			(sheetname "")
		)
		(fill yes
			(thermal_gap 0.5)
			(thermal_bridge_width 0.5)
			(island_removal_mode 0)
		)
		(polygon
			(pts
				(arc
					(start 445.532002 -50.292)
					(mid 443.754002 -50.292)
					(end 445.532002 -50.292)
				)
			)
		)
	)
	(zone
		(layers "In4.Cu" "In5.Cu")
		(hatch none 0.5)
		(connect_pads
			(clearance 0)
		)
		(min_thickness 0.25)
		(keepout
			(tracks not_allowed)
			(vias allowed)
			(pads allowed)
			(copperpour not_allowed)
			(footprints allowed)
		)
		(placement
			(enabled no)
			(sheetname "")
		)
		(fill yes
			(thermal_gap 0.5)
			(thermal_bridge_width 0.5)
			(island_removal_mode 0)
		)
		(polygon
			(pts
				(arc
					(start 439.5724 -41.72712)
					(mid 437.7944 -41.72712)
					(end 439.5724 -41.72712)
				)
			)
		)
	)
	(zone
		(layers "In4.Cu" "In5.Cu")
		(hatch none 0.5)
		(connect_pads
			(clearance 0)
		)
		(min_thickness 0.25)
		(keepout
			(tracks not_allowed)
			(vias allowed)
			(pads allowed)
			(copperpour not_allowed)
			(footprints allowed)
		)
		(placement
			(enabled no)
			(sheetname "")
		)
		(fill yes
			(thermal_gap 0.5)
			(thermal_bridge_width 0.5)
			(island_removal_mode 0)
		)
		(polygon
			(pts
				(arc
					(start 421.7797 -29.65704)
					(mid 420.0017 -29.65704)
					(end 421.7797 -29.65704)
				)
			)
		)
	)
	(zone
		(layers "In4.Cu" "In5.Cu")
		(hatch none 0.5)
		(connect_pads
			(clearance 0)
		)
		(min_thickness 0.25)
		(keepout
			(tracks not_allowed)
			(vias allowed)
			(pads allowed)
			(copperpour not_allowed)
			(footprints allowed)
		)
		(placement
			(enabled no)
			(sheetname "")
		)
		(fill yes
			(thermal_gap 0.5)
			(thermal_bridge_width 0.5)
			(island_removal_mode 0)
		)
		(polygon
			(pts
				(arc
					(start 64.213232 -166.829994)
					(mid 61.787024 -166.829994)
					(end 64.213232 -166.829994)
				)
			)
		)
	)
	(zone
		(layers "In4.Cu" "In5.Cu")
		(hatch none 0.5)
		(connect_pads
			(clearance 0)
		)
		(min_thickness 0.25)
		(keepout
			(tracks not_allowed)
			(vias allowed)
			(pads allowed)
			(copperpour not_allowed)
			(footprints allowed)
		)
		(placement
			(enabled no)
			(sheetname "")
		)
		(fill yes
			(thermal_gap 0.5)
			(thermal_bridge_width 0.5)
			(island_removal_mode 0)
		)
		(polygon
			(pts
				(arc
					(start 418.16401 -29.0703)
					(mid 416.43681 -29.0703)
					(end 418.16401 -29.0703)
				)
			)
		)
	)
	(zone
		(layers "In4.Cu" "In5.Cu")
		(hatch none 0.5)
		(connect_pads
			(clearance 0)
		)
		(min_thickness 0.25)
		(keepout
			(tracks not_allowed)
			(vias allowed)
			(pads allowed)
			(copperpour not_allowed)
			(footprints allowed)
		)
		(placement
			(enabled no)
			(sheetname "")
		)
		(fill yes
			(thermal_gap 0.5)
			(thermal_bridge_width 0.5)
			(island_removal_mode 0)
		)
		(polygon
			(pts
				(arc
					(start 424.307 -35.052)
					(mid 422.529 -35.052)
					(end 424.307 -35.052)
				)
			)
		)
	)
	(zone
		(layers "In4.Cu" "In5.Cu")
		(hatch none 0.5)
		(connect_pads
			(clearance 0)
		)
		(min_thickness 0.25)
		(keepout
			(tracks not_allowed)
			(vias allowed)
			(pads allowed)
			(copperpour not_allowed)
			(footprints allowed)
		)
		(placement
			(enabled no)
			(sheetname "")
		)
		(fill yes
			(thermal_gap 0.5)
			(thermal_bridge_width 0.5)
			(island_removal_mode 0)
		)
		(polygon
			(pts
				(arc
					(start 101.527864 -11.90625)
					(mid 99.749864 -11.90625)
					(end 101.527864 -11.90625)
				)
			)
		)
	)
	(zone
		(layers "In4.Cu" "In5.Cu")
		(hatch none 0.5)
		(connect_pads
			(clearance 0)
		)
		(min_thickness 0.25)
		(keepout
			(tracks not_allowed)
			(vias allowed)
			(pads allowed)
			(copperpour not_allowed)
			(footprints allowed)
		)
		(placement
			(enabled no)
			(sheetname "")
		)
		(fill yes
			(thermal_gap 0.5)
			(thermal_bridge_width 0.5)
			(island_removal_mode 0)
		)
		(polygon
			(pts
				(arc
					(start 379.603 -91.559888)
					(mid 376.555 -91.559888)
					(end 379.603 -91.559888)
				)
			)
		)
	)
	(zone
		(layers "In4.Cu" "In5.Cu")
		(hatch none 0.5)
		(connect_pads
			(clearance 0)
		)
		(min_thickness 0.25)
		(keepout
			(tracks not_allowed)
			(vias allowed)
			(pads allowed)
			(copperpour not_allowed)
			(footprints allowed)
		)
		(placement
			(enabled no)
			(sheetname "")
		)
		(fill yes
			(thermal_gap 0.5)
			(thermal_bridge_width 0.5)
			(island_removal_mode 0)
		)
		(polygon
			(pts
				(arc
					(start 436.63235 -38.862)
					(mid 434.85435 -38.862)
					(end 436.63235 -38.862)
				)
			)
		)
	)
	(zone
		(layers "In4.Cu" "In5.Cu")
		(hatch none 0.5)
		(connect_pads
			(clearance 0)
		)
		(min_thickness 0.25)
		(keepout
			(tracks not_allowed)
			(vias allowed)
			(pads allowed)
			(copperpour not_allowed)
			(footprints allowed)
		)
		(placement
			(enabled no)
			(sheetname "")
		)
		(fill yes
			(thermal_gap 0.5)
			(thermal_bridge_width 0.5)
			(island_removal_mode 0)
		)
		(polygon
			(pts
				(arc
					(start 43.379644 -78.74)
					(mid 41.347136 -78.74)
					(end 43.379644 -78.74)
				)
			)
		)
	)
	(zone
		(layers "In4.Cu" "In5.Cu")
		(hatch none 0.5)
		(connect_pads
			(clearance 0)
		)
		(min_thickness 0.25)
		(keepout
			(tracks not_allowed)
			(vias allowed)
			(pads allowed)
			(copperpour not_allowed)
			(footprints allowed)
		)
		(placement
			(enabled no)
			(sheetname "")
		)
		(fill yes
			(thermal_gap 0.5)
			(thermal_bridge_width 0.5)
			(island_removal_mode 0)
		)
		(polygon
			(pts
				(arc
					(start 451.848728 -62.828678)
					(mid 450.070728 -62.828678)
					(end 451.848728 -62.828678)
				)
			)
		)
	)
	(zone
		(layers "In4.Cu" "In5.Cu")
		(hatch none 0.5)
		(connect_pads
			(clearance 0)
		)
		(min_thickness 0.25)
		(keepout
			(tracks not_allowed)
			(vias allowed)
			(pads allowed)
			(copperpour not_allowed)
			(footprints allowed)
		)
		(placement
			(enabled no)
			(sheetname "")
		)
		(fill yes
			(thermal_gap 0.5)
			(thermal_bridge_width 0.5)
			(island_removal_mode 0)
		)
		(polygon
			(pts
				(arc
					(start 76.213208 -166.829994)
					(mid 73.787 -166.829994)
					(end 76.213208 -166.829994)
				)
			)
		)
	)
	(zone
		(layers "In4.Cu" "In5.Cu")
		(hatch none 0.5)
		(connect_pads
			(clearance 0)
		)
		(min_thickness 0.25)
		(keepout
			(tracks not_allowed)
			(vias allowed)
			(pads allowed)
			(copperpour not_allowed)
			(footprints allowed)
		)
		(placement
			(enabled no)
			(sheetname "")
		)
		(fill yes
			(thermal_gap 0.5)
			(thermal_bridge_width 0.5)
			(island_removal_mode 0)
		)
		(polygon
			(pts
				(arc
					(start 433.33035 -32.893)
					(mid 431.55235 -32.893)
					(end 433.33035 -32.893)
				)
			)
		)
	)
	(zone
		(layers "In4.Cu" "In5.Cu")
		(hatch none 0.5)
		(connect_pads
			(clearance 0)
		)
		(min_thickness 0.25)
		(keepout
			(tracks not_allowed)
			(vias allowed)
			(pads allowed)
			(copperpour not_allowed)
			(footprints allowed)
		)
		(placement
			(enabled no)
			(sheetname "")
		)
		(fill yes
			(thermal_gap 0.5)
			(thermal_bridge_width 0.5)
			(island_removal_mode 0)
		)
		(polygon
			(pts
				(arc
					(start 40.83812 -152.830022)
					(mid 38.411912 -152.830022)
					(end 40.83812 -152.830022)
				)
			)
		)
	)
	(zone
		(layers "In4.Cu" "In5.Cu")
		(hatch none 0.5)
		(connect_pads
			(clearance 0)
		)
		(min_thickness 0.25)
		(keepout
			(tracks not_allowed)
			(vias allowed)
			(pads allowed)
			(copperpour not_allowed)
			(footprints allowed)
		)
		(placement
			(enabled no)
			(sheetname "")
		)
		(fill yes
			(thermal_gap 0.5)
			(thermal_bridge_width 0.5)
			(island_removal_mode 0)
		)
		(polygon
			(pts
				(arc
					(start 399.161 -111.879888)
					(mid 396.113 -111.879888)
					(end 399.161 -111.879888)
				)
			)
		)
	)
	(zone
		(layers "In4.Cu" "In5.Cu")
		(hatch none 0.5)
		(connect_pads
			(clearance 0)
		)
		(min_thickness 0.25)
		(keepout
			(tracks not_allowed)
			(vias allowed)
			(pads allowed)
			(copperpour not_allowed)
			(footprints allowed)
		)
		(placement
			(enabled no)
			(sheetname "")
		)
		(fill yes
			(thermal_gap 0.5)
			(thermal_bridge_width 0.5)
			(island_removal_mode 0)
		)
		(polygon
			(pts
				(arc
					(start 66.213228 -166.829994)
					(mid 63.78702 -166.829994)
					(end 66.213228 -166.829994)
				)
			)
		)
	)
	(zone
		(layers "In4.Cu" "In5.Cu")
		(hatch none 0.5)
		(connect_pads
			(clearance 0)
		)
		(min_thickness 0.25)
		(keepout
			(tracks not_allowed)
			(vias allowed)
			(pads allowed)
			(copperpour not_allowed)
			(footprints allowed)
		)
		(placement
			(enabled no)
			(sheetname "")
		)
		(fill yes
			(thermal_gap 0.5)
			(thermal_bridge_width 0.5)
			(island_removal_mode 0)
		)
		(polygon
			(pts
				(arc
					(start 419.862 -44.043092)
					(mid 418.084 -44.043092)
					(end 419.862 -44.043092)
				)
			)
		)
	)
	(zone
		(layers "In4.Cu" "In5.Cu")
		(hatch none 0.5)
		(connect_pads
			(clearance 0)
		)
		(min_thickness 0.25)
		(keepout
			(tracks not_allowed)
			(vias allowed)
			(pads allowed)
			(copperpour not_allowed)
			(footprints allowed)
		)
		(placement
			(enabled no)
			(sheetname "")
		)
		(fill yes
			(thermal_gap 0.5)
			(thermal_bridge_width 0.5)
			(island_removal_mode 0)
		)
		(polygon
			(pts
				(arc
					(start 433.0319 -29.0195)
					(mid 431.2539 -29.0195)
					(end 433.0319 -29.0195)
				)
			)
		)
	)
	(zone
		(layers "In4.Cu" "In5.Cu")
		(hatch none 0.5)
		(connect_pads
			(clearance 0)
		)
		(min_thickness 0.25)
		(keepout
			(tracks not_allowed)
			(vias allowed)
			(pads allowed)
			(copperpour not_allowed)
			(footprints allowed)
		)
		(placement
			(enabled no)
			(sheetname "")
		)
		(fill yes
			(thermal_gap 0.5)
			(thermal_bridge_width 0.5)
			(island_removal_mode 0)
		)
		(polygon
			(pts
				(arc
					(start 379.095254 -58.42)
					(mid 377.062746 -58.42)
					(end 379.095254 -58.42)
				)
			)
		)
	)
	(zone
		(layers "In4.Cu" "In5.Cu")
		(hatch none 0.5)
		(connect_pads
			(clearance 0)
		)
		(min_thickness 0.25)
		(keepout
			(tracks not_allowed)
			(vias allowed)
			(pads allowed)
			(copperpour not_allowed)
			(footprints allowed)
		)
		(placement
			(enabled no)
			(sheetname "")
		)
		(fill yes
			(thermal_gap 0.5)
			(thermal_bridge_width 0.5)
			(island_removal_mode 0)
		)
		(polygon
			(pts
				(arc
					(start 404.338282 -156.830014)
					(mid 401.912074 -156.830014)
					(end 404.338282 -156.830014)
				)
			)
		)
	)
	(zone
		(layers "In4.Cu" "In5.Cu")
		(hatch none 0.5)
		(connect_pads
			(clearance 0)
		)
		(min_thickness 0.25)
		(keepout
			(tracks not_allowed)
			(vias allowed)
			(pads allowed)
			(copperpour not_allowed)
			(footprints allowed)
		)
		(placement
			(enabled no)
			(sheetname "")
		)
		(fill yes
			(thermal_gap 0.5)
			(thermal_bridge_width 0.5)
			(island_removal_mode 0)
		)
		(polygon
			(pts
				(arc
					(start 443.0014 -59.182)
					(mid 441.2234 -59.182)
					(end 443.0014 -59.182)
				)
			)
		)
	)
	(zone
		(layers "In4.Cu" "In5.Cu")
		(hatch none 0.5)
		(connect_pads
			(clearance 0)
		)
		(min_thickness 0.25)
		(keepout
			(tracks not_allowed)
			(vias allowed)
			(pads allowed)
			(copperpour not_allowed)
			(footprints allowed)
		)
		(placement
			(enabled no)
			(sheetname "")
		)
		(fill yes
			(thermal_gap 0.5)
			(thermal_bridge_width 0.5)
			(island_removal_mode 0)
		)
		(polygon
			(pts
				(arc
					(start 378.213112 -168.82999)
					(mid 375.786904 -168.82999)
					(end 378.213112 -168.82999)
				)
			)
		)
	)
	(zone
		(layers "In4.Cu" "In5.Cu")
		(hatch none 0.5)
		(connect_pads
			(clearance 0)
		)
		(min_thickness 0.25)
		(keepout
			(tracks not_allowed)
			(vias allowed)
			(pads allowed)
			(copperpour not_allowed)
			(footprints allowed)
		)
		(placement
			(enabled no)
			(sheetname "")
		)
		(fill yes
			(thermal_gap 0.5)
			(thermal_bridge_width 0.5)
			(island_removal_mode 0)
		)
		(polygon
			(pts
				(arc
					(start 82.363564 -9.959594)
					(mid 80.585564 -9.959594)
					(end 82.363564 -9.959594)
				)
			)
		)
	)
	(zone
		(layers "In4.Cu" "In5.Cu")
		(hatch none 0.5)
		(connect_pads
			(clearance 0)
		)
		(min_thickness 0.25)
		(keepout
			(tracks not_allowed)
			(vias allowed)
			(pads allowed)
			(copperpour not_allowed)
			(footprints allowed)
		)
		(placement
			(enabled no)
			(sheetname "")
		)
		(fill yes
			(thermal_gap 0.5)
			(thermal_bridge_width 0.5)
			(island_removal_mode 0)
		)
		(polygon
			(pts
				(arc
					(start 436.124096 -29.083)
					(mid 434.346096 -29.083)
					(end 436.124096 -29.083)
				)
			)
		)
	)
	(zone
		(layers "In4.Cu" "In5.Cu")
		(hatch none 0.5)
		(connect_pads
			(clearance 0)
		)
		(min_thickness 0.25)
		(keepout
			(tracks not_allowed)
			(vias allowed)
			(pads allowed)
			(copperpour not_allowed)
			(footprints allowed)
		)
		(placement
			(enabled no)
			(sheetname "")
		)
		(fill yes
			(thermal_gap 0.5)
			(thermal_bridge_width 0.5)
			(island_removal_mode 0)
		)
		(polygon
			(pts
				(arc
					(start 448.945 -36.20135)
					(mid 447.167 -36.20135)
					(end 448.945 -36.20135)
				)
			)
		)
	)
	(zone
		(layers "In4.Cu" "In5.Cu" "In7.Cu")
		(hatch none 0.5)
		(connect_pads
			(clearance 0)
		)
		(min_thickness 0.25)
		(keepout
			(tracks not_allowed)
			(vias allowed)
			(pads allowed)
			(copperpour not_allowed)
			(footprints allowed)
		)
		(placement
			(enabled no)
			(sheetname "")
		)
		(fill yes
			(thermal_gap 0.5)
			(thermal_bridge_width 0.5)
			(island_removal_mode 0)
		)
		(polygon
			(pts
				(arc
					(start 424.999912 -65.129156)
					(mid 430.029112 -60.099956)
					(end 424.999912 -55.070756)
				)
				(arc
					(start 424.999912 -55.070756)
					(mid 424.885612 -54.956456)
					(end 424.999912 -54.842156)
				)
				(arc
					(start 424.999912 -54.842156)
					(mid 430.257712 -60.099956)
					(end 424.999912 -65.357756)
				)
				(arc
					(start 424.999912 -65.357756)
					(mid 424.885612 -65.243456)
					(end 424.999912 -65.129156)
				)
			)
		)
	)
	(zone
		(layers "In4.Cu" "In5.Cu" "In7.Cu")
		(hatch none 0.5)
		(connect_pads
			(clearance 0)
		)
		(min_thickness 0.25)
		(keepout
			(tracks not_allowed)
			(vias allowed)
			(pads allowed)
			(copperpour not_allowed)
			(footprints allowed)
		)
		(placement
			(enabled no)
			(sheetname "")
		)
		(fill yes
			(thermal_gap 0.5)
			(thermal_bridge_width 0.5)
			(island_removal_mode 0)
		)
		(polygon
			(pts
				(arc
					(start 132.31114 -83.566)
					(mid 130.53314 -83.566)
					(end 132.31114 -83.566)
				)
			)
		)
	)
	(zone
		(layers "In4.Cu" "In5.Cu" "In7.Cu")
		(hatch none 0.5)
		(connect_pads
			(clearance 0)
		)
		(min_thickness 0.25)
		(keepout
			(tracks not_allowed)
			(vias allowed)
			(pads allowed)
			(copperpour not_allowed)
			(footprints allowed)
		)
		(placement
			(enabled no)
			(sheetname "")
		)
		(fill yes
			(thermal_gap 0.5)
			(thermal_bridge_width 0.5)
			(island_removal_mode 0)
		)
		(polygon
			(pts
				(arc
					(start 430.127664 -60.099956)
					(mid 419.87216 -60.099956)
					(end 430.127664 -60.099956)
				)
			)
		)
	)
	(zone
		(layers "In4.Cu" "In5.Cu" "In7.Cu")
		(hatch none 0.5)
		(connect_pads
			(clearance 0)
		)
		(min_thickness 0.25)
		(keepout
			(tracks not_allowed)
			(vias allowed)
			(pads allowed)
			(copperpour not_allowed)
			(footprints allowed)
		)
		(placement
			(enabled no)
			(sheetname "")
		)
		(fill yes
			(thermal_gap 0.5)
			(thermal_bridge_width 0.5)
			(island_removal_mode 0)
		)
		(polygon
			(pts
				(arc
					(start 129.491486 -83.566)
					(mid 127.713486 -83.566)
					(end 129.491486 -83.566)
				)
			)
		)
	)
	(zone
		(layers "In4.Cu" "In5.Cu" "In7.Cu")
		(hatch none 0.5)
		(connect_pads
			(clearance 0)
		)
		(min_thickness 0.25)
		(keepout
			(tracks not_allowed)
			(vias allowed)
			(pads allowed)
			(copperpour not_allowed)
			(footprints allowed)
		)
		(placement
			(enabled no)
			(sheetname "")
		)
		(fill yes
			(thermal_gap 0.5)
			(thermal_bridge_width 0.5)
			(island_removal_mode 0)
		)
		(polygon
			(pts
				(arc
					(start 363.86516 -18.50009)
					(mid 369.000278 -23.635208)
					(end 374.135142 -18.50009)
				)
				(arc
					(start 374.135142 -13.5001)
					(mid 369.000278 -8.365236)
					(end 363.86516 -13.5001)
				)
			)
		)
	)
	(zone
		(layers "In4.Cu" "In5.Cu" "In7.Cu")
		(hatch none 0.5)
		(connect_pads
			(clearance 0)
		)
		(min_thickness 0.25)
		(keepout
			(tracks not_allowed)
			(vias allowed)
			(pads allowed)
			(copperpour not_allowed)
			(footprints allowed)
		)
		(placement
			(enabled no)
			(sheetname "")
		)
		(fill yes
			(thermal_gap 0.5)
			(thermal_bridge_width 0.5)
			(island_removal_mode 0)
		)
		(polygon
			(pts
				(arc
					(start 424.999912 -55.070756)
					(mid 419.970712 -60.099956)
					(end 424.999912 -65.129156)
				)
				(arc
					(start 424.999912 -65.129156)
					(mid 425.114212 -65.243456)
					(end 424.999912 -65.357756)
				)
				(arc
					(start 424.999912 -65.357756)
					(mid 419.742112 -60.099956)
					(end 424.999912 -54.842156)
				)
				(arc
					(start 424.999912 -54.842156)
					(mid 425.114212 -54.956456)
					(end 424.999912 -55.070756)
				)
			)
		)
	)
	(zone
		(layers "In4.Cu" "In5.Cu" "In7.Cu")
		(hatch none 0.5)
		(connect_pads
			(clearance 0)
		)
		(min_thickness 0.25)
		(keepout
			(tracks not_allowed)
			(vias allowed)
			(pads allowed)
			(copperpour not_allowed)
			(footprints allowed)
		)
		(placement
			(enabled no)
			(sheetname "")
		)
		(fill yes
			(thermal_gap 0.5)
			(thermal_bridge_width 0.5)
			(island_removal_mode 0)
		)
		(polygon
			(pts
				(arc
					(start 430.762664 -60.099956)
					(mid 419.23716 -60.099956)
					(end 430.762664 -60.099956)
				)
			)
		)
	)
	(zone
		(layers "In4.Cu" "In7.Cu")
		(hatch none 0.5)
		(connect_pads
			(clearance 0)
		)
		(min_thickness 0.25)
		(keepout
			(tracks not_allowed)
			(vias allowed)
			(pads allowed)
			(copperpour not_allowed)
			(footprints allowed)
		)
		(placement
			(enabled no)
			(sheetname "")
		)
		(fill yes
			(thermal_gap 0.5)
			(thermal_bridge_width 0.5)
			(island_removal_mode 0)
		)
		(polygon
			(pts
				(arc
					(start 132.310886 -81.788)
					(mid 130.532886 -81.788)
					(end 132.310886 -81.788)
				)
			)
		)
	)
	(zone
		(layers "In4.Cu" "In7.Cu")
		(hatch none 0.5)
		(connect_pads
			(clearance 0)
		)
		(min_thickness 0.25)
		(keepout
			(tracks not_allowed)
			(vias allowed)
			(pads allowed)
			(copperpour not_allowed)
			(footprints allowed)
		)
		(placement
			(enabled no)
			(sheetname "")
		)
		(fill yes
			(thermal_gap 0.5)
			(thermal_bridge_width 0.5)
			(island_removal_mode 0)
		)
		(polygon
			(pts
				(arc
					(start 129.491486 -81.788)
					(mid 127.713486 -81.788)
					(end 129.491486 -81.788)
				)
			)
		)
	)
	(zone
		(layer "In5.Cu")
		(hatch none 0.5)
		(connect_pads
			(clearance 0)
		)
		(min_thickness 0.25)
		(keepout
			(tracks not_allowed)
			(vias allowed)
			(pads allowed)
			(copperpour not_allowed)
			(footprints allowed)
		)
		(placement
			(enabled no)
			(sheetname "")
		)
		(fill
			(thermal_gap 0.5)
			(thermal_bridge_width 0.5)
			(island_removal_mode 0)
		)
		(polygon
			(pts
				(arc
					(start 375.405142 -3.432048)
					(mid 372.978934 -3.432048)
					(end 375.405142 -3.432048)
				)
			)
		)
	)
	(zone
		(layer "In5.Cu")
		(hatch none 0.5)
		(connect_pads
			(clearance 0)
		)
		(min_thickness 0.25)
		(keepout
			(tracks not_allowed)
			(vias allowed)
			(pads allowed)
			(copperpour not_allowed)
			(footprints allowed)
		)
		(placement
			(enabled no)
			(sheetname "")
		)
		(fill
			(thermal_gap 0.5)
			(thermal_bridge_width 0.5)
			(island_removal_mode 0)
		)
		(polygon
			(pts
				(arc
					(start 122.414284 -85.906864)
					(mid 120.636284 -85.906864)
					(end 122.414284 -85.906864)
				)
			)
		)
	)
	(zone
		(layer "In5.Cu")
		(hatch none 0.5)
		(connect_pads
			(clearance 0)
		)
		(min_thickness 0.25)
		(keepout
			(tracks not_allowed)
			(vias allowed)
			(pads allowed)
			(copperpour not_allowed)
			(footprints allowed)
		)
		(placement
			(enabled no)
			(sheetname "")
		)
		(fill
			(thermal_gap 0.5)
			(thermal_bridge_width 0.5)
			(island_removal_mode 0)
		)
		(polygon
			(pts
				(arc
					(start 41.822116 -157.846014)
					(mid 39.395908 -157.846014)
					(end 41.822116 -157.846014)
				)
			)
		)
	)
	(zone
		(layer "In5.Cu")
		(hatch none 0.5)
		(connect_pads
			(clearance 0)
		)
		(min_thickness 0.25)
		(keepout
			(tracks not_allowed)
			(vias allowed)
			(pads allowed)
			(copperpour not_allowed)
			(footprints allowed)
		)
		(placement
			(enabled no)
			(sheetname "")
		)
		(fill
			(thermal_gap 0.5)
			(thermal_bridge_width 0.5)
			(island_removal_mode 0)
		)
		(polygon
			(pts
				(arc
					(start 41.822116 -159.84601)
					(mid 39.395908 -159.84601)
					(end 41.822116 -159.84601)
				)
			)
		)
	)
	(zone
		(layer "In5.Cu")
		(hatch none 0.5)
		(connect_pads
			(clearance 0)
		)
		(min_thickness 0.25)
		(keepout
			(tracks not_allowed)
			(vias allowed)
			(pads allowed)
			(copperpour not_allowed)
			(footprints allowed)
		)
		(placement
			(enabled no)
			(sheetname "")
		)
		(fill
			(thermal_gap 0.5)
			(thermal_bridge_width 0.5)
			(island_removal_mode 0)
		)
		(polygon
			(pts
				(arc
					(start 261.91845 -54.61)
					(mid 260.14045 -54.61)
					(end 261.91845 -54.61)
				)
			)
		)
	)
	(zone
		(layer "In5.Cu")
		(hatch none 0.5)
		(connect_pads
			(clearance 0)
		)
		(min_thickness 0.25)
		(keepout
			(tracks not_allowed)
			(vias allowed)
			(pads allowed)
			(copperpour not_allowed)
			(footprints allowed)
		)
		(placement
			(enabled no)
			(sheetname "")
		)
		(fill
			(thermal_gap 0.5)
			(thermal_bridge_width 0.5)
			(island_removal_mode 0)
		)
		(polygon
			(pts
				(arc
					(start 377.818142 -1.527048)
					(mid 375.391934 -1.527048)
					(end 377.818142 -1.527048)
				)
			)
		)
	)
	(zone
		(layer "In5.Cu")
		(hatch none 0.5)
		(connect_pads
			(clearance 0)
		)
		(min_thickness 0.25)
		(keepout
			(tracks not_allowed)
			(vias allowed)
			(pads allowed)
			(copperpour not_allowed)
			(footprints allowed)
		)
		(placement
			(enabled no)
			(sheetname "")
		)
		(fill
			(thermal_gap 0.5)
			(thermal_bridge_width 0.5)
			(island_removal_mode 0)
		)
		(polygon
			(pts
				(arc
					(start 405.354282 -161.846006)
					(mid 402.928074 -161.846006)
					(end 405.354282 -161.846006)
				)
			)
		)
	)
	(zone
		(layer "In5.Cu")
		(hatch none 0.5)
		(connect_pads
			(clearance 0)
		)
		(min_thickness 0.25)
		(keepout
			(tracks not_allowed)
			(vias allowed)
			(pads allowed)
			(copperpour not_allowed)
			(footprints allowed)
		)
		(placement
			(enabled no)
			(sheetname "")
		)
		(fill
			(thermal_gap 0.5)
			(thermal_bridge_width 0.5)
			(island_removal_mode 0)
		)
		(polygon
			(pts
				(arc
					(start 71.095108 -167.972994)
					(mid 68.6689 -167.972994)
					(end 71.095108 -167.972994)
				)
			)
		)
	)
	(zone
		(layer "In5.Cu")
		(hatch none 0.5)
		(connect_pads
			(clearance 0)
		)
		(min_thickness 0.25)
		(keepout
			(tracks not_allowed)
			(vias allowed)
			(pads allowed)
			(copperpour not_allowed)
			(footprints allowed)
		)
		(placement
			(enabled no)
			(sheetname "")
		)
		(fill
			(thermal_gap 0.5)
			(thermal_bridge_width 0.5)
			(island_removal_mode 0)
		)
		(polygon
			(pts
				(arc
					(start 119.493284 -87.472012)
					(mid 119.679009 -87.536141)
					(end 119.874284 -87.557864)
				)
				(arc
					(start 119.874284 -87.557864)
					(mid 120.502902 -87.297482)
					(end 120.763284 -86.668864)
				)
				(arc
					(start 120.763284 -86.668864)
					(mid 120.741517 -86.473599)
					(end 120.677432 -86.287864)
				)
				(arc
					(start 120.677432 -86.287864)
					(mid 120.741561 -86.102139)
					(end 120.763284 -85.906864)
				)
				(arc
					(start 120.763284 -85.906864)
					(mid 120.502902 -85.278246)
					(end 119.874284 -85.017864)
				)
				(arc
					(start 119.874284 -85.017864)
					(mid 119.679019 -85.039631)
					(end 119.493284 -85.103716)
				)
				(arc
					(start 119.493284 -85.103716)
					(mid 119.307559 -85.039587)
					(end 119.112284 -85.017864)
				)
				(arc
					(start 119.112284 -85.017864)
					(mid 118.917019 -85.039631)
					(end 118.731284 -85.103716)
				)
				(arc
					(start 118.731284 -85.103716)
					(mid 118.545559 -85.039587)
					(end 118.350284 -85.017864)
				)
				(arc
					(start 118.350284 -85.017864)
					(mid 117.721666 -85.278246)
					(end 117.461284 -85.906864)
				)
				(arc
					(start 117.461284 -85.906864)
					(mid 117.483051 -86.102129)
					(end 117.547136 -86.287864)
				)
				(arc
					(start 117.547136 -86.287864)
					(mid 117.483007 -86.473589)
					(end 117.461284 -86.668864)
				)
				(arc
					(start 117.461284 -86.668864)
					(mid 117.721666 -87.297482)
					(end 118.350284 -87.557864)
				)
				(arc
					(start 118.350284 -87.557864)
					(mid 118.545549 -87.536097)
					(end 118.731284 -87.472012)
				)
				(arc
					(start 118.731284 -87.472012)
					(mid 118.917009 -87.536141)
					(end 119.112284 -87.557864)
				)
				(arc
					(start 119.112284 -87.557864)
					(mid 119.307549 -87.536097)
					(end 119.493284 -87.472012)
				)
			)
		)
	)
	(zone
		(layer "In5.Cu")
		(hatch none 0.5)
		(connect_pads
			(clearance 0)
		)
		(min_thickness 0.25)
		(keepout
			(tracks not_allowed)
			(vias allowed)
			(pads allowed)
			(copperpour not_allowed)
			(footprints allowed)
		)
		(placement
			(enabled no)
			(sheetname "")
		)
		(fill
			(thermal_gap 0.5)
			(thermal_bridge_width 0.5)
			(island_removal_mode 0)
		)
		(polygon
			(pts
				(arc
					(start 41.822116 -155.846018)
					(mid 39.395908 -155.846018)
					(end 41.822116 -155.846018)
				)
			)
		)
	)
	(zone
		(layer "In5.Cu")
		(hatch none 0.5)
		(connect_pads
			(clearance 0)
		)
		(min_thickness 0.25)
		(keepout
			(tracks not_allowed)
			(vias allowed)
			(pads allowed)
			(copperpour not_allowed)
			(footprints allowed)
		)
		(placement
			(enabled no)
			(sheetname "")
		)
		(fill
			(thermal_gap 0.5)
			(thermal_bridge_width 0.5)
			(island_removal_mode 0)
		)
		(polygon
			(pts
				(arc
					(start 405.354282 -155.846018)
					(mid 402.928074 -155.846018)
					(end 405.354282 -155.846018)
				)
			)
		)
	)
	(zone
		(layer "In5.Cu")
		(hatch none 0.5)
		(connect_pads
			(clearance 0)
		)
		(min_thickness 0.25)
		(keepout
			(tracks not_allowed)
			(vias allowed)
			(pads allowed)
			(copperpour not_allowed)
			(footprints allowed)
		)
		(placement
			(enabled no)
			(sheetname "")
		)
		(fill
			(thermal_gap 0.5)
			(thermal_bridge_width 0.5)
			(island_removal_mode 0)
		)
		(polygon
			(pts
				(arc
					(start 123.176284 -85.906864)
					(mid 121.398284 -85.906864)
					(end 123.176284 -85.906864)
				)
			)
		)
	)
	(zone
		(layer "In5.Cu")
		(hatch none 0.5)
		(connect_pads
			(clearance 0)
		)
		(min_thickness 0.25)
		(keepout
			(tracks not_allowed)
			(vias allowed)
			(pads allowed)
			(copperpour not_allowed)
			(footprints allowed)
		)
		(placement
			(enabled no)
			(sheetname "")
		)
		(fill
			(thermal_gap 0.5)
			(thermal_bridge_width 0.5)
			(island_removal_mode 0)
		)
		(polygon
			(pts
				(arc
					(start 405.354282 -165.845998)
					(mid 402.928074 -165.845998)
					(end 405.354282 -165.845998)
				)
			)
		)
	)
	(zone
		(layer "In5.Cu")
		(hatch none 0.5)
		(connect_pads
			(clearance 0)
		)
		(min_thickness 0.25)
		(keepout
			(tracks not_allowed)
			(vias allowed)
			(pads allowed)
			(copperpour not_allowed)
			(footprints allowed)
		)
		(placement
			(enabled no)
			(sheetname "")
		)
		(fill
			(thermal_gap 0.5)
			(thermal_bridge_width 0.5)
			(island_removal_mode 0)
		)
		(polygon
			(pts
				(arc
					(start 72.243188 -1.527048)
					(mid 69.81698 -1.527048)
					(end 72.243188 -1.527048)
				)
			)
		)
	)
	(zone
		(layer "In5.Cu")
		(hatch none 0.5)
		(connect_pads
			(clearance 0)
		)
		(min_thickness 0.25)
		(keepout
			(tracks not_allowed)
			(vias allowed)
			(pads allowed)
			(copperpour not_allowed)
			(footprints allowed)
		)
		(placement
			(enabled no)
			(sheetname "")
		)
		(fill
			(thermal_gap 0.5)
			(thermal_bridge_width 0.5)
			(island_removal_mode 0)
		)
		(polygon
			(pts
				(arc
					(start 377.16714 -167.591994)
					(mid 374.740932 -167.591994)
					(end 377.16714 -167.591994)
				)
			)
		)
	)
	(zone
		(layer "In5.Cu")
		(hatch none 0.5)
		(connect_pads
			(clearance 0)
		)
		(min_thickness 0.25)
		(keepout
			(tracks not_allowed)
			(vias allowed)
			(pads allowed)
			(copperpour not_allowed)
			(footprints allowed)
		)
		(placement
			(enabled no)
			(sheetname "")
		)
		(fill
			(thermal_gap 0.5)
			(thermal_bridge_width 0.5)
			(island_removal_mode 0)
		)
		(polygon
			(pts
				(arc
					(start 51.029108 -166.099998)
					(mid 48.6029 -166.099998)
					(end 51.029108 -166.099998)
				)
			)
		)
	)
	(zone
		(layer "In5.Cu")
		(hatch none 0.5)
		(connect_pads
			(clearance 0)
		)
		(min_thickness 0.25)
		(keepout
			(tracks not_allowed)
			(vias allowed)
			(pads allowed)
			(copperpour not_allowed)
			(footprints allowed)
		)
		(placement
			(enabled no)
			(sheetname "")
		)
		(fill
			(thermal_gap 0.5)
			(thermal_bridge_width 0.5)
			(island_removal_mode 0)
		)
		(polygon
			(pts
				(arc
					(start 365.35614 -167.972994)
					(mid 362.929932 -167.972994)
					(end 365.35614 -167.972994)
				)
			)
		)
	)
	(zone
		(layer "In5.Cu")
		(hatch none 0.5)
		(connect_pads
			(clearance 0)
		)
		(min_thickness 0.25)
		(keepout
			(tracks not_allowed)
			(vias allowed)
			(pads allowed)
			(copperpour not_allowed)
			(footprints allowed)
		)
		(placement
			(enabled no)
			(sheetname "")
		)
		(fill
			(thermal_gap 0.5)
			(thermal_bridge_width 0.5)
			(island_removal_mode 0)
		)
		(polygon
			(pts
				(arc
					(start 41.822116 -161.846006)
					(mid 39.395908 -161.846006)
					(end 41.822116 -161.846006)
				)
			)
		)
	)
	(zone
		(layer "In5.Cu")
		(hatch none 0.5)
		(connect_pads
			(clearance 0)
		)
		(min_thickness 0.25)
		(keepout
			(tracks not_allowed)
			(vias allowed)
			(pads allowed)
			(copperpour not_allowed)
			(footprints allowed)
		)
		(placement
			(enabled no)
			(sheetname "")
		)
		(fill
			(thermal_gap 0.5)
			(thermal_bridge_width 0.5)
			(island_removal_mode 0)
		)
		(polygon
			(pts
				(arc
					(start 371.32514 -165.718998)
					(mid 368.898932 -165.718998)
					(end 371.32514 -165.718998)
				)
			)
		)
	)
	(zone
		(layer "In5.Cu")
		(hatch none 0.5)
		(connect_pads
			(clearance 0)
		)
		(min_thickness 0.25)
		(keepout
			(tracks not_allowed)
			(vias allowed)
			(pads allowed)
			(copperpour not_allowed)
			(footprints allowed)
		)
		(placement
			(enabled no)
			(sheetname "")
		)
		(fill
			(thermal_gap 0.5)
			(thermal_bridge_width 0.5)
			(island_removal_mode 0)
		)
		(polygon
			(pts
				(arc
					(start 123.176284 -86.668864)
					(mid 121.398284 -86.668864)
					(end 123.176284 -86.668864)
				)
			)
		)
	)
	(zone
		(layer "In5.Cu")
		(hatch none 0.5)
		(connect_pads
			(clearance 0)
		)
		(min_thickness 0.25)
		(keepout
			(tracks not_allowed)
			(vias allowed)
			(pads allowed)
			(copperpour not_allowed)
			(footprints allowed)
		)
		(placement
			(enabled no)
			(sheetname "")
		)
		(fill
			(thermal_gap 0.5)
			(thermal_bridge_width 0.5)
			(island_removal_mode 0)
		)
		(polygon
			(pts
				(arc
					(start 391.51814 -165.845998)
					(mid 389.091932 -165.845998)
					(end 391.51814 -165.845998)
				)
			)
		)
	)
	(zone
		(layer "In5.Cu")
		(hatch none 0.5)
		(connect_pads
			(clearance 0)
		)
		(min_thickness 0.25)
		(keepout
			(tracks not_allowed)
			(vias allowed)
			(pads allowed)
			(copperpour not_allowed)
			(footprints allowed)
		)
		(placement
			(enabled no)
			(sheetname "")
		)
		(fill
			(thermal_gap 0.5)
			(thermal_bridge_width 0.5)
			(island_removal_mode 0)
		)
		(polygon
			(pts
				(arc
					(start 266.868402 -50.148998)
					(mid 265.090402 -50.148998)
					(end 266.868402 -50.148998)
				)
			)
		)
	)
	(zone
		(layer "In5.Cu")
		(hatch none 0.5)
		(connect_pads
			(clearance 0)
		)
		(min_thickness 0.25)
		(keepout
			(tracks not_allowed)
			(vias allowed)
			(pads allowed)
			(copperpour not_allowed)
			(footprints allowed)
		)
		(placement
			(enabled no)
			(sheetname "")
		)
		(fill
			(thermal_gap 0.5)
			(thermal_bridge_width 0.5)
			(island_removal_mode 0)
		)
		(polygon
			(pts
				(arc
					(start 116.699284 -86.668864)
					(mid 114.921284 -86.668864)
					(end 116.699284 -86.668864)
				)
			)
		)
	)
	(zone
		(layer "In5.Cu")
		(hatch none 0.5)
		(connect_pads
			(clearance 0)
		)
		(min_thickness 0.25)
		(keepout
			(tracks not_allowed)
			(vias allowed)
			(pads allowed)
			(copperpour not_allowed)
			(footprints allowed)
		)
		(placement
			(enabled no)
			(sheetname "")
		)
		(fill
			(thermal_gap 0.5)
			(thermal_bridge_width 0.5)
			(island_removal_mode 0)
		)
		(polygon
			(pts
				(arc
					(start 365.35614 -165.972998)
					(mid 362.929932 -165.972998)
					(end 365.35614 -165.972998)
				)
			)
		)
	)
	(zone
		(layer "In5.Cu")
		(hatch none 0.5)
		(connect_pads
			(clearance 0)
		)
		(min_thickness 0.25)
		(keepout
			(tracks not_allowed)
			(vias allowed)
			(pads allowed)
			(copperpour not_allowed)
			(footprints allowed)
		)
		(placement
			(enabled no)
			(sheetname "")
		)
		(fill
			(thermal_gap 0.5)
			(thermal_bridge_width 0.5)
			(island_removal_mode 0)
		)
		(polygon
			(pts
				(arc
					(start 117.461284 -86.668864)
					(mid 115.683284 -86.668864)
					(end 117.461284 -86.668864)
				)
			)
		)
	)
	(zone
		(layer "In5.Cu")
		(hatch none 0.5)
		(connect_pads
			(clearance 0)
		)
		(min_thickness 0.25)
		(keepout
			(tracks not_allowed)
			(vias allowed)
			(pads allowed)
			(copperpour not_allowed)
			(footprints allowed)
		)
		(placement
			(enabled no)
			(sheetname "")
		)
		(fill
			(thermal_gap 0.5)
			(thermal_bridge_width 0.5)
			(island_removal_mode 0)
		)
		(polygon
			(pts
				(arc
					(start 77.064108 -165.718998)
					(mid 74.6379 -165.718998)
					(end 77.064108 -165.718998)
				)
			)
		)
	)
	(zone
		(layer "In5.Cu")
		(hatch none 0.5)
		(connect_pads
			(clearance 0)
		)
		(min_thickness 0.25)
		(keepout
			(tracks not_allowed)
			(vias allowed)
			(pads allowed)
			(copperpour not_allowed)
			(footprints allowed)
		)
		(placement
			(enabled no)
			(sheetname "")
		)
		(fill
			(thermal_gap 0.5)
			(thermal_bridge_width 0.5)
			(island_removal_mode 0)
		)
		(polygon
			(pts
				(arc
					(start 72.243188 -4.448048)
					(mid 69.81698 -4.448048)
					(end 72.243188 -4.448048)
				)
			)
		)
	)
	(zone
		(layer "In5.Cu")
		(hatch none 0.5)
		(connect_pads
			(clearance 0)
		)
		(min_thickness 0.25)
		(keepout
			(tracks not_allowed)
			(vias allowed)
			(pads allowed)
			(copperpour not_allowed)
			(footprints allowed)
		)
		(placement
			(enabled no)
			(sheetname "")
		)
		(fill
			(thermal_gap 0.5)
			(thermal_bridge_width 0.5)
			(island_removal_mode 0)
		)
		(polygon
			(pts
				(arc
					(start 405.354282 -157.846014)
					(mid 402.928074 -157.846014)
					(end 405.354282 -157.846014)
				)
			)
		)
	)
	(zone
		(layer "In5.Cu")
		(hatch none 0.5)
		(connect_pads
			(clearance 0)
		)
		(min_thickness 0.25)
		(keepout
			(tracks not_allowed)
			(vias allowed)
			(pads allowed)
			(copperpour not_allowed)
			(footprints allowed)
		)
		(placement
			(enabled no)
			(sheetname "")
		)
		(fill
			(thermal_gap 0.5)
			(thermal_bridge_width 0.5)
			(island_removal_mode 0)
		)
		(polygon
			(pts
				(arc
					(start 376.675142 -1.654048)
					(mid 374.248934 -1.654048)
					(end 376.675142 -1.654048)
				)
			)
		)
	)
	(zone
		(layer "In5.Cu")
		(hatch none 0.5)
		(connect_pads
			(clearance 0)
		)
		(min_thickness 0.25)
		(keepout
			(tracks not_allowed)
			(vias allowed)
			(pads allowed)
			(copperpour not_allowed)
			(footprints allowed)
		)
		(placement
			(enabled no)
			(sheetname "")
		)
		(fill
			(thermal_gap 0.5)
			(thermal_bridge_width 0.5)
			(island_removal_mode 0)
		)
		(polygon
			(pts
				(arc
					(start 406.751282 -169.97299)
					(mid 404.325074 -169.97299)
					(end 406.751282 -169.97299)
				)
			)
		)
	)
	(zone
		(layer "In5.Cu")
		(hatch none 0.5)
		(connect_pads
			(clearance 0)
		)
		(min_thickness 0.25)
		(keepout
			(tracks not_allowed)
			(vias allowed)
			(pads allowed)
			(copperpour not_allowed)
			(footprints allowed)
		)
		(placement
			(enabled no)
			(sheetname "")
		)
		(fill
			(thermal_gap 0.5)
			(thermal_bridge_width 0.5)
			(island_removal_mode 0)
		)
		(polygon
			(pts
				(arc
					(start 65.126108 -168.099994)
					(mid 62.6999 -168.099994)
					(end 65.126108 -168.099994)
				)
			)
		)
	)
	(zone
		(layer "In5.Cu")
		(hatch none 0.5)
		(connect_pads
			(clearance 0)
		)
		(min_thickness 0.25)
		(keepout
			(tracks not_allowed)
			(vias allowed)
			(pads allowed)
			(copperpour not_allowed)
			(footprints allowed)
		)
		(placement
			(enabled no)
			(sheetname "")
		)
		(fill
			(thermal_gap 0.5)
			(thermal_bridge_width 0.5)
			(island_removal_mode 0)
		)
		(polygon
			(pts
				(arc
					(start 117.461284 -85.906864)
					(mid 115.683284 -85.906864)
					(end 117.461284 -85.906864)
				)
			)
		)
	)
	(zone
		(layer "In5.Cu")
		(hatch none 0.5)
		(connect_pads
			(clearance 0)
		)
		(min_thickness 0.25)
		(keepout
			(tracks not_allowed)
			(vias allowed)
			(pads allowed)
			(copperpour not_allowed)
			(footprints allowed)
		)
		(placement
			(enabled no)
			(sheetname "")
		)
		(fill
			(thermal_gap 0.5)
			(thermal_bridge_width 0.5)
			(island_removal_mode 0)
		)
		(polygon
			(pts
				(arc
					(start 75.545188 -1.654048)
					(mid 73.11898 -1.654048)
					(end 75.545188 -1.654048)
				)
			)
		)
	)
	(zone
		(layer "In5.Cu")
		(hatch none 0.5)
		(connect_pads
			(clearance 0)
		)
		(min_thickness 0.25)
		(keepout
			(tracks not_allowed)
			(vias allowed)
			(pads allowed)
			(copperpour not_allowed)
			(footprints allowed)
		)
		(placement
			(enabled no)
			(sheetname "")
		)
		(fill
			(thermal_gap 0.5)
			(thermal_bridge_width 0.5)
			(island_removal_mode 0)
		)
		(polygon
			(pts
				(arc
					(start 385.42214 -167.718994)
					(mid 382.995932 -167.718994)
					(end 385.42214 -167.718994)
				)
			)
		)
	)
	(zone
		(layer "In5.Cu")
		(hatch none 0.5)
		(connect_pads
			(clearance 0)
		)
		(min_thickness 0.25)
		(keepout
			(tracks not_allowed)
			(vias allowed)
			(pads allowed)
			(copperpour not_allowed)
			(footprints allowed)
		)
		(placement
			(enabled no)
			(sheetname "")
		)
		(fill
			(thermal_gap 0.5)
			(thermal_bridge_width 0.5)
			(island_removal_mode 0)
		)
		(polygon
			(pts
				(arc
					(start 56.871108 -165.718998)
					(mid 54.4449 -165.718998)
					(end 56.871108 -165.718998)
				)
			)
		)
	)
	(zone
		(layer "In5.Cu")
		(hatch none 0.5)
		(connect_pads
			(clearance 0)
		)
		(min_thickness 0.25)
		(keepout
			(tracks not_allowed)
			(vias allowed)
			(pads allowed)
			(copperpour not_allowed)
			(footprints allowed)
		)
		(placement
			(enabled no)
			(sheetname "")
		)
		(fill
			(thermal_gap 0.5)
			(thermal_bridge_width 0.5)
			(island_removal_mode 0)
		)
		(polygon
			(pts
				(arc
					(start 405.227282 -169.97299)
					(mid 402.801074 -169.97299)
					(end 405.227282 -169.97299)
				)
			)
		)
	)
	(zone
		(layer "In5.Cu")
		(hatch none 0.5)
		(connect_pads
			(clearance 0)
		)
		(min_thickness 0.25)
		(keepout
			(tracks not_allowed)
			(vias allowed)
			(pads allowed)
			(copperpour not_allowed)
			(footprints allowed)
		)
		(placement
			(enabled no)
			(sheetname "")
		)
		(fill
			(thermal_gap 0.5)
			(thermal_bridge_width 0.5)
			(island_removal_mode 0)
		)
		(polygon
			(pts
				(arc
					(start 67.507104 -169.926)
					(mid 65.080896 -169.926)
					(end 67.507104 -169.926)
				)
			)
		)
	)
	(zone
		(layer "In5.Cu")
		(hatch none 0.5)
		(connect_pads
			(clearance 0)
		)
		(min_thickness 0.25)
		(keepout
			(tracks not_allowed)
			(vias allowed)
			(pads allowed)
			(copperpour not_allowed)
			(footprints allowed)
		)
		(placement
			(enabled no)
			(sheetname "")
		)
		(fill
			(thermal_gap 0.5)
			(thermal_bridge_width 0.5)
			(island_removal_mode 0)
		)
		(polygon
			(pts
				(arc
					(start 41.822116 -153.846022)
					(mid 39.395908 -153.846022)
					(end 41.822116 -153.846022)
				)
			)
		)
	)
	(zone
		(layer "In5.Cu")
		(hatch none 0.5)
		(connect_pads
			(clearance 0)
		)
		(min_thickness 0.25)
		(keepout
			(tracks not_allowed)
			(vias allowed)
			(pads allowed)
			(copperpour not_allowed)
			(footprints allowed)
		)
		(placement
			(enabled no)
			(sheetname "")
		)
		(fill
			(thermal_gap 0.5)
			(thermal_bridge_width 0.5)
			(island_removal_mode 0)
		)
		(polygon
			(pts
				(arc
					(start 391.51814 -167.845994)
					(mid 389.091932 -167.845994)
					(end 391.51814 -167.845994)
				)
			)
		)
	)
	(zone
		(layer "In5.Cu")
		(hatch none 0.5)
		(connect_pads
			(clearance 0)
		)
		(min_thickness 0.25)
		(keepout
			(tracks not_allowed)
			(vias allowed)
			(pads allowed)
			(copperpour not_allowed)
			(footprints allowed)
		)
		(placement
			(enabled no)
			(sheetname "")
		)
		(fill
			(thermal_gap 0.5)
			(thermal_bridge_width 0.5)
			(island_removal_mode 0)
		)
		(polygon
			(pts
				(arc
					(start 71.095108 -165.972998)
					(mid 68.6689 -165.972998)
					(end 71.095108 -165.972998)
				)
			)
		)
	)
	(zone
		(layer "In5.Cu")
		(hatch none 0.5)
		(connect_pads
			(clearance 0)
		)
		(min_thickness 0.25)
		(keepout
			(tracks not_allowed)
			(vias allowed)
			(pads allowed)
			(copperpour not_allowed)
			(footprints allowed)
		)
		(placement
			(enabled no)
			(sheetname "")
		)
		(fill
			(thermal_gap 0.5)
			(thermal_bridge_width 0.5)
			(island_removal_mode 0)
		)
		(polygon
			(pts
				(arc
					(start 65.126108 -166.099998)
					(mid 62.6999 -166.099998)
					(end 65.126108 -166.099998)
				)
			)
		)
	)
	(zone
		(layer "In5.Cu")
		(hatch none 0.5)
		(connect_pads
			(clearance 0)
		)
		(min_thickness 0.25)
		(keepout
			(tracks not_allowed)
			(vias allowed)
			(pads allowed)
			(copperpour not_allowed)
			(footprints allowed)
		)
		(placement
			(enabled no)
			(sheetname "")
		)
		(fill
			(thermal_gap 0.5)
			(thermal_bridge_width 0.5)
			(island_removal_mode 0)
		)
		(polygon
			(pts
				(arc
					(start 69.361304 -170.1038)
					(mid 66.935096 -170.1038)
					(end 69.361304 -170.1038)
				)
			)
		)
	)
	(zone
		(layer "In5.Cu")
		(hatch none 0.5)
		(connect_pads
			(clearance 0)
		)
		(min_thickness 0.25)
		(keepout
			(tracks not_allowed)
			(vias allowed)
			(pads allowed)
			(copperpour not_allowed)
			(footprints allowed)
		)
		(placement
			(enabled no)
			(sheetname "")
		)
		(fill
			(thermal_gap 0.5)
			(thermal_bridge_width 0.5)
			(island_removal_mode 0)
		)
		(polygon
			(pts
				(arc
					(start 371.32514 -167.718994)
					(mid 368.898932 -167.718994)
					(end 371.32514 -167.718994)
				)
			)
		)
	)
	(zone
		(layer "In5.Cu")
		(hatch none 0.5)
		(connect_pads
			(clearance 0)
		)
		(min_thickness 0.25)
		(keepout
			(tracks not_allowed)
			(vias allowed)
			(pads allowed)
			(copperpour not_allowed)
			(footprints allowed)
		)
		(placement
			(enabled no)
			(sheetname "")
		)
		(fill
			(thermal_gap 0.5)
			(thermal_bridge_width 0.5)
			(island_removal_mode 0)
		)
		(polygon
			(pts
				(arc
					(start 221.623382 -7.983728)
					(mid 219.845382 -7.983728)
					(end 221.623382 -7.983728)
				)
			)
		)
	)
	(zone
		(layer "In5.Cu")
		(hatch none 0.5)
		(connect_pads
			(clearance 0)
		)
		(min_thickness 0.25)
		(keepout
			(tracks not_allowed)
			(vias allowed)
			(pads allowed)
			(copperpour not_allowed)
			(footprints allowed)
		)
		(placement
			(enabled no)
			(sheetname "")
		)
		(fill
			(thermal_gap 0.5)
			(thermal_bridge_width 0.5)
			(island_removal_mode 0)
		)
		(polygon
			(pts
				(arc
					(start 405.354282 -153.846022)
					(mid 402.928074 -153.846022)
					(end 405.354282 -153.846022)
				)
			)
		)
	)
	(zone
		(layer "In5.Cu")
		(hatch none 0.5)
		(connect_pads
			(clearance 0)
		)
		(min_thickness 0.25)
		(keepout
			(tracks not_allowed)
			(vias allowed)
			(pads allowed)
			(copperpour not_allowed)
			(footprints allowed)
		)
		(placement
			(enabled no)
			(sheetname "")
		)
		(fill
			(thermal_gap 0.5)
			(thermal_bridge_width 0.5)
			(island_removal_mode 0)
		)
		(polygon
			(pts
				(arc
					(start 377.16714 -165.591998)
					(mid 374.740932 -165.591998)
					(end 377.16714 -165.591998)
				)
			)
		)
	)
	(zone
		(layer "In5.Cu")
		(hatch none 0.5)
		(connect_pads
			(clearance 0)
		)
		(min_thickness 0.25)
		(keepout
			(tracks not_allowed)
			(vias allowed)
			(pads allowed)
			(copperpour not_allowed)
			(footprints allowed)
		)
		(placement
			(enabled no)
			(sheetname "")
		)
		(fill
			(thermal_gap 0.5)
			(thermal_bridge_width 0.5)
			(island_removal_mode 0)
		)
		(polygon
			(pts
				(arc
					(start 263.661398 -51.164998)
					(mid 261.883398 -51.164998)
					(end 263.661398 -51.164998)
				)
			)
		)
	)
	(zone
		(layer "In5.Cu")
		(hatch none 0.5)
		(connect_pads
			(clearance 0)
		)
		(min_thickness 0.25)
		(keepout
			(tracks not_allowed)
			(vias allowed)
			(pads allowed)
			(copperpour not_allowed)
			(footprints allowed)
		)
		(placement
			(enabled no)
			(sheetname "")
		)
		(fill
			(thermal_gap 0.5)
			(thermal_bridge_width 0.5)
			(island_removal_mode 0)
		)
		(polygon
			(pts
				(arc
					(start 122.414284 -86.668864)
					(mid 120.636284 -86.668864)
					(end 122.414284 -86.668864)
				)
			)
		)
	)
	(zone
		(layer "In5.Cu")
		(hatch none 0.5)
		(connect_pads
			(clearance 0)
		)
		(min_thickness 0.25)
		(keepout
			(tracks not_allowed)
			(vias allowed)
			(pads allowed)
			(copperpour not_allowed)
			(footprints allowed)
		)
		(placement
			(enabled no)
			(sheetname "")
		)
		(fill
			(thermal_gap 0.5)
			(thermal_bridge_width 0.5)
			(island_removal_mode 0)
		)
		(polygon
			(pts
				(arc
					(start 51.029108 -168.099994)
					(mid 48.6029 -168.099994)
					(end 51.029108 -168.099994)
				)
			)
		)
	)
	(zone
		(layer "In5.Cu")
		(hatch none 0.5)
		(connect_pads
			(clearance 0)
		)
		(min_thickness 0.25)
		(keepout
			(tracks not_allowed)
			(vias allowed)
			(pads allowed)
			(copperpour not_allowed)
			(footprints allowed)
		)
		(placement
			(enabled no)
			(sheetname "")
		)
		(fill
			(thermal_gap 0.5)
			(thermal_bridge_width 0.5)
			(island_removal_mode 0)
		)
		(polygon
			(pts
				(arc
					(start 405.354282 -167.845994)
					(mid 402.928074 -167.845994)
					(end 405.354282 -167.845994)
				)
			)
		)
	)
	(zone
		(layer "In5.Cu")
		(hatch none 0.5)
		(connect_pads
			(clearance 0)
		)
		(min_thickness 0.25)
		(keepout
			(tracks not_allowed)
			(vias allowed)
			(pads allowed)
			(copperpour not_allowed)
			(footprints allowed)
		)
		(placement
			(enabled no)
			(sheetname "")
		)
		(fill
			(thermal_gap 0.5)
			(thermal_bridge_width 0.5)
			(island_removal_mode 0)
		)
		(polygon
			(pts
				(arc
					(start 374.516142 -4.575048)
					(mid 372.089934 -4.575048)
					(end 374.516142 -4.575048)
				)
			)
		)
	)
	(zone
		(layer "In5.Cu")
		(hatch none 0.5)
		(connect_pads
			(clearance 0)
		)
		(min_thickness 0.25)
		(keepout
			(tracks not_allowed)
			(vias allowed)
			(pads allowed)
			(copperpour not_allowed)
			(footprints allowed)
		)
		(placement
			(enabled no)
			(sheetname "")
		)
		(fill
			(thermal_gap 0.5)
			(thermal_bridge_width 0.5)
			(island_removal_mode 0)
		)
		(polygon
			(pts
				(arc
					(start 77.514704 -169.9006)
					(mid 75.088496 -169.9006)
					(end 77.514704 -169.9006)
				)
			)
		)
	)
	(zone
		(layer "In5.Cu")
		(hatch none 0.5)
		(connect_pads
			(clearance 0)
		)
		(min_thickness 0.25)
		(keepout
			(tracks not_allowed)
			(vias allowed)
			(pads allowed)
			(copperpour not_allowed)
			(footprints allowed)
		)
		(placement
			(enabled no)
			(sheetname "")
		)
		(fill
			(thermal_gap 0.5)
			(thermal_bridge_width 0.5)
			(island_removal_mode 0)
		)
		(polygon
			(pts
				(arc
					(start 41.822116 -165.845998)
					(mid 39.395908 -165.845998)
					(end 41.822116 -165.845998)
				)
			)
		)
	)
	(zone
		(layer "In5.Cu")
		(hatch none 0.5)
		(connect_pads
			(clearance 0)
		)
		(min_thickness 0.25)
		(keepout
			(tracks not_allowed)
			(vias allowed)
			(pads allowed)
			(copperpour not_allowed)
			(footprints allowed)
		)
		(placement
			(enabled no)
			(sheetname "")
		)
		(fill
			(thermal_gap 0.5)
			(thermal_bridge_width 0.5)
			(island_removal_mode 0)
		)
		(polygon
			(pts
				(arc
					(start 73.513188 -3.432048)
					(mid 71.08698 -3.432048)
					(end 73.513188 -3.432048)
				)
			)
		)
	)
	(zone
		(layer "In5.Cu")
		(hatch none 0.5)
		(connect_pads
			(clearance 0)
		)
		(min_thickness 0.25)
		(keepout
			(tracks not_allowed)
			(vias allowed)
			(pads allowed)
			(copperpour not_allowed)
			(footprints allowed)
		)
		(placement
			(enabled no)
			(sheetname "")
		)
		(fill
			(thermal_gap 0.5)
			(thermal_bridge_width 0.5)
			(island_removal_mode 0)
		)
		(polygon
			(pts
				(arc
					(start 116.699284 -85.906864)
					(mid 114.921284 -85.906864)
					(end 116.699284 -85.906864)
				)
			)
		)
	)
	(zone
		(layer "In5.Cu")
		(hatch none 0.5)
		(connect_pads
			(clearance 0)
		)
		(min_thickness 0.25)
		(keepout
			(tracks not_allowed)
			(vias allowed)
			(pads allowed)
			(copperpour not_allowed)
			(footprints allowed)
		)
		(placement
			(enabled no)
			(sheetname "")
		)
		(fill
			(thermal_gap 0.5)
			(thermal_bridge_width 0.5)
			(island_removal_mode 0)
		)
		(polygon
			(pts
				(arc
					(start 68.548504 -169.9768)
					(mid 66.122296 -169.9768)
					(end 68.548504 -169.9768)
				)
			)
		)
	)
	(zone
		(layer "In5.Cu")
		(hatch none 0.5)
		(connect_pads
			(clearance 0)
		)
		(min_thickness 0.25)
		(keepout
			(tracks not_allowed)
			(vias allowed)
			(pads allowed)
			(copperpour not_allowed)
			(footprints allowed)
		)
		(placement
			(enabled no)
			(sheetname "")
		)
		(fill
			(thermal_gap 0.5)
			(thermal_bridge_width 0.5)
			(island_removal_mode 0)
		)
		(polygon
			(pts
				(arc
					(start 41.822116 -163.846002)
					(mid 39.395908 -163.846002)
					(end 41.822116 -163.846002)
				)
			)
		)
	)
	(zone
		(layer "In5.Cu")
		(hatch none 0.5)
		(connect_pads
			(clearance 0)
		)
		(min_thickness 0.25)
		(keepout
			(tracks not_allowed)
			(vias allowed)
			(pads allowed)
			(copperpour not_allowed)
			(footprints allowed)
		)
		(placement
			(enabled no)
			(sheetname "")
		)
		(fill
			(thermal_gap 0.5)
			(thermal_bridge_width 0.5)
			(island_removal_mode 0)
		)
		(polygon
			(pts
				(arc
					(start 123.938284 -85.906864)
					(mid 122.160284 -85.906864)
					(end 123.938284 -85.906864)
				)
			)
		)
	)
	(zone
		(layer "In5.Cu")
		(hatch none 0.5)
		(connect_pads
			(clearance 0)
		)
		(min_thickness 0.25)
		(keepout
			(tracks not_allowed)
			(vias allowed)
			(pads allowed)
			(copperpour not_allowed)
			(footprints allowed)
		)
		(placement
			(enabled no)
			(sheetname "")
		)
		(fill
			(thermal_gap 0.5)
			(thermal_bridge_width 0.5)
			(island_removal_mode 0)
		)
		(polygon
			(pts
				(arc
					(start 405.354282 -159.84601)
					(mid 402.928074 -159.84601)
					(end 405.354282 -159.84601)
				)
			)
		)
	)
	(zone
		(layer "In5.Cu")
		(hatch none 0.5)
		(connect_pads
			(clearance 0)
		)
		(min_thickness 0.25)
		(keepout
			(tracks not_allowed)
			(vias allowed)
			(pads allowed)
			(copperpour not_allowed)
			(footprints allowed)
		)
		(placement
			(enabled no)
			(sheetname "")
		)
		(fill
			(thermal_gap 0.5)
			(thermal_bridge_width 0.5)
			(island_removal_mode 0)
		)
		(polygon
			(pts
				(arc
					(start 41.822116 -167.845994)
					(mid 39.395908 -167.845994)
					(end 41.822116 -167.845994)
				)
			)
		)
	)
	(zone
		(layer "In5.Cu")
		(hatch none 0.5)
		(connect_pads
			(clearance 0)
		)
		(min_thickness 0.25)
		(keepout
			(tracks not_allowed)
			(vias allowed)
			(pads allowed)
			(copperpour not_allowed)
			(footprints allowed)
		)
		(placement
			(enabled no)
			(sheetname "")
		)
		(fill
			(thermal_gap 0.5)
			(thermal_bridge_width 0.5)
			(island_removal_mode 0)
		)
		(polygon
			(pts
				(arc
					(start 385.42214 -165.718998)
					(mid 382.995932 -165.718998)
					(end 385.42214 -165.718998)
				)
			)
		)
	)
	(zone
		(layer "In5.Cu")
		(hatch none 0.5)
		(connect_pads
			(clearance 0)
		)
		(min_thickness 0.25)
		(keepout
			(tracks not_allowed)
			(vias allowed)
			(pads allowed)
			(copperpour not_allowed)
			(footprints allowed)
		)
		(placement
			(enabled no)
			(sheetname "")
		)
		(fill
			(thermal_gap 0.5)
			(thermal_bridge_width 0.5)
			(island_removal_mode 0)
		)
		(polygon
			(pts
				(arc
					(start 262.5344 -52.705)
					(mid 260.7564 -52.705)
					(end 262.5344 -52.705)
				)
			)
		)
	)
	(zone
		(layer "In5.Cu")
		(hatch none 0.5)
		(connect_pads
			(clearance 0)
		)
		(min_thickness 0.25)
		(keepout
			(tracks not_allowed)
			(vias allowed)
			(pads allowed)
			(copperpour not_allowed)
			(footprints allowed)
		)
		(placement
			(enabled no)
			(sheetname "")
		)
		(fill
			(thermal_gap 0.5)
			(thermal_bridge_width 0.5)
			(island_removal_mode 0)
		)
		(polygon
			(pts
				(arc
					(start 56.871108 -167.718994)
					(mid 54.4449 -167.718994)
					(end 56.871108 -167.718994)
				)
			)
		)
	)
	(zone
		(layer "In5.Cu")
		(hatch none 0.5)
		(connect_pads
			(clearance 0)
		)
		(min_thickness 0.25)
		(keepout
			(tracks not_allowed)
			(vias allowed)
			(pads allowed)
			(copperpour not_allowed)
			(footprints allowed)
		)
		(placement
			(enabled no)
			(sheetname "")
		)
		(fill
			(thermal_gap 0.5)
			(thermal_bridge_width 0.5)
			(island_removal_mode 0)
		)
		(polygon
			(pts
				(arc
					(start 123.938284 -86.668864)
					(mid 122.160284 -86.668864)
					(end 123.938284 -86.668864)
				)
			)
		)
	)
	(zone
		(layer "In5.Cu")
		(hatch none 0.5)
		(connect_pads
			(clearance 0)
		)
		(min_thickness 0.25)
		(keepout
			(tracks not_allowed)
			(vias allowed)
			(pads allowed)
			(copperpour not_allowed)
			(footprints allowed)
		)
		(placement
			(enabled no)
			(sheetname "")
		)
		(fill
			(thermal_gap 0.5)
			(thermal_bridge_width 0.5)
			(island_removal_mode 0)
		)
		(polygon
			(pts
				(arc
					(start 77.064108 -167.718994)
					(mid 74.6379 -167.718994)
					(end 77.064108 -167.718994)
				)
			)
		)
	)
	(zone
		(layer "In5.Cu")
		(hatch none 0.5)
		(connect_pads
			(clearance 0)
		)
		(min_thickness 0.25)
		(keepout
			(tracks not_allowed)
			(vias allowed)
			(pads allowed)
			(copperpour not_allowed)
			(footprints allowed)
		)
		(placement
			(enabled no)
			(sheetname "")
		)
		(fill
			(thermal_gap 0.5)
			(thermal_bridge_width 0.5)
			(island_removal_mode 0)
		)
		(polygon
			(pts
				(arc
					(start 74.275188 -1.781048)
					(mid 71.84898 -1.781048)
					(end 74.275188 -1.781048)
				)
			)
		)
	)
	(zone
		(layer "In5.Cu")
		(hatch none 0.5)
		(connect_pads
			(clearance 0)
		)
		(min_thickness 0.25)
		(keepout
			(tracks not_allowed)
			(vias allowed)
			(pads allowed)
			(copperpour not_allowed)
			(footprints allowed)
		)
		(placement
			(enabled no)
			(sheetname "")
		)
		(fill
			(thermal_gap 0.5)
			(thermal_bridge_width 0.5)
			(island_removal_mode 0)
		)
		(polygon
			(pts
				(arc
					(start 261.56158 -77.147166)
					(mid 259.78358 -77.147166)
					(end 261.56158 -77.147166)
				)
			)
		)
	)
	(zone
		(layer "In5.Cu")
		(hatch none 0.5)
		(connect_pads
			(clearance 0)
		)
		(min_thickness 0.25)
		(keepout
			(tracks not_allowed)
			(vias allowed)
			(pads allowed)
			(copperpour not_allowed)
			(footprints allowed)
		)
		(placement
			(enabled no)
			(sheetname "")
		)
		(fill
			(thermal_gap 0.5)
			(thermal_bridge_width 0.5)
			(island_removal_mode 0)
		)
		(polygon
			(pts
				(arc
					(start 405.354282 -163.846002)
					(mid 402.928074 -163.846002)
					(end 405.354282 -163.846002)
				)
			)
		)
	)
	(zone
		(layer "In7.Cu")
		(hatch none 0.5)
		(connect_pads
			(clearance 0)
		)
		(min_thickness 0.25)
		(keepout
			(tracks not_allowed)
			(vias allowed)
			(pads allowed)
			(copperpour not_allowed)
			(footprints allowed)
		)
		(placement
			(enabled no)
			(sheetname "")
		)
		(fill
			(thermal_gap 0.5)
			(thermal_bridge_width 0.5)
			(island_removal_mode 0)
		)
		(polygon
			(pts
				(arc
					(start 451.864984 -29.500322)
					(mid 457.000102 -34.63544)
					(end 462.134966 -29.500322)
				)
				(arc
					(start 462.134966 -24.500332)
					(mid 457.000102 -19.365468)
					(end 451.864984 -24.500332)
				)
			)
		)
	)
	(zone
		(layer "In7.Cu")
		(hatch none 0.5)
		(connect_pads
			(clearance 0)
		)
		(min_thickness 0.25)
		(keepout
			(tracks not_allowed)
			(vias allowed)
			(pads allowed)
			(copperpour not_allowed)
			(footprints allowed)
		)
		(placement
			(enabled no)
			(sheetname "")
		)
		(fill
			(thermal_gap 0.5)
			(thermal_bridge_width 0.5)
			(island_removal_mode 0)
		)
		(polygon
			(pts
				(arc
					(start 244.865144 -92.499942)
					(mid 250.000262 -97.63506)
					(end 255.135126 -92.499942)
				)
				(arc
					(start 255.135126 -87.499952)
					(mid 250.000262 -82.365088)
					(end 244.865144 -87.499952)
				)
			)
		)
	)
	(zone
		(layer "In7.Cu")
		(hatch none 0.5)
		(connect_pads
			(clearance 0)
		)
		(min_thickness 0.25)
		(keepout
			(tracks not_allowed)
			(vias allowed)
			(pads allowed)
			(copperpour not_allowed)
			(footprints allowed)
		)
		(placement
			(enabled no)
			(sheetname "")
		)
		(fill
			(thermal_gap 0.5)
			(thermal_bridge_width 0.5)
			(island_removal_mode 0)
		)
		(polygon
			(pts
				(arc
					(start 452.499984 -24.500332)
					(mid 457.000102 -20.000214)
					(end 461.499966 -24.500332)
				)
				(arc
					(start 461.499966 -29.500322)
					(mid 457.000102 -34.000186)
					(end 452.499984 -29.500322)
				)
			)
		)
	)
	(zone
		(layer "In7.Cu")
		(hatch none 0.5)
		(connect_pads
			(clearance 0)
		)
		(min_thickness 0.25)
		(keepout
			(tracks not_allowed)
			(vias allowed)
			(pads allowed)
			(copperpour not_allowed)
			(footprints allowed)
		)
		(placement
			(enabled no)
			(sheetname "")
		)
		(fill
			(thermal_gap 0.5)
			(thermal_bridge_width 0.5)
			(island_removal_mode 0)
		)
		(polygon
			(pts
				(arc
					(start 422.865296 -9.500108)
					(mid 428.000414 -14.635226)
					(end 433.135278 -9.500108)
				)
				(arc
					(start 433.135278 -4.500118)
					(mid 428.000414 0.634746)
					(end 422.865296 -4.500118)
				)
			)
		)
	)
	(zone
		(layer "In7.Cu")
		(hatch none 0.5)
		(connect_pads
			(clearance 0)
		)
		(min_thickness 0.25)
		(keepout
			(tracks allowed)
			(vias allowed)
			(pads allowed)
			(copperpour allowed)
			(footprints allowed)
		)
		(placement
			(enabled no)
			(sheetname "")
		)
		(fill
			(thermal_gap 0.5)
			(thermal_bridge_width 0.5)
			(island_removal_mode 0)
		)
		(polygon
			(pts
				(xy 264.8204 -83.185) (xy 320.4464 -83.185) (xy 320.4464 -80.6704) (xy 320.4718 -80.645) (xy 267.2334 -80.645)
				(xy 266.4714 -79.883) (xy 266.4714 -70.104) (xy 265.9634 -69.596) (xy 264.0584 -69.596) (xy 263.4234 -70.231)
				(xy 263.4234 -81.788)
			)
		)
	)
	(zone
		(layer "In7.Cu")
		(hatch none 0.5)
		(connect_pads
			(clearance 0)
		)
		(min_thickness 0.25)
		(keepout
			(tracks not_allowed)
			(vias allowed)
			(pads allowed)
			(copperpour not_allowed)
			(footprints allowed)
		)
		(placement
			(enabled no)
			(sheetname "")
		)
		(fill
			(thermal_gap 0.5)
			(thermal_bridge_width 0.5)
			(island_removal_mode 0)
		)
		(polygon
			(pts
				(arc
					(start 423.500296 -84.000086)
					(mid 428.000414 -79.499968)
					(end 432.500278 -84.000086)
				)
				(arc
					(start 432.500278 -89.000076)
					(mid 428.000414 -93.49994)
					(end 423.500296 -89.000076)
				)
			)
		)
	)
	(zone
		(layer "In7.Cu")
		(hatch none 0.5)
		(connect_pads
			(clearance 0)
		)
		(min_thickness 0.25)
		(keepout
			(tracks not_allowed)
			(vias allowed)
			(pads allowed)
			(copperpour not_allowed)
			(footprints allowed)
		)
		(placement
			(enabled no)
			(sheetname "")
		)
		(fill
			(thermal_gap 0.5)
			(thermal_bridge_width 0.5)
			(island_removal_mode 0)
		)
		(polygon
			(pts
				(arc
					(start 422.865296 -89.000076)
					(mid 428.000414 -94.135194)
					(end 433.135278 -89.000076)
				)
				(arc
					(start 433.135278 -84.000086)
					(mid 428.000414 -78.865222)
					(end 422.865296 -84.000086)
				)
			)
		)
	)
	(zone
		(layer "In7.Cu")
		(hatch none 0.5)
		(connect_pads
			(clearance 0)
		)
		(min_thickness 0.25)
		(keepout
			(tracks not_allowed)
			(vias allowed)
			(pads allowed)
			(copperpour not_allowed)
			(footprints allowed)
		)
		(placement
			(enabled no)
			(sheetname "")
		)
		(fill
			(thermal_gap 0.5)
			(thermal_bridge_width 0.5)
			(island_removal_mode 0)
		)
		(polygon
			(pts
				(arc
					(start 244.865144 -21.500338)
					(mid 250.000262 -26.635456)
					(end 255.135126 -21.500338)
				)
				(arc
					(start 255.135126 -16.500348)
					(mid 250.000262 -11.365484)
					(end 244.865144 -16.500348)
				)
			)
		)
	)
	(zone
		(layer "In7.Cu")
		(hatch none 0.5)
		(connect_pads
			(clearance 0)
		)
		(min_thickness 0.25)
		(keepout
			(tracks not_allowed)
			(vias allowed)
			(pads allowed)
			(copperpour not_allowed)
			(footprints allowed)
		)
		(placement
			(enabled no)
			(sheetname "")
		)
		(fill
			(thermal_gap 0.5)
			(thermal_bridge_width 0.5)
			(island_removal_mode 0)
		)
		(polygon
			(pts
				(arc
					(start 423.500296 -4.500118)
					(mid 428.000414 0)
					(end 432.500278 -4.500118)
				)
				(arc
					(start 432.500278 -9.500108)
					(mid 428.000414 -13.999972)
					(end 423.500296 -9.500108)
				)
			)
		)
	)
)
